FILE_TYPE = EXPANDEDNETLIST;
{ Packager-XL run on 25-Aug-2023 AT 17:03:33 CONSTRAINTS_VIEW_GENERATED}
NET_NAME
'85_10INCH_BOT_DN'
 '@SCM_LIB.SCM(SCH_1):85_10INCH_BOT_DN':
 C_SIGNAL='@scm_lib.scm(sch_1):\85_10inch_bot_dn\';
NODE_NAME     J27 1
 '@SCM_LIB.SCM(SCH_1):PAGE58_I63@PURE_QUANTA.PICOPROBE_BXA(CHIPS)':
 '1_P': CDS_PINID='\1_p\';
NODE_NAME     J24 2
 '@SCM_LIB.SCM(SCH_1):PAGE58_I68@PURE_QUANTA.PICOPROBE_BXA(CHIPS)':
 '2_N': CDS_PINID='\2_n\';
NET_NAME
'85_10INCH_BOT_DP'
 '@SCM_LIB.SCM(SCH_1):85_10INCH_BOT_DP':
 C_SIGNAL='@scm_lib.scm(sch_1):\85_10inch_bot_dp\';
NODE_NAME     J27 2
 '@SCM_LIB.SCM(SCH_1):PAGE58_I63@PURE_QUANTA.PICOPROBE_BXA(CHIPS)':
 '2_N': CDS_PINID='\2_n\';
NODE_NAME     J24 1
 '@SCM_LIB.SCM(SCH_1):PAGE58_I68@PURE_QUANTA.PICOPROBE_BXA(CHIPS)':
 '1_P': CDS_PINID='\1_p\';
NET_NAME
'85_10INCH_IN1_DN'
 '@SCM_LIB.SCM(SCH_1):85_10INCH_IN1_DN':
 C_SIGNAL='@scm_lib.scm(sch_1):\85_10inch_in1_dn\';
NODE_NAME     J28 1
 '@SCM_LIB.SCM(SCH_1):PAGE58_I61@PURE_QUANTA.PICOPROBE_BXA(CHIPS)':
 '1_P': CDS_PINID='\1_p\';
NODE_NAME     J30 2
 '@SCM_LIB.SCM(SCH_1):PAGE58_I67@PURE_QUANTA.PICOPROBE_BXA(CHIPS)':
 '2_N': CDS_PINID='\2_n\';
NET_NAME
'85_10INCH_IN1_DP'
 '@SCM_LIB.SCM(SCH_1):85_10INCH_IN1_DP':
 C_SIGNAL='@scm_lib.scm(sch_1):\85_10inch_in1_dp\';
NODE_NAME     J28 2
 '@SCM_LIB.SCM(SCH_1):PAGE58_I61@PURE_QUANTA.PICOPROBE_BXA(CHIPS)':
 '2_N': CDS_PINID='\2_n\';
NODE_NAME     J30 1
 '@SCM_LIB.SCM(SCH_1):PAGE58_I67@PURE_QUANTA.PICOPROBE_BXA(CHIPS)':
 '1_P': CDS_PINID='\1_p\';
NET_NAME
'85_10INCH_IN4_DN'
 '@SCM_LIB.SCM(SCH_1):85_10INCH_IN4_DN':
 C_SIGNAL='@scm_lib.scm(sch_1):\85_10inch_in4_dn\';
NODE_NAME     J26 1
 '@SCM_LIB.SCM(SCH_1):PAGE58_I62@PURE_QUANTA.PICOPROBE_BXA(CHIPS)':
 '1_P': CDS_PINID='\1_p\';
NODE_NAME     J23 2
 '@SCM_LIB.SCM(SCH_1):PAGE58_I69@PURE_QUANTA.PICOPROBE_BXA(CHIPS)':
 '2_N': CDS_PINID='\2_n\';
NET_NAME
'85_10INCH_IN4_DP'
 '@SCM_LIB.SCM(SCH_1):85_10INCH_IN4_DP':
 C_SIGNAL='@scm_lib.scm(sch_1):\85_10inch_in4_dp\';
NODE_NAME     J26 2
 '@SCM_LIB.SCM(SCH_1):PAGE58_I62@PURE_QUANTA.PICOPROBE_BXA(CHIPS)':
 '2_N': CDS_PINID='\2_n\';
NODE_NAME     J23 1
 '@SCM_LIB.SCM(SCH_1):PAGE58_I69@PURE_QUANTA.PICOPROBE_BXA(CHIPS)':
 '1_P': CDS_PINID='\1_p\';
NET_NAME
'85_10INCH_TOP_DN'
 '@SCM_LIB.SCM(SCH_1):85_10INCH_TOP_DN':
 C_SIGNAL='@scm_lib.scm(sch_1):\85_10inch_top_dn\';
NODE_NAME     J25 1
 '@SCM_LIB.SCM(SCH_1):PAGE58_I60@PURE_QUANTA.PICOPROBE_BXA(CHIPS)':
 '1_P': CDS_PINID='\1_p\';
NODE_NAME     J22 2
 '@SCM_LIB.SCM(SCH_1):PAGE58_I66@PURE_QUANTA.PICOPROBE_BXA(CHIPS)':
 '2_N': CDS_PINID='\2_n\';
NET_NAME
'85_10INCH_TOP_DP'
 '@SCM_LIB.SCM(SCH_1):85_10INCH_TOP_DP':
 C_SIGNAL='@scm_lib.scm(sch_1):\85_10inch_top_dp\';
NODE_NAME     J25 2
 '@SCM_LIB.SCM(SCH_1):PAGE58_I60@PURE_QUANTA.PICOPROBE_BXA(CHIPS)':
 '2_N': CDS_PINID='\2_n\';
NODE_NAME     J22 1
 '@SCM_LIB.SCM(SCH_1):PAGE58_I66@PURE_QUANTA.PICOPROBE_BXA(CHIPS)':
 '1_P': CDS_PINID='\1_p\';
NET_NAME
'85_5INCH_BOT_DN'
 '@SCM_LIB.SCM(SCH_1):85_5INCH_BOT_DN':
 C_SIGNAL='@scm_lib.scm(sch_1):\85_5inch_bot_dn\';
NODE_NAME     J17 1
 '@SCM_LIB.SCM(SCH_1):PAGE58_I59@PURE_QUANTA.PICOPROBE_BXA(CHIPS)':
 '1_P': CDS_PINID='\1_p\';
NODE_NAME     J20 2
 '@SCM_LIB.SCM(SCH_1):PAGE58_I70@PURE_QUANTA.PICOPROBE_BXA(CHIPS)':
 '2_N': CDS_PINID='\2_n\';
NET_NAME
'85_5INCH_BOT_DP'
 '@SCM_LIB.SCM(SCH_1):85_5INCH_BOT_DP':
 C_SIGNAL='@scm_lib.scm(sch_1):\85_5inch_bot_dp\';
NODE_NAME     J17 2
 '@SCM_LIB.SCM(SCH_1):PAGE58_I59@PURE_QUANTA.PICOPROBE_BXA(CHIPS)':
 '2_N': CDS_PINID='\2_n\';
NODE_NAME     J20 1
 '@SCM_LIB.SCM(SCH_1):PAGE58_I70@PURE_QUANTA.PICOPROBE_BXA(CHIPS)':
 '1_P': CDS_PINID='\1_p\';
NET_NAME
'85_5INCH_IN1_DN'
 '@SCM_LIB.SCM(SCH_1):85_5INCH_IN1_DN':
 C_SIGNAL='@scm_lib.scm(sch_1):\85_5inch_in1_dn\';
NODE_NAME     J11 1
 '@SCM_LIB.SCM(SCH_1):PAGE58_I57@PURE_QUANTA.PICOPROBE_BXA(CHIPS)':
 '1_P': CDS_PINID='\1_p\';
NODE_NAME     J29 2
 '@SCM_LIB.SCM(SCH_1):PAGE58_I65@PURE_QUANTA.PICOPROBE_BXA(CHIPS)':
 '2_N': CDS_PINID='\2_n\';
NET_NAME
'85_5INCH_IN1_DP'
 '@SCM_LIB.SCM(SCH_1):85_5INCH_IN1_DP':
 C_SIGNAL='@scm_lib.scm(sch_1):\85_5inch_in1_dp\';
NODE_NAME     J11 2
 '@SCM_LIB.SCM(SCH_1):PAGE58_I57@PURE_QUANTA.PICOPROBE_BXA(CHIPS)':
 '2_N': CDS_PINID='\2_n\';
NODE_NAME     J29 1
 '@SCM_LIB.SCM(SCH_1):PAGE58_I65@PURE_QUANTA.PICOPROBE_BXA(CHIPS)':
 '1_P': CDS_PINID='\1_p\';
NET_NAME
'85_5INCH_IN4_DN'
 '@SCM_LIB.SCM(SCH_1):85_5INCH_IN4_DN':
 C_SIGNAL='@scm_lib.scm(sch_1):\85_5inch_in4_dn\';
NODE_NAME     J16 1
 '@SCM_LIB.SCM(SCH_1):PAGE58_I58@PURE_QUANTA.PICOPROBE_BXA(CHIPS)':
 '1_P': CDS_PINID='\1_p\';
NODE_NAME     J19 2
 '@SCM_LIB.SCM(SCH_1):PAGE58_I71@PURE_QUANTA.PICOPROBE_BXA(CHIPS)':
 '2_N': CDS_PINID='\2_n\';
NET_NAME
'85_5INCH_IN4_DP'
 '@SCM_LIB.SCM(SCH_1):85_5INCH_IN4_DP':
 C_SIGNAL='@scm_lib.scm(sch_1):\85_5inch_in4_dp\';
NODE_NAME     J16 2
 '@SCM_LIB.SCM(SCH_1):PAGE58_I58@PURE_QUANTA.PICOPROBE_BXA(CHIPS)':
 '2_N': CDS_PINID='\2_n\';
NODE_NAME     J19 1
 '@SCM_LIB.SCM(SCH_1):PAGE58_I71@PURE_QUANTA.PICOPROBE_BXA(CHIPS)':
 '1_P': CDS_PINID='\1_p\';
NET_NAME
'85_5INCH_TOP_DN'
 '@SCM_LIB.SCM(SCH_1):85_5INCH_TOP_DN':
 C_SIGNAL='@scm_lib.scm(sch_1):\85_5inch_top_dn\';
NODE_NAME     J9 1
 '@SCM_LIB.SCM(SCH_1):PAGE58_I55@PURE_QUANTA.PICOPROBE_BXA(CHIPS)':
 '1_P': CDS_PINID='\1_p\';
NODE_NAME     J12 2
 '@SCM_LIB.SCM(SCH_1):PAGE58_I64@PURE_QUANTA.PICOPROBE_BXA(CHIPS)':
 '2_N': CDS_PINID='\2_n\';
NET_NAME
'85_5INCH_TOP_DP'
 '@SCM_LIB.SCM(SCH_1):85_5INCH_TOP_DP':
 C_SIGNAL='@scm_lib.scm(sch_1):\85_5inch_top_dp\';
NODE_NAME     J9 2
 '@SCM_LIB.SCM(SCH_1):PAGE58_I55@PURE_QUANTA.PICOPROBE_BXA(CHIPS)':
 '2_N': CDS_PINID='\2_n\';
NODE_NAME     J12 1
 '@SCM_LIB.SCM(SCH_1):PAGE58_I64@PURE_QUANTA.PICOPROBE_BXA(CHIPS)':
 '1_P': CDS_PINID='\1_p\';
NET_NAME
'AC_PWR_BMC_BTN_N'
 '@SCM_LIB.SCM(SCH_1):AC_PWR_BMC_BTN_N':
 C_SIGNAL='@scm_lib.scm(sch_1):ac_pwr_bmc_btn_n';
NODE_NAME     U57 4
 '@SCM_LIB.SCM(SCH_1):PAGE50_I278@PURE_QUANTA.74LVC1G07GW(CHIPS)':
 'Y': CDS_PINID='Y';
NODE_NAME     R884 2
 '@SCM_LIB.SCM(SCH_1):PAGE14_I229@PURE_QUANTA.Q_RES(CHIPS)':
 'B': CDS_PINID='B';
NODE_NAME     R885 2
 '@SCM_LIB.SCM(SCH_1):PAGE14_I231@PURE_QUANTA.Q_RES(CHIPS)':
 'B': CDS_PINID='B';
NET_NAME
'AC_PWR_BMC_BTN_R_N'
 '@SCM_LIB.SCM(SCH_1):AC_PWR_BMC_BTN_R_N':
 C_SIGNAL='@scm_lib.scm(sch_1):ac_pwr_bmc_btn_r_n';
NODE_NAME     U5 C6
 '@SCM_LIB.SCM(SCH_1):PAGE14_I149@PURE_QUANTA.AST2600A3GP(CHIPS)':
 'RGMII1TXCK||RMII1RCLKO||GPIO18A0': CDS_PINID='\rgmii1txck||rmii1rclko||gpio18a0\';
NODE_NAME     R884 1
 '@SCM_LIB.SCM(SCH_1):PAGE14_I229@PURE_QUANTA.Q_RES(CHIPS)':
 'A': CDS_PINID='A';
NET_NAME
'AC_PWR_BTN_N'
 '@SCM_LIB.SCM(SCH_1):AC_PWR_BTN_N':
 C_SIGNAL='@scm_lib.scm(sch_1):ac_pwr_btn_n';
NODE_NAME     GF1 B42
 '@SCM_LIB.SCM(SCH_1):PAGE10_I553@PURE_QUANTA.FCONN168_ME1016810202011_SCM(CHIPS)':
 'QSPI0_CS1_N': CDS_PINID='QSPI0_CS1_N';
NODE_NAME     R471 2
 '@SCM_LIB.SCM(SCH_1):PAGE50_I242@PURE_QUANTA.Q_RES(CHIPS)':
 'B': CDS_PINID='B';
NET_NAME
'AC_PWR_BTN_R1_N'
 '@SCM_LIB.SCM(SCH_1):AC_PWR_BTN_R1_N':
 C_SIGNAL='@scm_lib.scm(sch_1):ac_pwr_btn_r1_n';
NODE_NAME     U16 4
 '@SCM_LIB.SCM(SCH_1):PAGE50_I227@PURE_QUANTA.74LVC1G07GW(CHIPS)':
 'Y': CDS_PINID='Y';
NODE_NAME     R463 1
 '@SCM_LIB.SCM(SCH_1):PAGE35_I131@PURE_QUANTA.Q_RES(CHIPS)':
 'A': CDS_PINID='A';
NODE_NAME     R472 2
 '@SCM_LIB.SCM(SCH_1):PAGE35_I136@PURE_QUANTA.Q_RES(CHIPS)':
 'B': CDS_PINID='B';
NET_NAME
'AC_PWR_BTN_R2_N'
 '@SCM_LIB.SCM(SCH_1):AC_PWR_BTN_R2_N':
 C_SIGNAL='@scm_lib.scm(sch_1):ac_pwr_btn_r2_n';
NODE_NAME     U25 N15
 '@SCM_LIB.SCM(SCH_1):PAGE35_I1@PURE_QUANTA.LCMXO3LF2100C5BG256C(CHIPS)':
 'PR13C': CDS_PINID='PR13C';
NODE_NAME     R463 2
 '@SCM_LIB.SCM(SCH_1):PAGE35_I131@PURE_QUANTA.Q_RES(CHIPS)':
 'B': CDS_PINID='B';
NET_NAME
'ADCVREFEXT0'
 '@SCM_LIB.SCM(SCH_1):ADCVREFEXT0':
 C_SIGNAL='@scm_lib.scm(sch_1):adcvrefext0';
NODE_NAME     U5 AF19
 '@SCM_LIB.SCM(SCH_1):PAGE16_I188@PURE_QUANTA.AST2600A3GP(CHIPS)':
 'ADCVREFEXT0': CDS_PINID='ADCVREFEXT0';
NODE_NAME     C284 1
 '@SCM_LIB.SCM(SCH_1):PAGE17_I250@PURE_QUANTA.Q_CAP(CHIPS)':
 'A': CDS_PINID='A';
NODE_NAME     C282 1
 '@SCM_LIB.SCM(SCH_1):PAGE17_I252@PURE_QUANTA.Q_CAP(CHIPS)':
 'A': CDS_PINID='A';
NODE_NAME     R780 2
 '@SCM_LIB.SCM(SCH_1):PAGE17_I256@PURE_QUANTA.Q_RES(CHIPS)':
 'B': CDS_PINID='B';
NODE_NAME     R783 2
 '@SCM_LIB.SCM(SCH_1):PAGE17_I260@PURE_QUANTA.Q_RES(CHIPS)':
 'B': CDS_PINID='B';
NODE_NAME     R784 2
 '@SCM_LIB.SCM(SCH_1):PAGE17_I267@PURE_QUANTA.Q_RES(CHIPS)':
 'B': CDS_PINID='B';
NET_NAME
'ADCVREFEXT1'
 '@SCM_LIB.SCM(SCH_1):ADCVREFEXT1':
 C_SIGNAL='@scm_lib.scm(sch_1):adcvrefext1';
NODE_NAME     U5 AF17
 '@SCM_LIB.SCM(SCH_1):PAGE16_I188@PURE_QUANTA.AST2600A3GP(CHIPS)':
 'ADCVREFEXT1': CDS_PINID='ADCVREFEXT1';
NODE_NAME     C277 1
 '@SCM_LIB.SCM(SCH_1):PAGE17_I253@PURE_QUANTA.Q_CAP(CHIPS)':
 'A': CDS_PINID='A';
NODE_NAME     C279 1
 '@SCM_LIB.SCM(SCH_1):PAGE17_I255@PURE_QUANTA.Q_CAP(CHIPS)':
 'A': CDS_PINID='A';
NODE_NAME     R779 2
 '@SCM_LIB.SCM(SCH_1):PAGE17_I259@PURE_QUANTA.Q_RES(CHIPS)':
 'B': CDS_PINID='B';
NODE_NAME     R781 2
 '@SCM_LIB.SCM(SCH_1):PAGE17_I263@PURE_QUANTA.Q_RES(CHIPS)':
 'B': CDS_PINID='B';
NODE_NAME     R782 2
 '@SCM_LIB.SCM(SCH_1):PAGE17_I264@PURE_QUANTA.Q_RES(CHIPS)':
 'B': CDS_PINID='B';
NET_NAME
'A_BMC_ADCAV33'
 '@SCM_LIB.SCM(SCH_1):A_BMC_ADCAV33':
 C_SIGNAL='@scm_lib.scm(sch_1):a_bmc_adcav33';
NODE_NAME     C75 1
 '@SCM_LIB.SCM(SCH_1):PAGE16_I93@PURE_QUANTA.Q_CAP(CHIPS)':
 'A': CDS_PINID='A';
NODE_NAME     L12 2
 '@SCM_LIB.SCM(SCH_1):PAGE16_I99@PURE_QUANTA.Q_INDUCTOR(CHIPS)':
 '2': CDS_PINID='\2\';
NODE_NAME     C77 1
 '@SCM_LIB.SCM(SCH_1):PAGE16_I100@PURE_QUANTA.Q_CAP(CHIPS)':
 'A': CDS_PINID='A';
NODE_NAME     U5 AA21
 '@SCM_LIB.SCM(SCH_1):PAGE16_I188@PURE_QUANTA.AST2600A3GP(CHIPS)':
 'ADCAV33_AA21': CDS_PINID='ADCAV33_AA21';
NODE_NAME     U5 Y21
 '@SCM_LIB.SCM(SCH_1):PAGE16_I188@PURE_QUANTA.AST2600A3GP(CHIPS)':
 'ADCAV33_Y21': CDS_PINID='ADCAV33_Y21';
NET_NAME
'A_BMC_ADCREXT0'
 '@SCM_LIB.SCM(SCH_1):A_BMC_ADCREXT0':
 C_SIGNAL='@scm_lib.scm(sch_1):a_bmc_adcrext0';
NODE_NAME     R233 2
 '@SCM_LIB.SCM(SCH_1):PAGE16_I87@PURE_QUANTA.Q_RES(CHIPS)':
 'B': CDS_PINID='B';
NODE_NAME     U5 AF20
 '@SCM_LIB.SCM(SCH_1):PAGE16_I188@PURE_QUANTA.AST2600A3GP(CHIPS)':
 'ADCREXT0': CDS_PINID='ADCREXT0';
NET_NAME
'A_BMC_ADCREXT1'
 '@SCM_LIB.SCM(SCH_1):A_BMC_ADCREXT1':
 C_SIGNAL='@scm_lib.scm(sch_1):a_bmc_adcrext1';
NODE_NAME     R234 2
 '@SCM_LIB.SCM(SCH_1):PAGE16_I86@PURE_QUANTA.Q_RES(CHIPS)':
 'B': CDS_PINID='B';
NODE_NAME     U5 AF18
 '@SCM_LIB.SCM(SCH_1):PAGE16_I188@PURE_QUANTA.AST2600A3GP(CHIPS)':
 'ADCREXT1': CDS_PINID='ADCREXT1';
NET_NAME
'A_BMC_ADCVREFN0'
 '@SCM_LIB.SCM(SCH_1):A_BMC_ADCVREFN0':
 C_SIGNAL='@scm_lib.scm(sch_1):a_bmc_adcvrefn0';
NODE_NAME     U5 AB20
 '@SCM_LIB.SCM(SCH_1):PAGE16_I188@PURE_QUANTA.AST2600A3GP(CHIPS)':
 'ADCVREFN0': CDS_PINID='ADCVREFN0';
NODE_NAME     C134 2
 '@SCM_LIB.SCM(SCH_1):PAGE17_I106@PURE_QUANTA.Q_CAP(CHIPS)':
 'B': CDS_PINID='B';
NODE_NAME     C138 1
 '@SCM_LIB.SCM(SCH_1):PAGE17_I109@PURE_QUANTA.Q_CAP(CHIPS)':
 'A': CDS_PINID='A';
NET_NAME
'A_BMC_ADCVREFN1'
 '@SCM_LIB.SCM(SCH_1):A_BMC_ADCVREFN1':
 C_SIGNAL='@scm_lib.scm(sch_1):a_bmc_adcvrefn1';
NODE_NAME     U5 AD18
 '@SCM_LIB.SCM(SCH_1):PAGE16_I188@PURE_QUANTA.AST2600A3GP(CHIPS)':
 'ADCVREFN1': CDS_PINID='ADCVREFN1';
NODE_NAME     C133 2
 '@SCM_LIB.SCM(SCH_1):PAGE17_I104@PURE_QUANTA.Q_CAP(CHIPS)':
 'B': CDS_PINID='B';
NODE_NAME     C137 1
 '@SCM_LIB.SCM(SCH_1):PAGE17_I108@PURE_QUANTA.Q_CAP(CHIPS)':
 'A': CDS_PINID='A';
NET_NAME
'A_BMC_ADCVREFP0'
 '@SCM_LIB.SCM(SCH_1):A_BMC_ADCVREFP0':
 C_SIGNAL='@scm_lib.scm(sch_1):a_bmc_adcvrefp0';
NODE_NAME     U5 AC20
 '@SCM_LIB.SCM(SCH_1):PAGE16_I188@PURE_QUANTA.AST2600A3GP(CHIPS)':
 'ADCVREFP0': CDS_PINID='ADCVREFP0';
NODE_NAME     C138 2
 '@SCM_LIB.SCM(SCH_1):PAGE17_I109@PURE_QUANTA.Q_CAP(CHIPS)':
 'B': CDS_PINID='B';
NODE_NAME     C136 2
 '@SCM_LIB.SCM(SCH_1):PAGE17_I110@PURE_QUANTA.Q_CAP(CHIPS)':
 'B': CDS_PINID='B';
NET_NAME
'A_BMC_ADCVREFP1'
 '@SCM_LIB.SCM(SCH_1):A_BMC_ADCVREFP1':
 C_SIGNAL='@scm_lib.scm(sch_1):a_bmc_adcvrefp1';
NODE_NAME     U5 AD17
 '@SCM_LIB.SCM(SCH_1):PAGE16_I188@PURE_QUANTA.AST2600A3GP(CHIPS)':
 'ADCVREFP1': CDS_PINID='ADCVREFP1';
NODE_NAME     C135 2
 '@SCM_LIB.SCM(SCH_1):PAGE17_I107@PURE_QUANTA.Q_CAP(CHIPS)':
 'B': CDS_PINID='B';
NODE_NAME     C137 2
 '@SCM_LIB.SCM(SCH_1):PAGE17_I108@PURE_QUANTA.Q_CAP(CHIPS)':
 'B': CDS_PINID='B';
NET_NAME
'A_BMC_DACREST'
 '@SCM_LIB.SCM(SCH_1):A_BMC_DACREST':
 C_SIGNAL='@scm_lib.scm(sch_1):a_bmc_dacrest';
NODE_NAME     R235 2
 '@SCM_LIB.SCM(SCH_1):PAGE16_I187@PURE_QUANTA.Q_RES(CHIPS)':
 'B': CDS_PINID='B';
NODE_NAME     U5 AC21
 '@SCM_LIB.SCM(SCH_1):PAGE16_I188@PURE_QUANTA.AST2600A3GP(CHIPS)':
 'DACRSET': CDS_PINID='DACRSET';
NET_NAME
'BATTERY_DETECT'
 '@SCM_LIB.SCM(SCH_1):BATTERY_DETECT':
 C_SIGNAL='@scm_lib.scm(sch_1):battery_detect';
NODE_NAME     U5 AE15
 '@SCM_LIB.SCM(SCH_1):PAGE13_I363@PURE_QUANTA.AST2600A3GP(CHIPS)':
 'GPIOV4||SIOPWRGD': CDS_PINID='\gpiov4||siopwrgd\';
NODE_NAME     R775 1
 '@SCM_LIB.SCM(SCH_1):PAGE15_I183@PURE_QUANTA.Q_RES(CHIPS)':
 'A': CDS_PINID='A';
NET_NAME
'BATTERY_DETECT_R'
 '@SCM_LIB.SCM(SCH_1):BATTERY_DETECT_R':
 C_SIGNAL='@scm_lib.scm(sch_1):battery_detect_r';
NODE_NAME     Q11 G
 '@SCM_LIB.SCM(SCH_1):PAGE15_I179@PURE_QUANTA.MOSFET_N_GSD(CHIPS)':
 'GATE': CDS_PINID='GATE';
NODE_NAME     R775 2
 '@SCM_LIB.SCM(SCH_1):PAGE15_I183@PURE_QUANTA.Q_RES(CHIPS)':
 'B': CDS_PINID='B';
NODE_NAME     R776 1
 '@SCM_LIB.SCM(SCH_1):PAGE15_I184@PURE_QUANTA.Q_RES(CHIPS)':
 'A': CDS_PINID='A';
NET_NAME
'BEEP_LED'
 '@SCM_LIB.SCM(SCH_1):BEEP_LED':
 C_SIGNAL='@scm_lib.scm(sch_1):beep_led';
NODE_NAME     U9 1
 '@SCM_LIB.SCM(SCH_1):PAGE49_I5@PURE_QUANTA.MC74VHC1G32DTT1G(CHIPS)':
 'IN_B': CDS_PINID='IN_B';
NODE_NAME     R306 1
 '@SCM_LIB.SCM(SCH_1):PAGE49_I8@PURE_QUANTA.Q_RES(CHIPS)':
 'A': CDS_PINID='A';
NODE_NAME     U8 4
 '@SCM_LIB.SCM(SCH_1):PAGE49_I11@PURE_QUANTA.74LVC1G126SE7(CHIPS)':
 'Y': CDS_PINID='Y';
NET_NAME
'BJT_Q3_B'
 '@SCM_LIB.SCM(SCH_1):BJT_Q3_B':
 C_SIGNAL='@scm_lib.scm(sch_1):bjt_q3_b';
NODE_NAME     Q3 B
 '@SCM_LIB.SCM(SCH_1):PAGE22_I4@PURE_QUANTA.MMBT39047F(CHIPS)':
 '1': CDS_PINID='\1\';
NODE_NAME     R290 1
 '@SCM_LIB.SCM(SCH_1):PAGE22_I8@PURE_QUANTA.Q_RES(CHIPS)':
 'A': CDS_PINID='A';
NET_NAME
'BJT_Q3_C'
 '@SCM_LIB.SCM(SCH_1):BJT_Q3_C':
 C_SIGNAL='@scm_lib.scm(sch_1):bjt_q3_c';
NODE_NAME     Q1 B
 '@SCM_LIB.SCM(SCH_1):PAGE22_I2@PURE_QUANTA.MMBT39047F(CHIPS)':
 '1': CDS_PINID='\1\';
NODE_NAME     Q3 C
 '@SCM_LIB.SCM(SCH_1):PAGE22_I4@PURE_QUANTA.MMBT39047F(CHIPS)':
 '3': CDS_PINID='\3\';
NODE_NAME     R289 2
 '@SCM_LIB.SCM(SCH_1):PAGE22_I7@PURE_QUANTA.Q_RES(CHIPS)':
 'B': CDS_PINID='B';
NET_NAME
'BMC_CLK_25M'
 '@SCM_LIB.SCM(SCH_1):BMC_CLK_25M':
 C_SIGNAL='@scm_lib.scm(sch_1):bmc_clk_25m';
NODE_NAME     R215 2
 '@SCM_LIB.SCM(SCH_1):PAGE15_I42@PURE_QUANTA.Q_RES(CHIPS)':
 'B': CDS_PINID='B';
NODE_NAME     U5 D10
 '@SCM_LIB.SCM(SCH_1):PAGE15_I350@PURE_QUANTA.AST2600A3GP(CHIPS)':
 'CLKIN': CDS_PINID='CLKIN';
NET_NAME
'BMC_CLK_25M_R'
 '@SCM_LIB.SCM(SCH_1):BMC_CLK_25M_R':
 C_SIGNAL='@scm_lib.scm(sch_1):bmc_clk_25m_r';
NODE_NAME     OSC1 3
 '@SCM_LIB.SCM(SCH_1):PAGE15_I39@PURE_QUANTA.OSC4_7X25000018(CHIPS)':
 'OUT': CDS_PINID='\out\';
NODE_NAME     R215 1
 '@SCM_LIB.SCM(SCH_1):PAGE15_I42@PURE_QUANTA.Q_RES(CHIPS)':
 'A': CDS_PINID='A';
NET_NAME
'BMC_CPLD_GPIO_12'
 '@SCM_LIB.SCM(SCH_1):BMC_CPLD_GPIO_12':
 C_SIGNAL='@scm_lib.scm(sch_1):bmc_cpld_gpio_12';
NODE_NAME     R607 2
 '@SCM_LIB.SCM(SCH_1):PAGE42_I29@PURE_QUANTA.Q_RES(CHIPS)':
 'B': CDS_PINID='B';
NODE_NAME     R536 2
 '@SCM_LIB.SCM(SCH_1):PAGE35_I144@PURE_QUANTA.Q_RES(CHIPS)':
 'B': CDS_PINID='B';
NET_NAME
'BMC_CPLD_GPIO_12_R2'
 '@SCM_LIB.SCM(SCH_1):BMC_CPLD_GPIO_12_R2':
 C_SIGNAL='@scm_lib.scm(sch_1):bmc_cpld_gpio_12_r2';
NODE_NAME     U25 G16
 '@SCM_LIB.SCM(SCH_1):PAGE35_I1@PURE_QUANTA.LCMXO3LF2100C5BG256C(CHIPS)':
 'PR6A': CDS_PINID='PR6A';
NODE_NAME     R536 1
 '@SCM_LIB.SCM(SCH_1):PAGE35_I144@PURE_QUANTA.Q_RES(CHIPS)':
 'A': CDS_PINID='A';
NET_NAME
'BMC_CPLD_GPIO_13'
 '@SCM_LIB.SCM(SCH_1):BMC_CPLD_GPIO_13':
 C_SIGNAL='@scm_lib.scm(sch_1):bmc_cpld_gpio_13';
NODE_NAME     R608 2
 '@SCM_LIB.SCM(SCH_1):PAGE42_I27@PURE_QUANTA.Q_RES(CHIPS)':
 'B': CDS_PINID='B';
NODE_NAME     R537 2
 '@SCM_LIB.SCM(SCH_1):PAGE35_I145@PURE_QUANTA.Q_RES(CHIPS)':
 'B': CDS_PINID='B';
NET_NAME
'BMC_CPLD_GPIO_13_R2'
 '@SCM_LIB.SCM(SCH_1):BMC_CPLD_GPIO_13_R2':
 C_SIGNAL='@scm_lib.scm(sch_1):bmc_cpld_gpio_13_r2';
NODE_NAME     U25 H15
 '@SCM_LIB.SCM(SCH_1):PAGE35_I1@PURE_QUANTA.LCMXO3LF2100C5BG256C(CHIPS)':
 'PR6B': CDS_PINID='PR6B';
NODE_NAME     R537 1
 '@SCM_LIB.SCM(SCH_1):PAGE35_I145@PURE_QUANTA.Q_RES(CHIPS)':
 'A': CDS_PINID='A';
NET_NAME
'BMC_CPLD_GPIO_2'
 '@SCM_LIB.SCM(SCH_1):BMC_CPLD_GPIO_2':
 C_SIGNAL='@scm_lib.scm(sch_1):bmc_cpld_gpio_2';
NODE_NAME     R586 2
 '@SCM_LIB.SCM(SCH_1):PAGE42_I67@PURE_QUANTA.Q_RES(CHIPS)':
 'B': CDS_PINID='B';
NODE_NAME     R519 1
 '@SCM_LIB.SCM(SCH_1):PAGE34_I147@PURE_QUANTA.Q_RES(CHIPS)':
 'A': CDS_PINID='A';
NODE_NAME     R65 2
 '@SCM_LIB.SCM(SCH_1):PAGE13_I421@PURE_QUANTA.Q_RES(CHIPS)':
 'B': CDS_PINID='B';
NODE_NAME     R629 1
 '@SCM_LIB.SCM(SCH_1):PAGE31_I78@PURE_QUANTA.Q_RES(CHIPS)':
 'A': CDS_PINID='A';
NET_NAME
'BMC_CPLD_GPIO_2_R1'
 '@SCM_LIB.SCM(SCH_1):BMC_CPLD_GPIO_2_R1':
 C_SIGNAL='@scm_lib.scm(sch_1):bmc_cpld_gpio_2_r1';
NODE_NAME     U5 T24
 '@SCM_LIB.SCM(SCH_1):PAGE13_I363@PURE_QUANTA.AST2600A3GP(CHIPS)':
 'GPIOS7||RXD11': CDS_PINID='\gpios7||rxd11\';
NODE_NAME     R65 1
 '@SCM_LIB.SCM(SCH_1):PAGE13_I421@PURE_QUANTA.Q_RES(CHIPS)':
 'A': CDS_PINID='A';
NET_NAME
'BMC_CPLD_GPIO_2_R2'
 '@SCM_LIB.SCM(SCH_1):BMC_CPLD_GPIO_2_R2':
 C_SIGNAL='@scm_lib.scm(sch_1):bmc_cpld_gpio_2_r2';
NODE_NAME     U25 E6
 '@SCM_LIB.SCM(SCH_1):PAGE34_I1@PURE_QUANTA.LCMXO3LF2100C5BG256C(CHIPS)':
 'PT13C': CDS_PINID='PT13C';
NODE_NAME     R519 2
 '@SCM_LIB.SCM(SCH_1):PAGE34_I147@PURE_QUANTA.Q_RES(CHIPS)':
 'B': CDS_PINID='B';
NET_NAME
'BMC_CPLD_GPIO_7'
 '@SCM_LIB.SCM(SCH_1):BMC_CPLD_GPIO_7':
 C_SIGNAL='@scm_lib.scm(sch_1):bmc_cpld_gpio_7';
NODE_NAME     R593 2
 '@SCM_LIB.SCM(SCH_1):PAGE42_I39@PURE_QUANTA.Q_RES(CHIPS)':
 'B': CDS_PINID='B';
NODE_NAME     R526 2
 '@SCM_LIB.SCM(SCH_1):PAGE35_I147@PURE_QUANTA.Q_RES(CHIPS)':
 'B': CDS_PINID='B';
NET_NAME
'BMC_CPLD_GPIO_7_R2'
 '@SCM_LIB.SCM(SCH_1):BMC_CPLD_GPIO_7_R2':
 C_SIGNAL='@scm_lib.scm(sch_1):bmc_cpld_gpio_7_r2';
NODE_NAME     U25 F15
 '@SCM_LIB.SCM(SCH_1):PAGE35_I1@PURE_QUANTA.LCMXO3LF2100C5BG256C(CHIPS)':
 'PR3B': CDS_PINID='PR3B';
NODE_NAME     R526 1
 '@SCM_LIB.SCM(SCH_1):PAGE35_I147@PURE_QUANTA.Q_RES(CHIPS)':
 'A': CDS_PINID='A';
NET_NAME
'BMC_CPLD_GPIO_8'
 '@SCM_LIB.SCM(SCH_1):BMC_CPLD_GPIO_8':
 C_SIGNAL='@scm_lib.scm(sch_1):bmc_cpld_gpio_8';
NODE_NAME     R595 2
 '@SCM_LIB.SCM(SCH_1):PAGE42_I37@PURE_QUANTA.Q_RES(CHIPS)':
 'B': CDS_PINID='B';
NODE_NAME     R531 2
 '@SCM_LIB.SCM(SCH_1):PAGE35_I146@PURE_QUANTA.Q_RES(CHIPS)':
 'B': CDS_PINID='B';
NET_NAME
'BMC_CPLD_GPIO_8_R2'
 '@SCM_LIB.SCM(SCH_1):BMC_CPLD_GPIO_8_R2':
 C_SIGNAL='@scm_lib.scm(sch_1):bmc_cpld_gpio_8_r2';
NODE_NAME     U25 F14
 '@SCM_LIB.SCM(SCH_1):PAGE35_I1@PURE_QUANTA.LCMXO3LF2100C5BG256C(CHIPS)':
 'PR4A': CDS_PINID='PR4A';
NODE_NAME     R531 1
 '@SCM_LIB.SCM(SCH_1):PAGE35_I146@PURE_QUANTA.Q_RES(CHIPS)':
 'A': CDS_PINID='A';
NET_NAME
'BMC_DDC_BUF_EN'
 '@SCM_LIB.SCM(SCH_1):BMC_DDC_BUF_EN':
 C_SIGNAL='@scm_lib.scm(sch_1):bmc_ddc_buf_en';
NODE_NAME     U33 1
 '@SCM_LIB.SCM(SCH_1):PAGE23_I32@PURE_QUANTA.74HC1G126GW(CHIPS)':
 '1': CDS_PINID='\1\';
NODE_NAME     U26 1
 '@SCM_LIB.SCM(SCH_1):PAGE23_I33@PURE_QUANTA.74HC1G126GW(CHIPS)':
 '1': CDS_PINID='\1\';
NODE_NAME     R30 2
 '@SCM_LIB.SCM(SCH_1):PAGE23_I39@PURE_QUANTA.Q_RES(CHIPS)':
 'B': CDS_PINID='B';
NET_NAME
'BMC_DDC_BUF_PWR'
 '@SCM_LIB.SCM(SCH_1):BMC_DDC_BUF_PWR':
 C_SIGNAL='@scm_lib.scm(sch_1):bmc_ddc_buf_pwr';
NODE_NAME     R18 2
 '@SCM_LIB.SCM(SCH_1):PAGE23_I19@PURE_QUANTA.Q_RES(CHIPS)':
 'B': CDS_PINID='B';
NODE_NAME     U33 5
 '@SCM_LIB.SCM(SCH_1):PAGE23_I32@PURE_QUANTA.74HC1G126GW(CHIPS)':
 '5': CDS_PINID='\5\';
NODE_NAME     U26 5
 '@SCM_LIB.SCM(SCH_1):PAGE23_I33@PURE_QUANTA.74HC1G126GW(CHIPS)':
 '5': CDS_PINID='\5\';
NET_NAME
'BMC_EMMC_CD_N'
 '@SCM_LIB.SCM(SCH_1):BMC_EMMC_CD_N':
 C_SIGNAL='@scm_lib.scm(sch_1):bmc_emmc_cd_n';
NODE_NAME     U5 A24
 '@SCM_LIB.SCM(SCH_1):PAGE12_I436@PURE_QUANTA.AST2600A3GP(CHIPS)':
 'GPIOF6||SD1CD#||PWM14': CDS_PINID='\gpiof6||sd1cd#||pwm14\';
NODE_NAME     R685 1
 '@SCM_LIB.SCM(SCH_1):PAGE14_I165@PURE_QUANTA.Q_RES(CHIPS)':
 'A': CDS_PINID='A';
NODE_NAME     R687 2
 '@SCM_LIB.SCM(SCH_1):PAGE14_I166@PURE_QUANTA.Q_RES(CHIPS)':
 'B': CDS_PINID='B';
NET_NAME
'BMC_EMMC_CLK'
 '@SCM_LIB.SCM(SCH_1):BMC_EMMC_CLK':
 C_SIGNAL='@scm_lib.scm(sch_1):bmc_emmc_clk';
NODE_NAME     U5 D22
 '@SCM_LIB.SCM(SCH_1):PAGE12_I436@PURE_QUANTA.AST2600A3GP(CHIPS)':
 'GPIOF0||SD1CLK||PWM8': CDS_PINID='\gpiof0||sd1clk||pwm8\';
NODE_NAME     R654 2
 '@SCM_LIB.SCM(SCH_1):PAGE21_I33@PURE_QUANTA.Q_RES(CHIPS)':
 'B': CDS_PINID='B';
NET_NAME
'BMC_EMMC_CMD'
 '@SCM_LIB.SCM(SCH_1):BMC_EMMC_CMD':
 C_SIGNAL='@scm_lib.scm(sch_1):bmc_emmc_cmd';
NODE_NAME     U5 E22
 '@SCM_LIB.SCM(SCH_1):PAGE12_I436@PURE_QUANTA.AST2600A3GP(CHIPS)':
 'GPIOF1||SD1CMD||PWM9': CDS_PINID='\gpiof1||sd1cmd||pwm9\';
NODE_NAME     R48 2
 '@SCM_LIB.SCM(SCH_1):PAGE21_I35@PURE_QUANTA.Q_RES(CHIPS)':
 'B': CDS_PINID='B';
NET_NAME
'BMC_EMMC_DT0'
 '@SCM_LIB.SCM(SCH_1):BMC_EMMC_DT0':
 C_SIGNAL='@scm_lib.scm(sch_1):bmc_emmc_dt0';
NODE_NAME     U5 D23
 '@SCM_LIB.SCM(SCH_1):PAGE12_I436@PURE_QUANTA.AST2600A3GP(CHIPS)':
 'GPIOF2||SD1DAT0||PWM10': CDS_PINID='\gpiof2||sd1dat0||pwm10\';
NODE_NAME     R649 2
 '@SCM_LIB.SCM(SCH_1):PAGE21_I42@PURE_QUANTA.Q_RES(CHIPS)':
 'B': CDS_PINID='B';
NET_NAME
'BMC_EMMC_DT1'
 '@SCM_LIB.SCM(SCH_1):BMC_EMMC_DT1':
 C_SIGNAL='@scm_lib.scm(sch_1):bmc_emmc_dt1';
NODE_NAME     U5 C23
 '@SCM_LIB.SCM(SCH_1):PAGE12_I436@PURE_QUANTA.AST2600A3GP(CHIPS)':
 'GPIOF3||SD1DAT1||PWM11': CDS_PINID='\gpiof3||sd1dat1||pwm11\';
NODE_NAME     R648 2
 '@SCM_LIB.SCM(SCH_1):PAGE21_I43@PURE_QUANTA.Q_RES(CHIPS)':
 'B': CDS_PINID='B';
NET_NAME
'BMC_EMMC_DT2'
 '@SCM_LIB.SCM(SCH_1):BMC_EMMC_DT2':
 C_SIGNAL='@scm_lib.scm(sch_1):bmc_emmc_dt2';
NODE_NAME     U5 C22
 '@SCM_LIB.SCM(SCH_1):PAGE12_I436@PURE_QUANTA.AST2600A3GP(CHIPS)':
 'GPIOF4||SD1DAT2||PWM12': CDS_PINID='\gpiof4||sd1dat2||pwm12\';
NODE_NAME     R647 2
 '@SCM_LIB.SCM(SCH_1):PAGE21_I45@PURE_QUANTA.Q_RES(CHIPS)':
 'B': CDS_PINID='B';
NET_NAME
'BMC_EMMC_DT3'
 '@SCM_LIB.SCM(SCH_1):BMC_EMMC_DT3':
 C_SIGNAL='@scm_lib.scm(sch_1):bmc_emmc_dt3';
NODE_NAME     U5 A25
 '@SCM_LIB.SCM(SCH_1):PAGE12_I436@PURE_QUANTA.AST2600A3GP(CHIPS)':
 'GPIOF5||SD1DAT3||PWM13': CDS_PINID='\gpiof5||sd1dat3||pwm13\';
NODE_NAME     R532 2
 '@SCM_LIB.SCM(SCH_1):PAGE21_I46@PURE_QUANTA.Q_RES(CHIPS)':
 'B': CDS_PINID='B';
NET_NAME
'BMC_EMMC_DT4'
 '@SCM_LIB.SCM(SCH_1):BMC_EMMC_DT4':
 C_SIGNAL='@scm_lib.scm(sch_1):bmc_emmc_dt4';
NODE_NAME     U5 C21
 '@SCM_LIB.SCM(SCH_1):PAGE12_I436@PURE_QUANTA.AST2600A3GP(CHIPS)':
 'GPIOG2||TXD7||SD2DAT0||SALT11': CDS_PINID='\gpiog2||txd7||sd2dat0||salt11\';
NODE_NAME     R653 1
 '@SCM_LIB.SCM(SCH_1):PAGE21_I100@PURE_QUANTA.Q_RES(CHIPS)':
 'A': CDS_PINID='A';
NET_NAME
'BMC_EMMC_DT5'
 '@SCM_LIB.SCM(SCH_1):BMC_EMMC_DT5':
 C_SIGNAL='@scm_lib.scm(sch_1):bmc_emmc_dt5';
NODE_NAME     U5 A22
 '@SCM_LIB.SCM(SCH_1):PAGE12_I436@PURE_QUANTA.AST2600A3GP(CHIPS)':
 'GPIOG3||RXD7||SD2DAT1||SALT12': CDS_PINID='\gpiog3||rxd7||sd2dat1||salt12\';
NODE_NAME     R652 1
 '@SCM_LIB.SCM(SCH_1):PAGE21_I101@PURE_QUANTA.Q_RES(CHIPS)':
 'A': CDS_PINID='A';
NET_NAME
'BMC_EMMC_DT6'
 '@SCM_LIB.SCM(SCH_1):BMC_EMMC_DT6':
 C_SIGNAL='@scm_lib.scm(sch_1):bmc_emmc_dt6';
NODE_NAME     U5 A21
 '@SCM_LIB.SCM(SCH_1):PAGE12_I436@PURE_QUANTA.AST2600A3GP(CHIPS)':
 'GPIOG4||TXD8||SD2DAT2||SALT13': CDS_PINID='\gpiog4||txd8||sd2dat2||salt13\';
NODE_NAME     R651 1
 '@SCM_LIB.SCM(SCH_1):PAGE21_I98@PURE_QUANTA.Q_RES(CHIPS)':
 'A': CDS_PINID='A';
NET_NAME
'BMC_EMMC_DT7'
 '@SCM_LIB.SCM(SCH_1):BMC_EMMC_DT7':
 C_SIGNAL='@scm_lib.scm(sch_1):bmc_emmc_dt7';
NODE_NAME     U5 E20
 '@SCM_LIB.SCM(SCH_1):PAGE12_I436@PURE_QUANTA.AST2600A3GP(CHIPS)':
 'GPIOG5||RXD8||SD2DAT3||SALT14': CDS_PINID='\gpiog5||rxd8||sd2dat3||salt14\';
NODE_NAME     R650 1
 '@SCM_LIB.SCM(SCH_1):PAGE21_I99@PURE_QUANTA.Q_RES(CHIPS)':
 'A': CDS_PINID='A';
NET_NAME
'BMC_EMMC_RST_N'
 '@SCM_LIB.SCM(SCH_1):BMC_EMMC_RST_N':
 C_SIGNAL='@scm_lib.scm(sch_1):bmc_emmc_rst_n';
NODE_NAME     R96 2
 '@SCM_LIB.SCM(SCH_1):PAGE13_I286@PURE_QUANTA.Q_RES(CHIPS)':
 'B': CDS_PINID='B';
NODE_NAME     J4 66
 '@SCM_LIB.SCM(SCH_1):PAGE21_I84@PURE_QUANTA.SCONN67_NASA0S6730TS67(CHIPS)':
 '66': CDS_PINID='\66\';
NODE_NAME     R11 2
 '@SCM_LIB.SCM(SCH_1):PAGE21_I172@PURE_QUANTA.Q_RES(CHIPS)':
 'B': CDS_PINID='B';
NET_NAME
'BMC_EMMC_RST_R_N'
 '@SCM_LIB.SCM(SCH_1):BMC_EMMC_RST_R_N':
 C_SIGNAL='@scm_lib.scm(sch_1):bmc_emmc_rst_r_n';
NODE_NAME     R96 1
 '@SCM_LIB.SCM(SCH_1):PAGE13_I286@PURE_QUANTA.Q_RES(CHIPS)':
 'A': CDS_PINID='A';
NODE_NAME     U5 AA12
 '@SCM_LIB.SCM(SCH_1):PAGE13_I363@PURE_QUANTA.AST2600A3GP(CHIPS)':
 'GPIOY3||SALT8||WDTRST4#': CDS_PINID='\gpioy3||salt8||wdtrst4#\';
NET_NAME
'BMC_EMMC_WP_N'
 '@SCM_LIB.SCM(SCH_1):BMC_EMMC_WP_N':
 C_SIGNAL='@scm_lib.scm(sch_1):bmc_emmc_wp_n';
NODE_NAME     U5 A23
 '@SCM_LIB.SCM(SCH_1):PAGE12_I436@PURE_QUANTA.AST2600A3GP(CHIPS)':
 'GPIOF7||SD1WP#||PWM15': CDS_PINID='\gpiof7||sd1wp#||pwm15\';
NODE_NAME     R684 1
 '@SCM_LIB.SCM(SCH_1):PAGE14_I163@PURE_QUANTA.Q_RES(CHIPS)':
 'A': CDS_PINID='A';
NODE_NAME     R686 2
 '@SCM_LIB.SCM(SCH_1):PAGE14_I164@PURE_QUANTA.Q_RES(CHIPS)':
 'B': CDS_PINID='B';
NET_NAME
'BMC_HEARTBEAT_N'
 '@SCM_LIB.SCM(SCH_1):BMC_HEARTBEAT_N':
 C_SIGNAL='@scm_lib.scm(sch_1):bmc_heartbeat_n';
NODE_NAME     D8 C
 '@SCM_LIB.SCM(SCH_1):PAGE13_I46@PURE_QUANTA.Q_LED(CHIPS)':
 'C': CDS_PINID='C';
NODE_NAME     R805 2
 '@SCM_LIB.SCM(SCH_1):PAGE13_I356@PURE_QUANTA.Q_RES(CHIPS)':
 'B': CDS_PINID='B';
NODE_NAME     U5 Y23
 '@SCM_LIB.SCM(SCH_1):PAGE15_I350@PURE_QUANTA.AST2600A3GP(CHIPS)':
 'GPIOP7||PWM15||HBLED#': CDS_PINID='\gpiop7||pwm15||hbled#\';
NET_NAME
'BMC_HEARTBEAT_R_N'
 '@SCM_LIB.SCM(SCH_1):BMC_HEARTBEAT_R_N':
 C_SIGNAL='@scm_lib.scm(sch_1):bmc_heartbeat_r_n';
NODE_NAME     R167 2
 '@SCM_LIB.SCM(SCH_1):PAGE13_I33@PURE_QUANTA.Q_RES(CHIPS)':
 'B': CDS_PINID='B';
NODE_NAME     D8 A
 '@SCM_LIB.SCM(SCH_1):PAGE13_I46@PURE_QUANTA.Q_LED(CHIPS)':
 'A': CDS_PINID='A';
NET_NAME
'BMC_ID_BEEP_SEL'
 '@SCM_LIB.SCM(SCH_1):BMC_ID_BEEP_SEL':
 C_SIGNAL='@scm_lib.scm(sch_1):bmc_id_beep_sel';
NODE_NAME     R461 1
 '@SCM_LIB.SCM(SCH_1):PAGE13_I365@PURE_QUANTA.Q_RES(CHIPS)':
 'A': CDS_PINID='A';
NODE_NAME     R319 2
 '@SCM_LIB.SCM(SCH_1):PAGE42_I65@PURE_QUANTA.Q_RES(CHIPS)':
 'B': CDS_PINID='B';
NODE_NAME     U8 1
 '@SCM_LIB.SCM(SCH_1):PAGE49_I11@PURE_QUANTA.74LVC1G126SE7(CHIPS)':
 'OE': CDS_PINID='OE';
NET_NAME
'BMC_ID_BEEP_SEL_R1'
 '@SCM_LIB.SCM(SCH_1):BMC_ID_BEEP_SEL_R1':
 C_SIGNAL='@scm_lib.scm(sch_1):bmc_id_beep_sel_r1';
NODE_NAME     U5 AD14
 '@SCM_LIB.SCM(SCH_1):PAGE13_I363@PURE_QUANTA.AST2600A3GP(CHIPS)':
 'GPIOV2||SIOPWREQ#': CDS_PINID='\gpiov2||siopwreq#\';
NODE_NAME     R461 2
 '@SCM_LIB.SCM(SCH_1):PAGE13_I365@PURE_QUANTA.Q_RES(CHIPS)':
 'B': CDS_PINID='B';
NET_NAME
'BMC_MONITER'
 '@SCM_LIB.SCM(SCH_1):BMC_MONITER':
 C_SIGNAL='@scm_lib.scm(sch_1):bmc_moniter';
NODE_NAME     U5 T25
 '@SCM_LIB.SCM(SCH_1):PAGE13_I363@PURE_QUANTA.AST2600A3GP(CHIPS)':
 'GPIOS1||MDIO1': CDS_PINID='\gpios1||mdio1\';
NODE_NAME     U25 M6
 '@SCM_LIB.SCM(SCH_1):PAGE36_I1@PURE_QUANTA.LCMXO3LF2100C5BG256C(CHIPS)':
 'PB11C': CDS_PINID='PB11C';
NET_NAME
'BMC_PWR_LED'
 '@SCM_LIB.SCM(SCH_1):BMC_PWR_LED':
 C_SIGNAL='@scm_lib.scm(sch_1):bmc_pwr_led';
NODE_NAME     R316 1
 '@SCM_LIB.SCM(SCH_1):PAGE15_I318@PURE_QUANTA.Q_RES(CHIPS)':
 'A': CDS_PINID='A';
NODE_NAME     U5 W23
 '@SCM_LIB.SCM(SCH_1):PAGE15_I350@PURE_QUANTA.AST2600A3GP(CHIPS)':
 'GPIOP4||PWM12||THRUIN2': CDS_PINID='\gpiop4||pwm12||thruin2\';
NET_NAME
'BMC_RSTIND_N'
 '@SCM_LIB.SCM(SCH_1):BMC_RSTIND_N':
 C_SIGNAL='@scm_lib.scm(sch_1):bmc_rstind_n';
NODE_NAME     R548 1
 '@SCM_LIB.SCM(SCH_1):PAGE25_I172@PURE_QUANTA.Q_RES(CHIPS)':
 'A': CDS_PINID='A';
NODE_NAME     R585 1
 '@SCM_LIB.SCM(SCH_1):PAGE15_I404@PURE_QUANTA.Q_RES(CHIPS)':
 'A': CDS_PINID='A';
NET_NAME
'BSM_PRSNT_N'
 '@SCM_LIB.SCM(SCH_1):BSM_PRSNT_N':
 C_SIGNAL='@scm_lib.scm(sch_1):bsm_prsnt_n';
NODE_NAME     J4 16
 '@SCM_LIB.SCM(SCH_1):PAGE21_I84@PURE_QUANTA.SCONN67_NASA0S6730TS67(CHIPS)':
 '16': CDS_PINID='\16\';
NODE_NAME     R404 2
 '@SCM_LIB.SCM(SCH_1):PAGE21_I166@PURE_QUANTA.Q_RES(CHIPS)':
 'B': CDS_PINID='B';
NODE_NAME     R57 2
 '@SCM_LIB.SCM(SCH_1):PAGE21_I167@PURE_QUANTA.Q_RES(CHIPS)':
 'B': CDS_PINID='B';
NET_NAME
'BSM_PRSNT_R1_N'
 '@SCM_LIB.SCM(SCH_1):BSM_PRSNT_R1_N':
 C_SIGNAL='@scm_lib.scm(sch_1):bsm_prsnt_r1_n';
NODE_NAME     U25 A3
 '@SCM_LIB.SCM(SCH_1):PAGE34_I1@PURE_QUANTA.LCMXO3LF2100C5BG256C(CHIPS)':
 'PT11C': CDS_PINID='PT11C';
NODE_NAME     R459 2
 '@SCM_LIB.SCM(SCH_1):PAGE34_I159@PURE_QUANTA.Q_RES(CHIPS)':
 'B': CDS_PINID='B';
NET_NAME
'BSM_PRSNT_R_N'
 '@SCM_LIB.SCM(SCH_1):BSM_PRSNT_R_N':
 C_SIGNAL='@scm_lib.scm(sch_1):bsm_prsnt_r_n';
NODE_NAME     U5 AC16
 '@SCM_LIB.SCM(SCH_1):PAGE15_I350@PURE_QUANTA.AST2600A3GP(CHIPS)':
 'ADC12||GPIU4||SALT13': CDS_PINID='\adc12||gpiu4||salt13\';
NODE_NAME     R57 1
 '@SCM_LIB.SCM(SCH_1):PAGE21_I167@PURE_QUANTA.Q_RES(CHIPS)':
 'A': CDS_PINID='A';
NODE_NAME     R459 1
 '@SCM_LIB.SCM(SCH_1):PAGE34_I159@PURE_QUANTA.Q_RES(CHIPS)':
 'A': CDS_PINID='A';
NET_NAME
'CLK_100M_GPU_DN'
 '@SCM_LIB.SCM(SCH_1):CLK_100M_GPU_DN':
 C_SIGNAL='@scm_lib.scm(sch_1):clk_100m_gpu_dn';
NODE_NAME     GF1 A69
 '@SCM_LIB.SCM(SCH_1):PAGE10_I553@PURE_QUANTA.FCONN168_ME1016810202011_SCM(CHIPS)':
 'PCIE_HPM_RXN_3': CDS_PINID='PCIE_HPM_RXN_3';
NODE_NAME     U5 AE2
 '@SCM_LIB.SCM(SCH_1):PAGE12_I436@PURE_QUANTA.AST2600A3GP(CHIPS)':
 'RCREFCLKN': CDS_PINID='RCREFCLKN';
NET_NAME
'CLK_100M_GPU_DP'
 '@SCM_LIB.SCM(SCH_1):CLK_100M_GPU_DP':
 C_SIGNAL='@scm_lib.scm(sch_1):clk_100m_gpu_dp';
NODE_NAME     GF1 A68
 '@SCM_LIB.SCM(SCH_1):PAGE10_I553@PURE_QUANTA.FCONN168_ME1016810202011_SCM(CHIPS)':
 'PCIE_HPM_RXP_3': CDS_PINID='PCIE_HPM_RXP_3';
NODE_NAME     U5 AE1
 '@SCM_LIB.SCM(SCH_1):PAGE12_I436@PURE_QUANTA.AST2600A3GP(CHIPS)':
 'RCREFCLKP': CDS_PINID='RCREFCLKP';
NET_NAME
'CLK_100M_PCH_DN'
 '@SCM_LIB.SCM(SCH_1):CLK_100M_PCH_DN':
 C_SIGNAL='@scm_lib.scm(sch_1):clk_100m_pch_dn';
NODE_NAME     GF1 A15
 '@SCM_LIB.SCM(SCH_1):PAGE10_I553@PURE_QUANTA.FCONN168_ME1016810202011_SCM(CHIPS)':
 'CLK_100M_PCIE_DN': CDS_PINID='CLK_100M_PCIE_DN';
NODE_NAME     U5 AD6
 '@SCM_LIB.SCM(SCH_1):PAGE12_I436@PURE_QUANTA.AST2600A3GP(CHIPS)':
 'PEREFCLKN': CDS_PINID='PEREFCLKN';
NET_NAME
'CLK_100M_PCH_DP'
 '@SCM_LIB.SCM(SCH_1):CLK_100M_PCH_DP':
 C_SIGNAL='@scm_lib.scm(sch_1):clk_100m_pch_dp';
NODE_NAME     GF1 A14
 '@SCM_LIB.SCM(SCH_1):PAGE10_I553@PURE_QUANTA.FCONN168_ME1016810202011_SCM(CHIPS)':
 'CLK_100M_PCIE_DP': CDS_PINID='CLK_100M_PCIE_DP';
NODE_NAME     U5 AD5
 '@SCM_LIB.SCM(SCH_1):PAGE12_I436@PURE_QUANTA.AST2600A3GP(CHIPS)':
 'PEREFCLKP': CDS_PINID='PEREFCLKP';
NET_NAME
'CLK_25M_OSC_FPGA'
 '@SCM_LIB.SCM(SCH_1):CLK_25M_OSC_FPGA':
 C_SIGNAL='@scm_lib.scm(sch_1):clk_25m_osc_fpga';
NODE_NAME     U25 C8
 '@SCM_LIB.SCM(SCH_1):PAGE34_I1@PURE_QUANTA.LCMXO3LF2100C5BG256C(CHIPS)':
 'PT17A||PCLKT0_1': CDS_PINID='\pt17a||pclkt0_1\';
NODE_NAME     R807 2
 '@SCM_LIB.SCM(SCH_1):PAGE34_I126@PURE_QUANTA.Q_RES(CHIPS)':
 'B': CDS_PINID='B';
NET_NAME
'CLK_25M_OSC_FPGA_R'
 '@SCM_LIB.SCM(SCH_1):CLK_25M_OSC_FPGA_R':
 C_SIGNAL='@scm_lib.scm(sch_1):clk_25m_osc_fpga_r';
NODE_NAME     R807 1
 '@SCM_LIB.SCM(SCH_1):PAGE34_I126@PURE_QUANTA.Q_RES(CHIPS)':
 'A': CDS_PINID='A';
NODE_NAME     OSC2 3
 '@SCM_LIB.SCM(SCH_1):PAGE34_I127@PURE_QUANTA.OSC4_7X25000018(CHIPS)':
 'OUT': CDS_PINID='\out\';
NET_NAME
'CLK_BUF1_GPU_FPGA_OE_R_N'
 '@SCM_LIB.SCM(SCH_1):CLK_BUF1_GPU_FPGA_OE_R_N':
 C_SIGNAL='@scm_lib.scm(sch_1):clk_buf1_gpu_fpga_oe_r_n';
NODE_NAME     U5 F26
 '@SCM_LIB.SCM(SCH_1):PAGE13_I363@PURE_QUANTA.AST2600A3GP(CHIPS)':
 'RGMII3RXD1||RMII3RXD1||GPIOD1': CDS_PINID='\rgmii3rxd1||rmii3rxd1||gpiod1\';
NODE_NAME     U25 N8
 '@SCM_LIB.SCM(SCH_1):PAGE36_I1@PURE_QUANTA.LCMXO3LF2100C5BG256C(CHIPS)':
 'PB12C': CDS_PINID='PB12C';
NET_NAME
'CLK_GEN2_BMC_RC_OE_N'
 '@SCM_LIB.SCM(SCH_1):CLK_GEN2_BMC_RC_OE_N':
 C_SIGNAL='@scm_lib.scm(sch_1):clk_gen2_bmc_rc_oe_n';
NODE_NAME     U5 AF10
 '@SCM_LIB.SCM(SCH_1):PAGE13_I363@PURE_QUANTA.AST2600A3GP(CHIPS)':
 'GPIOZ7||SPI1DQ3||RXD13': CDS_PINID='\gpioz7||spi1dq3||rxd13\';
NODE_NAME     U25 M7
 '@SCM_LIB.SCM(SCH_1):PAGE36_I1@PURE_QUANTA.LCMXO3LF2100C5BG256C(CHIPS)':
 'PB9C': CDS_PINID='PB9C';
NET_NAME
'CRT_VCC5'
 '@SCM_LIB.SCM(SCH_1):CRT_VCC5':
 C_SIGNAL='@scm_lib.scm(sch_1):crt_vcc5',
 CDS_GLOBAL_NET='TRUE';
NODE_NAME     R30 1
 '@SCM_LIB.SCM(SCH_1):PAGE23_I39@PURE_QUANTA.Q_RES(CHIPS)':
 'A': CDS_PINID='A';
NODE_NAME     R27 2
 '@SCM_LIB.SCM(SCH_1):PAGE23_I40@PURE_QUANTA.Q_RES(CHIPS)':
 'B': CDS_PINID='B';
NODE_NAME     D11 C
 '@SCM_LIB.SCM(SCH_1):PAGE23_I41@PURE_QUANTA.SCHOTTKY_AC(CHIPS)':
 'C': CDS_PINID='C';
NODE_NAME     D9 C
 '@SCM_LIB.SCM(SCH_1):PAGE23_I42@PURE_QUANTA.SCHOTTKY_AC(CHIPS)':
 'C': CDS_PINID='C';
NODE_NAME     C204 1
 '@SCM_LIB.SCM(SCH_1):PAGE23_I45@PURE_QUANTA.Q_CAP(CHIPS)':
 'A': CDS_PINID='A';
NODE_NAME     R91 1
 '@SCM_LIB.SCM(SCH_1):PAGE23_I62@PURE_QUANTA.Q_RES(CHIPS)':
 'A': CDS_PINID='A';
NODE_NAME     R92 1
 '@SCM_LIB.SCM(SCH_1):PAGE23_I64@PURE_QUANTA.Q_RES(CHIPS)':
 'A': CDS_PINID='A';
NODE_NAME     R17 2
 '@SCM_LIB.SCM(SCH_1):PAGE23_I68@PURE_QUANTA.Q_RES(CHIPS)':
 'B': CDS_PINID='B';
NODE_NAME     D12 1
 '@SCM_LIB.SCM(SCH_1):PAGE23_I74@PURE_QUANTA.BZA462A(CHIPS)':
 '1': CDS_PINID='\1\';
NODE_NAME     D12 3
 '@SCM_LIB.SCM(SCH_1):PAGE23_I74@PURE_QUANTA.BZA462A(CHIPS)':
 '3': CDS_PINID='\3\';
NODE_NAME     D12 4
 '@SCM_LIB.SCM(SCH_1):PAGE23_I74@PURE_QUANTA.BZA462A(CHIPS)':
 '4': CDS_PINID='\4\';
NODE_NAME     D12 6
 '@SCM_LIB.SCM(SCH_1):PAGE23_I74@PURE_QUANTA.BZA462A(CHIPS)':
 '6': CDS_PINID='\6\';
NODE_NAME     R16 2
 '@SCM_LIB.SCM(SCH_1):PAGE23_I75@PURE_QUANTA.Q_RES(CHIPS)':
 'B': CDS_PINID='B';
NET_NAME
'CRT_VCC5_2_D'
 '@SCM_LIB.SCM(SCH_1):CRT_VCC5_2_D':
 C_SIGNAL='@scm_lib.scm(sch_1):crt_vcc5_2_d';
NODE_NAME     FS1 1
 '@SCM_LIB.SCM(SCH_1):PAGE23_I153@PURE_QUANTA.Q_FUSE(CHIPS)':
 '1': CDS_PINID='\1\';
NODE_NAME     D16 2
 '@SCM_LIB.SCM(SCH_1):PAGE23_I161@PURE_QUANTA.SCHOTTKY_12(CHIPS)':
 'C': CDS_PINID='C';
NET_NAME
'CRT_VCC5_2_FUSE'
 '@SCM_LIB.SCM(SCH_1):CRT_VCC5_2_FUSE':
 C_SIGNAL='@scm_lib.scm(sch_1):crt_vcc5_2_fuse';
NODE_NAME     FS1 2
 '@SCM_LIB.SCM(SCH_1):PAGE23_I153@PURE_QUANTA.Q_FUSE(CHIPS)':
 '2': CDS_PINID='\2\';
NODE_NAME     J8 13
 '@SCM_LIB.SCM(SCH_1):PAGE23_I165@PURE_QUANTA.SCONN13_502280130CV01(CHIPS)':
 '13': CDS_PINID='\13\';
NET_NAME
'DEBUG_PORT_PRSNT'
 '@SCM_LIB.SCM(SCH_1):DEBUG_PORT_PRSNT':
 C_SIGNAL='@scm_lib.scm(sch_1):debug_port_prsnt';
NODE_NAME     U23 2
 '@SCM_LIB.SCM(SCH_1):PAGE28_I180@PURE_QUANTA.74LVC1G07W57(CHIPS)':
 'A': CDS_PINID='A';
NODE_NAME     U36 1
 '@SCM_LIB.SCM(SCH_1):PAGE29_I164@PURE_QUANTA.74HC1G126GW(CHIPS)':
 '1': CDS_PINID='\1\';
NODE_NAME     U29 1
 '@SCM_LIB.SCM(SCH_1):PAGE29_I174@PURE_QUANTA.74HC1G126GW(CHIPS)':
 '1': CDS_PINID='\1\';
NODE_NAME     Q6 G
 '@SCM_LIB.SCM(SCH_1):PAGE29_I202@PURE_QUANTA.2N7002A7(CHIPS)':
 'G': CDS_PINID='G';
NODE_NAME     U22 9
 '@SCM_LIB.SCM(SCH_1):PAGE29_I206@PURE_QUANTA.PI3PCIE3212ZBEX(CHIPS)':
 'SEL': CDS_PINID='SEL';
NODE_NAME     R693 1
 '@SCM_LIB.SCM(SCH_1):PAGE29_I222@PURE_QUANTA.Q_RES(CHIPS)':
 'A': CDS_PINID='A';
NET_NAME
'DEBUG_PORT_PRSNT_BUF_EN'
 '@SCM_LIB.SCM(SCH_1):DEBUG_PORT_PRSNT_BUF_EN':
 C_SIGNAL='@scm_lib.scm(sch_1):debug_port_prsnt_buf_en';
NODE_NAME     U37 5
 '@SCM_LIB.SCM(SCH_1):PAGE28_I99@PURE_QUANTA.PCA9517ADP(CHIPS)':
 'ENABLE': CDS_PINID='ENABLE';
NODE_NAME     R670 2
 '@SCM_LIB.SCM(SCH_1):PAGE28_I104@PURE_QUANTA.Q_RES(CHIPS)':
 'B': CDS_PINID='B';
NET_NAME
'DEBUG_PORT_PRSNT_BUF_R_EN'
 '@SCM_LIB.SCM(SCH_1):DEBUG_PORT_PRSNT_BUF_R_EN':
 C_SIGNAL='@scm_lib.scm(sch_1):debug_port_prsnt_buf_r_en';
NODE_NAME     R670 1
 '@SCM_LIB.SCM(SCH_1):PAGE28_I104@PURE_QUANTA.Q_RES(CHIPS)':
 'A': CDS_PINID='A';
NODE_NAME     R296 1
 '@SCM_LIB.SCM(SCH_1):PAGE28_I105@PURE_QUANTA.Q_RES(CHIPS)':
 'A': CDS_PINID='A';
NODE_NAME     R295 2
 '@SCM_LIB.SCM(SCH_1):PAGE28_I113@PURE_QUANTA.Q_RES(CHIPS)':
 'B': CDS_PINID='B';
NODE_NAME     U23 4
 '@SCM_LIB.SCM(SCH_1):PAGE28_I180@PURE_QUANTA.74LVC1G07W57(CHIPS)':
 'Y': CDS_PINID='Y';
NET_NAME
'DEBUG_PORT_PRSNT_R'
 '@SCM_LIB.SCM(SCH_1):DEBUG_PORT_PRSNT_R':
 C_SIGNAL='@scm_lib.scm(sch_1):debug_port_prsnt_r';
NODE_NAME     R205 1
 '@SCM_LIB.SCM(SCH_1):PAGE29_I184@PURE_QUANTA.Q_RES(CHIPS)':
 'A': CDS_PINID='A';
NODE_NAME     J2 7
 '@SCM_LIB.SCM(SCH_1):PAGE29_I221@PURE_QUANTA.CONN9_GSB3111315HR(CHIPS)':
 'GND_D': CDS_PINID='GND_D';
NODE_NAME     R693 2
 '@SCM_LIB.SCM(SCH_1):PAGE29_I222@PURE_QUANTA.Q_RES(CHIPS)':
 'B': CDS_PINID='B';
NET_NAME
'DEBUG_PORT_UART_RX'
 '@SCM_LIB.SCM(SCH_1):DEBUG_PORT_UART_RX':
 C_SIGNAL='@scm_lib.scm(sch_1):debug_port_uart_rx';
NODE_NAME     R274 2
 '@SCM_LIB.SCM(SCH_1):PAGE29_I157@PURE_QUANTA.Q_RES(CHIPS)':
 'B': CDS_PINID='B';
NODE_NAME     U36 2
 '@SCM_LIB.SCM(SCH_1):PAGE29_I164@PURE_QUANTA.74HC1G126GW(CHIPS)':
 '2': CDS_PINID='\2\';
NODE_NAME     U22 15
 '@SCM_LIB.SCM(SCH_1):PAGE29_I206@PURE_QUANTA.PI3PCIE3212ZBEX(CHIPS)':
 'C0_P': CDS_PINID='C0_P';
NET_NAME
'DEBUG_PORT_UART_TX'
 '@SCM_LIB.SCM(SCH_1):DEBUG_PORT_UART_TX':
 C_SIGNAL='@scm_lib.scm(sch_1):debug_port_uart_tx';
NODE_NAME     R219 1
 '@SCM_LIB.SCM(SCH_1):PAGE29_I170@PURE_QUANTA.Q_RES(CHIPS)':
 'A': CDS_PINID='A';
NODE_NAME     U29 4
 '@SCM_LIB.SCM(SCH_1):PAGE29_I174@PURE_QUANTA.74HC1G126GW(CHIPS)':
 '4': CDS_PINID='\4\';
NODE_NAME     U22 14
 '@SCM_LIB.SCM(SCH_1):PAGE29_I206@PURE_QUANTA.PI3PCIE3212ZBEX(CHIPS)':
 'C0_N': CDS_PINID='C0_N';
NET_NAME
'DP_BMC_HPD_3V3_BUF'
 '@SCM_LIB.SCM(SCH_1):DP_BMC_HPD_3V3_BUF':
 C_SIGNAL='@scm_lib.scm(sch_1):dp_bmc_hpd_3v3_buf';
NODE_NAME     U5 C7
 '@SCM_LIB.SCM(SCH_1):PAGE12_I436@PURE_QUANTA.AST2600A3GP(CHIPS)':
 'DPHPD': CDS_PINID='DPHPD';
NODE_NAME     R387 2
 '@SCM_LIB.SCM(SCH_1):PAGE12_I508@PURE_QUANTA.Q_RES(CHIPS)':
 'B': CDS_PINID='B';
NET_NAME
'EMMC_CLK_R'
 '@SCM_LIB.SCM(SCH_1):EMMC_CLK_R':
 C_SIGNAL='@scm_lib.scm(sch_1):emmc_clk_r';
NODE_NAME     R654 1
 '@SCM_LIB.SCM(SCH_1):PAGE21_I33@PURE_QUANTA.Q_RES(CHIPS)':
 'A': CDS_PINID='A';
NODE_NAME     J4 55
 '@SCM_LIB.SCM(SCH_1):PAGE21_I84@PURE_QUANTA.SCONN67_NASA0S6730TS67(CHIPS)':
 '55': CDS_PINID='\55\';
NET_NAME
'EMMC_CMD_R'
 '@SCM_LIB.SCM(SCH_1):EMMC_CMD_R':
 C_SIGNAL='@scm_lib.scm(sch_1):emmc_cmd_r';
NODE_NAME     R48 1
 '@SCM_LIB.SCM(SCH_1):PAGE21_I35@PURE_QUANTA.Q_RES(CHIPS)':
 'A': CDS_PINID='A';
NODE_NAME     R663 2
 '@SCM_LIB.SCM(SCH_1):PAGE21_I59@PURE_QUANTA.Q_RES(CHIPS)':
 'B': CDS_PINID='B';
NODE_NAME     J4 59
 '@SCM_LIB.SCM(SCH_1):PAGE21_I84@PURE_QUANTA.SCONN67_NASA0S6730TS67(CHIPS)':
 '59': CDS_PINID='\59\';
NET_NAME
'EMMC_DT0_R'
 '@SCM_LIB.SCM(SCH_1):EMMC_DT0_R':
 C_SIGNAL='@scm_lib.scm(sch_1):emmc_dt0_r';
NODE_NAME     R649 1
 '@SCM_LIB.SCM(SCH_1):PAGE21_I42@PURE_QUANTA.Q_RES(CHIPS)':
 'A': CDS_PINID='A';
NODE_NAME     R655 2
 '@SCM_LIB.SCM(SCH_1):PAGE21_I67@PURE_QUANTA.Q_RES(CHIPS)':
 'B': CDS_PINID='B';
NODE_NAME     J4 71
 '@SCM_LIB.SCM(SCH_1):PAGE21_I84@PURE_QUANTA.SCONN67_NASA0S6730TS67(CHIPS)':
 '71': CDS_PINID='\71\';
NET_NAME
'EMMC_DT1_R'
 '@SCM_LIB.SCM(SCH_1):EMMC_DT1_R':
 C_SIGNAL='@scm_lib.scm(sch_1):emmc_dt1_r';
NODE_NAME     R648 1
 '@SCM_LIB.SCM(SCH_1):PAGE21_I43@PURE_QUANTA.Q_RES(CHIPS)':
 'A': CDS_PINID='A';
NODE_NAME     R656 2
 '@SCM_LIB.SCM(SCH_1):PAGE21_I66@PURE_QUANTA.Q_RES(CHIPS)':
 'B': CDS_PINID='B';
NODE_NAME     J4 67
 '@SCM_LIB.SCM(SCH_1):PAGE21_I84@PURE_QUANTA.SCONN67_NASA0S6730TS67(CHIPS)':
 '67': CDS_PINID='\67\';
NET_NAME
'EMMC_DT2_R'
 '@SCM_LIB.SCM(SCH_1):EMMC_DT2_R':
 C_SIGNAL='@scm_lib.scm(sch_1):emmc_dt2_r';
NODE_NAME     R647 1
 '@SCM_LIB.SCM(SCH_1):PAGE21_I45@PURE_QUANTA.Q_RES(CHIPS)':
 'A': CDS_PINID='A';
NODE_NAME     R657 2
 '@SCM_LIB.SCM(SCH_1):PAGE21_I63@PURE_QUANTA.Q_RES(CHIPS)':
 'B': CDS_PINID='B';
NODE_NAME     J4 65
 '@SCM_LIB.SCM(SCH_1):PAGE21_I84@PURE_QUANTA.SCONN67_NASA0S6730TS67(CHIPS)':
 '65': CDS_PINID='\65\';
NET_NAME
'EMMC_DT3_R'
 '@SCM_LIB.SCM(SCH_1):EMMC_DT3_R':
 C_SIGNAL='@scm_lib.scm(sch_1):emmc_dt3_r';
NODE_NAME     R532 1
 '@SCM_LIB.SCM(SCH_1):PAGE21_I46@PURE_QUANTA.Q_RES(CHIPS)':
 'A': CDS_PINID='A';
NODE_NAME     R658 2
 '@SCM_LIB.SCM(SCH_1):PAGE21_I62@PURE_QUANTA.Q_RES(CHIPS)':
 'B': CDS_PINID='B';
NODE_NAME     J4 61
 '@SCM_LIB.SCM(SCH_1):PAGE21_I84@PURE_QUANTA.SCONN67_NASA0S6730TS67(CHIPS)':
 '61': CDS_PINID='\61\';
NET_NAME
'EMMC_DT4_R'
 '@SCM_LIB.SCM(SCH_1):EMMC_DT4_R':
 C_SIGNAL='@scm_lib.scm(sch_1):emmc_dt4_r';
NODE_NAME     R659 2
 '@SCM_LIB.SCM(SCH_1):PAGE21_I64@PURE_QUANTA.Q_RES(CHIPS)':
 'B': CDS_PINID='B';
NODE_NAME     J4 58
 '@SCM_LIB.SCM(SCH_1):PAGE21_I84@PURE_QUANTA.SCONN67_NASA0S6730TS67(CHIPS)':
 '58': CDS_PINID='\58\';
NODE_NAME     R653 2
 '@SCM_LIB.SCM(SCH_1):PAGE21_I100@PURE_QUANTA.Q_RES(CHIPS)':
 'B': CDS_PINID='B';
NET_NAME
'EMMC_DT5_R'
 '@SCM_LIB.SCM(SCH_1):EMMC_DT5_R':
 C_SIGNAL='@scm_lib.scm(sch_1):emmc_dt5_r';
NODE_NAME     R660 2
 '@SCM_LIB.SCM(SCH_1):PAGE21_I61@PURE_QUANTA.Q_RES(CHIPS)':
 'B': CDS_PINID='B';
NODE_NAME     J4 56
 '@SCM_LIB.SCM(SCH_1):PAGE21_I84@PURE_QUANTA.SCONN67_NASA0S6730TS67(CHIPS)':
 '56': CDS_PINID='\56\';
NODE_NAME     R652 2
 '@SCM_LIB.SCM(SCH_1):PAGE21_I101@PURE_QUANTA.Q_RES(CHIPS)':
 'B': CDS_PINID='B';
NET_NAME
'EMMC_DT6_R'
 '@SCM_LIB.SCM(SCH_1):EMMC_DT6_R':
 C_SIGNAL='@scm_lib.scm(sch_1):emmc_dt6_r';
NODE_NAME     R661 2
 '@SCM_LIB.SCM(SCH_1):PAGE21_I60@PURE_QUANTA.Q_RES(CHIPS)':
 'B': CDS_PINID='B';
NODE_NAME     J4 54
 '@SCM_LIB.SCM(SCH_1):PAGE21_I84@PURE_QUANTA.SCONN67_NASA0S6730TS67(CHIPS)':
 '54': CDS_PINID='\54\';
NODE_NAME     R651 2
 '@SCM_LIB.SCM(SCH_1):PAGE21_I98@PURE_QUANTA.Q_RES(CHIPS)':
 'B': CDS_PINID='B';
NET_NAME
'EMMC_DT7_R'
 '@SCM_LIB.SCM(SCH_1):EMMC_DT7_R':
 C_SIGNAL='@scm_lib.scm(sch_1):emmc_dt7_r';
NODE_NAME     R662 2
 '@SCM_LIB.SCM(SCH_1):PAGE21_I58@PURE_QUANTA.Q_RES(CHIPS)':
 'B': CDS_PINID='B';
NODE_NAME     J4 52
 '@SCM_LIB.SCM(SCH_1):PAGE21_I84@PURE_QUANTA.SCONN67_NASA0S6730TS67(CHIPS)':
 '52': CDS_PINID='\52\';
NODE_NAME     R650 2
 '@SCM_LIB.SCM(SCH_1):PAGE21_I99@PURE_QUANTA.Q_RES(CHIPS)':
 'B': CDS_PINID='B';
NET_NAME
'EMMC_WP'
 '@SCM_LIB.SCM(SCH_1):EMMC_WP':
 C_SIGNAL='@scm_lib.scm(sch_1):emmc_wp';
NODE_NAME     J4 46
 '@SCM_LIB.SCM(SCH_1):PAGE21_I84@PURE_QUANTA.SCONN67_NASA0S6730TS67(CHIPS)':
 '46': CDS_PINID='\46\';
NODE_NAME     R867 2
 '@SCM_LIB.SCM(SCH_1):PAGE21_I161@PURE_QUANTA.Q_RES(CHIPS)':
 'B': CDS_PINID='B';
NET_NAME
'EN_P1V0_AUX'
 '@SCM_LIB.SCM(SCH_1):EN_P1V0_AUX':
 C_SIGNAL='@scm_lib.scm(sch_1):en_p1v0_aux';
NODE_NAME     R399 1
 '@SCM_LIB.SCM(SCH_1):PAGE56_I55@PURE_QUANTA.Q_RES(CHIPS)':
 'A': CDS_PINID='A';
NODE_NAME     U53 4
 '@SCM_LIB.SCM(SCH_1):PAGE56_I66@PURE_QUANTA.74LVC1G08GW(CHIPS)':
 'Y': CDS_PINID='Y';
NET_NAME
'EN_P1V0_AUX_R'
 '@SCM_LIB.SCM(SCH_1):EN_P1V0_AUX_R':
 C_SIGNAL='@scm_lib.scm(sch_1):en_p1v0_aux_r';
NODE_NAME     PU42 5
 '@SCM_LIB.SCM(SCH_1):PAGE56_I15@PURE_QUANTA.NB695GDZ(CHIPS)':
 'EN': CDS_PINID='EN';
NODE_NAME     R399 2
 '@SCM_LIB.SCM(SCH_1):PAGE56_I55@PURE_QUANTA.Q_RES(CHIPS)':
 'B': CDS_PINID='B';
NODE_NAME     R878 2
 '@SCM_LIB.SCM(SCH_1):PAGE56_I72@PURE_QUANTA.Q_RES(CHIPS)':
 'B': CDS_PINID='B';
NET_NAME
'EN_P1V2_AUX'
 '@SCM_LIB.SCM(SCH_1):EN_P1V2_AUX':
 C_SIGNAL='@scm_lib.scm(sch_1):en_p1v2_aux';
NODE_NAME     R708 1
 '@SCM_LIB.SCM(SCH_1):PAGE55_I38@PURE_QUANTA.Q_RES(CHIPS)':
 'A': CDS_PINID='A';
NODE_NAME     U52 4
 '@SCM_LIB.SCM(SCH_1):PAGE55_I63@PURE_QUANTA.74LVC1G08GW(CHIPS)':
 'Y': CDS_PINID='Y';
NET_NAME
'EN_P1V2_AUX_R'
 '@SCM_LIB.SCM(SCH_1):EN_P1V2_AUX_R':
 C_SIGNAL='@scm_lib.scm(sch_1):en_p1v2_aux_r';
NODE_NAME     PU41 5
 '@SCM_LIB.SCM(SCH_1):PAGE55_I15@PURE_QUANTA.NB695GDZ(CHIPS)':
 'EN': CDS_PINID='EN';
NODE_NAME     R708 2
 '@SCM_LIB.SCM(SCH_1):PAGE55_I38@PURE_QUANTA.Q_RES(CHIPS)':
 'B': CDS_PINID='B';
NODE_NAME     R764 2
 '@SCM_LIB.SCM(SCH_1):PAGE55_I41@PURE_QUANTA.Q_RES(CHIPS)':
 'B': CDS_PINID='B';
NODE_NAME     R876 2
 '@SCM_LIB.SCM(SCH_1):PAGE55_I68@PURE_QUANTA.Q_RES(CHIPS)':
 'B': CDS_PINID='B';
NET_NAME
'EN_P1V8'
 '@SCM_LIB.SCM(SCH_1):EN_P1V8':
 C_SIGNAL='@scm_lib.scm(sch_1):en_p1v8';
NODE_NAME     R393 1
 '@SCM_LIB.SCM(SCH_1):PAGE54_I102@PURE_QUANTA.Q_RES(CHIPS)':
 'A': CDS_PINID='A';
NODE_NAME     U49 4
 '@SCM_LIB.SCM(SCH_1):PAGE54_I116@PURE_QUANTA.MC74VHC1G32DTT1G(CHIPS)':
 'OUT_Y': CDS_PINID='OUT_Y';
NET_NAME
'EN_P1V8_R'
 '@SCM_LIB.SCM(SCH_1):EN_P1V8_R':
 C_SIGNAL='@scm_lib.scm(sch_1):en_p1v8_r';
NODE_NAME     U41 6
 '@SCM_LIB.SCM(SCH_1):PAGE54_I96@PURE_QUANTA.RT9059GQW(CHIPS)':
 'EN': CDS_PINID='EN';
NODE_NAME     R393 2
 '@SCM_LIB.SCM(SCH_1):PAGE54_I102@PURE_QUANTA.Q_RES(CHIPS)':
 'B': CDS_PINID='B';
NODE_NAME     R875 2
 '@SCM_LIB.SCM(SCH_1):PAGE54_I137@PURE_QUANTA.Q_RES(CHIPS)':
 'B': CDS_PINID='B';
NET_NAME
'EN_P3V3'
 '@SCM_LIB.SCM(SCH_1):EN_P3V3':
 C_SIGNAL='@scm_lib.scm(sch_1):en_p3v3';
NODE_NAME     R381 1
 '@SCM_LIB.SCM(SCH_1):PAGE52_I97@PURE_QUANTA.Q_RES(CHIPS)':
 'A': CDS_PINID='A';
NODE_NAME     U42 4
 '@SCM_LIB.SCM(SCH_1):PAGE52_I104@PURE_QUANTA.MC74VHC1G32DTT1G(CHIPS)':
 'OUT_Y': CDS_PINID='OUT_Y';
NET_NAME
'EN_P3V3_R1'
 '@SCM_LIB.SCM(SCH_1):EN_P3V3_R1':
 C_SIGNAL='@scm_lib.scm(sch_1):en_p3v3_r1';
NODE_NAME     R868 2
 '@SCM_LIB.SCM(SCH_1):PAGE51_I54@PURE_QUANTA.Q_RES(CHIPS)':
 'B': CDS_PINID='B';
NODE_NAME     R871 1
 '@SCM_LIB.SCM(SCH_1):PAGE52_I137@PURE_QUANTA.Q_RES(CHIPS)':
 'A': CDS_PINID='A';
NET_NAME
'EN_P3V3_RGM'
 '@SCM_LIB.SCM(SCH_1):EN_P3V3_RGM':
 C_SIGNAL='@scm_lib.scm(sch_1):en_p3v3_rgm';
NODE_NAME     U18 4
 '@SCM_LIB.SCM(SCH_1):PAGE52_I114@PURE_QUANTA.74LVC1G08GW(CHIPS)':
 'Y': CDS_PINID='Y';
NODE_NAME     R380 1
 '@SCM_LIB.SCM(SCH_1):PAGE52_I147@PURE_QUANTA.Q_RES(CHIPS)':
 'A': CDS_PINID='A';
NET_NAME
'EN_P3V3_RGM_R'
 '@SCM_LIB.SCM(SCH_1):EN_P3V3_RGM_R':
 C_SIGNAL='@scm_lib.scm(sch_1):en_p3v3_rgm_r';
NODE_NAME     U14 4
 '@SCM_LIB.SCM(SCH_1):PAGE52_I79@PURE_QUANTA.AP22811AW57(CHIPS)':
 'EN': CDS_PINID='EN';
NODE_NAME     R869 2
 '@SCM_LIB.SCM(SCH_1):PAGE52_I139@PURE_QUANTA.Q_RES(CHIPS)':
 'B': CDS_PINID='B';
NODE_NAME     R380 2
 '@SCM_LIB.SCM(SCH_1):PAGE52_I147@PURE_QUANTA.Q_RES(CHIPS)':
 'B': CDS_PINID='B';
NET_NAME
'EN_P5V_AUX'
 '@SCM_LIB.SCM(SCH_1):EN_P5V_AUX':
 C_SIGNAL='@scm_lib.scm(sch_1):en_p5v_aux';
NODE_NAME     PC205 1
 '@SCM_LIB.SCM(SCH_1):PAGE51_I1@PURE_QUANTA.Q_CAP(CHIPS)':
 'A': CDS_PINID='A';
NODE_NAME     PR522 1
 '@SCM_LIB.SCM(SCH_1):PAGE51_I3@PURE_QUANTA.Q_RES(CHIPS)':
 'A': CDS_PINID='A';
NODE_NAME     PR521 2
 '@SCM_LIB.SCM(SCH_1):PAGE51_I4@PURE_QUANTA.Q_RES(CHIPS)':
 'B': CDS_PINID='B';
NODE_NAME     PU38 8
 '@SCM_LIB.SCM(SCH_1):PAGE51_I42@PURE_QUANTA.MPQ8633AGLEC807Z(CHIPS)':
 'EN': CDS_PINID='EN';
NET_NAME
'ESPI_HOST_LPC_BMC_CLK'
 '@SCM_LIB.SCM(SCH_1):ESPI_HOST_LPC_BMC_CLK':
 C_SIGNAL='@scm_lib.scm(sch_1):espi_host_lpc_bmc_clk';
NODE_NAME     GF1 B1
 '@SCM_LIB.SCM(SCH_1):PAGE10_I553@PURE_QUANTA.FCONN168_ME1016810202011_SCM(CHIPS)':
 'ESPI_CLK': CDS_PINID='ESPI_CLK';
NODE_NAME     R310 1
 '@SCM_LIB.SCM(SCH_1):PAGE12_I441@PURE_QUANTA.Q_RES(CHIPS)':
 'A': CDS_PINID='A';
NET_NAME
'ESPI_HOST_LPC_BMC_CLK_R'
 '@SCM_LIB.SCM(SCH_1):ESPI_HOST_LPC_BMC_CLK_R':
 C_SIGNAL='@scm_lib.scm(sch_1):espi_host_lpc_bmc_clk_r';
NODE_NAME     U5 AE7
 '@SCM_LIB.SCM(SCH_1):PAGE12_I436@PURE_QUANTA.AST2600A3GP(CHIPS)':
 'GPIOW4||LCLK||ESPICK': CDS_PINID='\gpiow4||lclk||espick\';
NODE_NAME     R310 2
 '@SCM_LIB.SCM(SCH_1):PAGE12_I441@PURE_QUANTA.Q_RES(CHIPS)':
 'B': CDS_PINID='B';
NET_NAME
'ESPI_HOST_LPC_BMC_LFRAME_N'
 '@SCM_LIB.SCM(SCH_1):ESPI_HOST_LPC_BMC_LFRAME_N':
 C_SIGNAL='@scm_lib.scm(sch_1):espi_host_lpc_bmc_lframe_n';
NODE_NAME     GF1 B2
 '@SCM_LIB.SCM(SCH_1):PAGE10_I553@PURE_QUANTA.FCONN168_ME1016810202011_SCM(CHIPS)':
 'ESPI_CS0_N': CDS_PINID='ESPI_CS0_N';
NODE_NAME     R115 2
 '@SCM_LIB.SCM(SCH_1):PAGE12_I4@PURE_QUANTA.Q_RES(CHIPS)':
 'B': CDS_PINID='B';
NODE_NAME     R311 1
 '@SCM_LIB.SCM(SCH_1):PAGE12_I447@PURE_QUANTA.Q_RES(CHIPS)':
 'A': CDS_PINID='A';
NET_NAME
'ESPI_HOST_LPC_BMC_LFRAME_N_R'
 '@SCM_LIB.SCM(SCH_1):ESPI_HOST_LPC_BMC_LFRAME_N_R':
 C_SIGNAL='@scm_lib.scm(sch_1):espi_host_lpc_bmc_lframe_n_r';
NODE_NAME     U5 AF7
 '@SCM_LIB.SCM(SCH_1):PAGE12_I436@PURE_QUANTA.AST2600A3GP(CHIPS)':
 'GPIOW5||LFRAME#||ESPICS#': CDS_PINID='\gpiow5||lframe#||espics#\';
NODE_NAME     R311 2
 '@SCM_LIB.SCM(SCH_1):PAGE12_I447@PURE_QUANTA.Q_RES(CHIPS)':
 'B': CDS_PINID='B';
NET_NAME
'ESPI_LPC_D0_IO0'
 '@SCM_LIB.SCM(SCH_1):ESPI_LPC_D0_IO0':
 C_SIGNAL='@scm_lib.scm(sch_1):espi_lpc_d0_io0';
NODE_NAME     U5 AB7
 '@SCM_LIB.SCM(SCH_1):PAGE12_I436@PURE_QUANTA.AST2600A3GP(CHIPS)':
 'GPIOW0||LAD0||ESPID0': CDS_PINID='\gpiow0||lad0||espid0\';
NODE_NAME     R128 1
 '@SCM_LIB.SCM(SCH_1):PAGE12_I442@PURE_QUANTA.Q_RES(CHIPS)':
 'A': CDS_PINID='A';
NET_NAME
'ESPI_LPC_D1_IO1'
 '@SCM_LIB.SCM(SCH_1):ESPI_LPC_D1_IO1':
 C_SIGNAL='@scm_lib.scm(sch_1):espi_lpc_d1_io1';
NODE_NAME     U5 AB8
 '@SCM_LIB.SCM(SCH_1):PAGE12_I436@PURE_QUANTA.AST2600A3GP(CHIPS)':
 'GPIOW1||LAD1||ESPID1': CDS_PINID='\gpiow1||lad1||espid1\';
NODE_NAME     R129 1
 '@SCM_LIB.SCM(SCH_1):PAGE12_I445@PURE_QUANTA.Q_RES(CHIPS)':
 'A': CDS_PINID='A';
NET_NAME
'ESPI_LPC_D2_IO2'
 '@SCM_LIB.SCM(SCH_1):ESPI_LPC_D2_IO2':
 C_SIGNAL='@scm_lib.scm(sch_1):espi_lpc_d2_io2';
NODE_NAME     U5 AC8
 '@SCM_LIB.SCM(SCH_1):PAGE12_I436@PURE_QUANTA.AST2600A3GP(CHIPS)':
 'GPIOW2||LAD2||ESPID2': CDS_PINID='\gpiow2||lad2||espid2\';
NODE_NAME     R130 1
 '@SCM_LIB.SCM(SCH_1):PAGE12_I444@PURE_QUANTA.Q_RES(CHIPS)':
 'A': CDS_PINID='A';
NET_NAME
'ESPI_LPC_D3_IO3'
 '@SCM_LIB.SCM(SCH_1):ESPI_LPC_D3_IO3':
 C_SIGNAL='@scm_lib.scm(sch_1):espi_lpc_d3_io3';
NODE_NAME     U5 AC7
 '@SCM_LIB.SCM(SCH_1):PAGE12_I436@PURE_QUANTA.AST2600A3GP(CHIPS)':
 'GPIOW3||LAD3||ESPID3': CDS_PINID='\gpiow3||lad3||espid3\';
NODE_NAME     R131 1
 '@SCM_LIB.SCM(SCH_1):PAGE12_I443@PURE_QUANTA.Q_RES(CHIPS)':
 'A': CDS_PINID='A';
NET_NAME
'ESPI_LPC_LAD0_IO0'
 '@SCM_LIB.SCM(SCH_1):ESPI_LPC_LAD0_IO0':
 C_SIGNAL='@scm_lib.scm(sch_1):espi_lpc_lad0_io0';
NODE_NAME     GF1 B5
 '@SCM_LIB.SCM(SCH_1):PAGE10_I553@PURE_QUANTA.FCONN168_ME1016810202011_SCM(CHIPS)':
 'ESPI_IO0': CDS_PINID='ESPI_IO0';
NODE_NAME     R128 2
 '@SCM_LIB.SCM(SCH_1):PAGE12_I442@PURE_QUANTA.Q_RES(CHIPS)':
 'B': CDS_PINID='B';
NET_NAME
'ESPI_LPC_LAD1_IO1'
 '@SCM_LIB.SCM(SCH_1):ESPI_LPC_LAD1_IO1':
 C_SIGNAL='@scm_lib.scm(sch_1):espi_lpc_lad1_io1';
NODE_NAME     GF1 B6
 '@SCM_LIB.SCM(SCH_1):PAGE10_I553@PURE_QUANTA.FCONN168_ME1016810202011_SCM(CHIPS)':
 'ESPI_IO1': CDS_PINID='ESPI_IO1';
NODE_NAME     R129 2
 '@SCM_LIB.SCM(SCH_1):PAGE12_I445@PURE_QUANTA.Q_RES(CHIPS)':
 'B': CDS_PINID='B';
NET_NAME
'ESPI_LPC_LAD2_IO2'
 '@SCM_LIB.SCM(SCH_1):ESPI_LPC_LAD2_IO2':
 C_SIGNAL='@scm_lib.scm(sch_1):espi_lpc_lad2_io2';
NODE_NAME     GF1 B7
 '@SCM_LIB.SCM(SCH_1):PAGE10_I553@PURE_QUANTA.FCONN168_ME1016810202011_SCM(CHIPS)':
 'ESPI_IO2': CDS_PINID='ESPI_IO2';
NODE_NAME     R130 2
 '@SCM_LIB.SCM(SCH_1):PAGE12_I444@PURE_QUANTA.Q_RES(CHIPS)':
 'B': CDS_PINID='B';
NET_NAME
'ESPI_LPC_LAD3_IO3'
 '@SCM_LIB.SCM(SCH_1):ESPI_LPC_LAD3_IO3':
 C_SIGNAL='@scm_lib.scm(sch_1):espi_lpc_lad3_io3';
NODE_NAME     GF1 B8
 '@SCM_LIB.SCM(SCH_1):PAGE10_I553@PURE_QUANTA.FCONN168_ME1016810202011_SCM(CHIPS)':
 'ESPI_IO3': CDS_PINID='ESPI_IO3';
NODE_NAME     R131 2
 '@SCM_LIB.SCM(SCH_1):PAGE12_I443@PURE_QUANTA.Q_RES(CHIPS)':
 'B': CDS_PINID='B';
NET_NAME
'FLASH_LATCH_CP'
 '@SCM_LIB.SCM(SCH_1):FLASH_LATCH_CP':
 C_SIGNAL='@scm_lib.scm(sch_1):flash_latch_cp';
NODE_NAME     U54 1
 '@SCM_LIB.SCM(SCH_1):PAGE25_I138@PURE_QUANTA.74LVC1G74DP(CHIPS)':
 'CP': CDS_PINID='CP';
NODE_NAME     R545 2
 '@SCM_LIB.SCM(SCH_1):PAGE25_I143@PURE_QUANTA.Q_RES(CHIPS)':
 'B': CDS_PINID='B';
NET_NAME
'FLASH_LATCH_D'
 '@SCM_LIB.SCM(SCH_1):FLASH_LATCH_D':
 C_SIGNAL='@scm_lib.scm(sch_1):flash_latch_d';
NODE_NAME     U54 2
 '@SCM_LIB.SCM(SCH_1):PAGE25_I138@PURE_QUANTA.74LVC1G74DP(CHIPS)':
 'D': CDS_PINID='D';
NODE_NAME     R182 2
 '@SCM_LIB.SCM(SCH_1):PAGE25_I142@PURE_QUANTA.Q_RES(CHIPS)':
 'B': CDS_PINID='B';
NET_NAME
'FLASH_LATCH_Q_N_R'
 '@SCM_LIB.SCM(SCH_1):FLASH_LATCH_Q_N_R':
 C_SIGNAL='@scm_lib.scm(sch_1):flash_latch_q_n_r';
NODE_NAME     U54 3
 '@SCM_LIB.SCM(SCH_1):PAGE25_I138@PURE_QUANTA.74LVC1G74DP(CHIPS)':
 'Q_N': CDS_PINID='Q_N';
NODE_NAME     R555 1
 '@SCM_LIB.SCM(SCH_1):PAGE25_I174@PURE_QUANTA.Q_RES(CHIPS)':
 'A': CDS_PINID='A';
NET_NAME
'FLASH_LATCH_Q_N_R1'
 '@SCM_LIB.SCM(SCH_1):FLASH_LATCH_Q_N_R1':
 C_SIGNAL='@scm_lib.scm(sch_1):flash_latch_q_n_r1';
NODE_NAME     R560 1
 '@SCM_LIB.SCM(SCH_1):PAGE25_I149@PURE_QUANTA.Q_RES(CHIPS)':
 'A': CDS_PINID='A';
NODE_NAME     R555 2
 '@SCM_LIB.SCM(SCH_1):PAGE25_I174@PURE_QUANTA.Q_RES(CHIPS)':
 'B': CDS_PINID='B';
NET_NAME
'FLASH_LATCH_Q_N_R2'
 '@SCM_LIB.SCM(SCH_1):FLASH_LATCH_Q_N_R2':
 C_SIGNAL='@scm_lib.scm(sch_1):flash_latch_q_n_r2';
NODE_NAME     R560 2
 '@SCM_LIB.SCM(SCH_1):PAGE25_I149@PURE_QUANTA.Q_RES(CHIPS)':
 'B': CDS_PINID='B';
NODE_NAME     U55 2
 '@SCM_LIB.SCM(SCH_1):PAGE25_I150@PURE_QUANTA.SN74LVC1G14DCKR(CHIPS)':
 'A': CDS_PINID='A';
NODE_NAME     J1 2
 '@SCM_LIB.SCM(SCH_1):PAGE25_I169@PURE_QUANTA.SCONN3_212H9103GBR1(CHIPS)':
 '2': CDS_PINID='\2\';
NODE_NAME     R556 2
 '@SCM_LIB.SCM(SCH_1):PAGE25_I175@PURE_QUANTA.Q_RES(CHIPS)':
 'B': CDS_PINID='B';
NODE_NAME     R559 2
 '@SCM_LIB.SCM(SCH_1):PAGE25_I176@PURE_QUANTA.Q_RES(CHIPS)':
 'B': CDS_PINID='B';
NET_NAME
'FLASH_R_WP_STATUS'
 '@SCM_LIB.SCM(SCH_1):FLASH_R_WP_STATUS':
 C_SIGNAL='@scm_lib.scm(sch_1):flash_r_wp_status';
NODE_NAME     U55 4
 '@SCM_LIB.SCM(SCH_1):PAGE25_I150@PURE_QUANTA.SN74LVC1G14DCKR(CHIPS)':
 'Y': CDS_PINID='Y';
NODE_NAME     R554 2
 '@SCM_LIB.SCM(SCH_1):PAGE25_I156@PURE_QUANTA.Q_RES(CHIPS)':
 'B': CDS_PINID='B';
NODE_NAME     R551 2
 '@SCM_LIB.SCM(SCH_1):PAGE25_I173@PURE_QUANTA.Q_RES(CHIPS)':
 'B': CDS_PINID='B';
NET_NAME
'FLASH_WP_STATUS'
 '@SCM_LIB.SCM(SCH_1):FLASH_WP_STATUS':
 C_SIGNAL='@scm_lib.scm(sch_1):flash_wp_status';
NODE_NAME     R466 2
 '@SCM_LIB.SCM(SCH_1):PAGE13_I431@PURE_QUANTA.Q_RES(CHIPS)':
 'B': CDS_PINID='B';
NODE_NAME     R551 1
 '@SCM_LIB.SCM(SCH_1):PAGE25_I173@PURE_QUANTA.Q_RES(CHIPS)':
 'A': CDS_PINID='A';
NET_NAME
'FLASH_WP_STATUS_R1'
 '@SCM_LIB.SCM(SCH_1):FLASH_WP_STATUS_R1':
 C_SIGNAL='@scm_lib.scm(sch_1):flash_wp_status_r1';
NODE_NAME     U5 E16
 '@SCM_LIB.SCM(SCH_1):PAGE13_I363@PURE_QUANTA.AST2600A3GP(CHIPS)':
 'GPIOI5||SIOPBO#': CDS_PINID='\gpioi5||siopbo#\';
NODE_NAME     R466 1
 '@SCM_LIB.SCM(SCH_1):PAGE13_I431@PURE_QUANTA.Q_RES(CHIPS)':
 'A': CDS_PINID='A';
NET_NAME
'FM_ADR_COMPLETE'
 '@SCM_LIB.SCM(SCH_1):FM_ADR_COMPLETE':
 C_SIGNAL='@scm_lib.scm(sch_1):fm_adr_complete';
NODE_NAME     U5 AC24
 '@SCM_LIB.SCM(SCH_1):PAGE15_I350@PURE_QUANTA.AST2600A3GP(CHIPS)':
 'GPIOO6||PWM6': CDS_PINID='\gpioo6||pwm6\';
NODE_NAME     U25 A12
 '@SCM_LIB.SCM(SCH_1):PAGE34_I1@PURE_QUANTA.LCMXO3LF2100C5BG256C(CHIPS)':
 'PT22B': CDS_PINID='PT22B';
NET_NAME
'FM_ADR_TRIGGER_N'
 '@SCM_LIB.SCM(SCH_1):FM_ADR_TRIGGER_N':
 C_SIGNAL='@scm_lib.scm(sch_1):fm_adr_trigger_n';
NODE_NAME     U5 AD25
 '@SCM_LIB.SCM(SCH_1):PAGE15_I350@PURE_QUANTA.AST2600A3GP(CHIPS)':
 'GPIOO4||PWM4': CDS_PINID='\gpioo4||pwm4\';
NODE_NAME     U25 J13
 '@SCM_LIB.SCM(SCH_1):PAGE35_I1@PURE_QUANTA.LCMXO3LF2100C5BG256C(CHIPS)':
 'PR9D': CDS_PINID='PR9D';
NODE_NAME     R835 2
 '@SCM_LIB.SCM(SCH_1):PAGE42_I63@PURE_QUANTA.Q_RES(CHIPS)':
 'B': CDS_PINID='B';
NET_NAME
'FM_BIC_DEBUG_SW_N'
 '@SCM_LIB.SCM(SCH_1):FM_BIC_DEBUG_SW_N':
 C_SIGNAL='@scm_lib.scm(sch_1):fm_bic_debug_sw_n';
NODE_NAME     U50 6
 '@SCM_LIB.SCM(SCH_1):PAGE31_I23@PURE_QUANTA.NC7SB3157(CHIPS)':
 'S': CDS_PINID='S';
NODE_NAME     U51 6
 '@SCM_LIB.SCM(SCH_1):PAGE31_I24@PURE_QUANTA.NC7SB3157(CHIPS)':
 'S': CDS_PINID='S';
NODE_NAME     R122 1
 '@SCM_LIB.SCM(SCH_1):PAGE13_I399@PURE_QUANTA.Q_RES(CHIPS)':
 'A': CDS_PINID='A';
NET_NAME
'FM_BIC_DEBUG_SW_N_R'
 '@SCM_LIB.SCM(SCH_1):FM_BIC_DEBUG_SW_N_R':
 C_SIGNAL='@scm_lib.scm(sch_1):fm_bic_debug_sw_n_r';
NODE_NAME     U5 F25
 '@SCM_LIB.SCM(SCH_1):PAGE13_I363@PURE_QUANTA.AST2600A3GP(CHIPS)':
 'RGMII3RXD2||RMII3CRSDV||GPIOD2': CDS_PINID='\rgmii3rxd2||rmii3crsdv||gpiod2\';
NODE_NAME     R122 2
 '@SCM_LIB.SCM(SCH_1):PAGE13_I399@PURE_QUANTA.Q_RES(CHIPS)':
 'B': CDS_PINID='B';
NET_NAME
'FM_BIOS_DEBUG_EN_N'
 '@SCM_LIB.SCM(SCH_1):FM_BIOS_DEBUG_EN_N':
 C_SIGNAL='@scm_lib.scm(sch_1):fm_bios_debug_en_n';
NODE_NAME     U25 K12
 '@SCM_LIB.SCM(SCH_1):PAGE35_I1@PURE_QUANTA.LCMXO3LF2100C5BG256C(CHIPS)':
 'PR11D': CDS_PINID='PR11D';
NODE_NAME     R112 2
 '@SCM_LIB.SCM(SCH_1):PAGE13_I427@PURE_QUANTA.Q_RES(CHIPS)':
 'B': CDS_PINID='B';
NET_NAME
'FM_BIOS_DEBUG_EN_R_N'
 '@SCM_LIB.SCM(SCH_1):FM_BIOS_DEBUG_EN_R_N':
 C_SIGNAL='@scm_lib.scm(sch_1):fm_bios_debug_en_r_n';
NODE_NAME     R56 2
 '@SCM_LIB.SCM(SCH_1):PAGE13_I279@PURE_QUANTA.Q_RES(CHIPS)':
 'B': CDS_PINID='B';
NODE_NAME     U5 D24
 '@SCM_LIB.SCM(SCH_1):PAGE13_I363@PURE_QUANTA.AST2600A3GP(CHIPS)':
 'RGMII4TXD3||NRTS3||GPIOE1': CDS_PINID='\rgmii4txd3||nrts3||gpioe1\';
NODE_NAME     R112 1
 '@SCM_LIB.SCM(SCH_1):PAGE13_I427@PURE_QUANTA.Q_RES(CHIPS)':
 'A': CDS_PINID='A';
NET_NAME
'FM_BIOS_POST_CMPLT_BMC_N'
 '@SCM_LIB.SCM(SCH_1):FM_BIOS_POST_CMPLT_BMC_N':
 C_SIGNAL='@scm_lib.scm(sch_1):fm_bios_post_cmplt_bmc_n';
NODE_NAME     U5 U26
 '@SCM_LIB.SCM(SCH_1):PAGE15_I350@PURE_QUANTA.AST2600A3GP(CHIPS)':
 'GPIOR7||TACH15': CDS_PINID='\gpior7||tach15\';
NODE_NAME     U25 E8
 '@SCM_LIB.SCM(SCH_1):PAGE34_I1@PURE_QUANTA.LCMXO3LF2100C5BG256C(CHIPS)':
 'PT16B': CDS_PINID='PT16B';
NET_NAME
'FM_BMC_BIOS_MUX_CS_SPI_R_SEL_0'
 '@SCM_LIB.SCM(SCH_1):FM_BMC_BIOS_MUX_CS_SPI_R_SEL_0':
 C_SIGNAL='@scm_lib.scm(sch_1):fm_bmc_bios_mux_cs_spi_r_sel_0';
NODE_NAME     U30 1
 '@SCM_LIB.SCM(SCH_1):PAGE44_I271@PURE_QUANTA.IDTQS3VH257PAG(CHIPS)':
 'S': CDS_PINID='S';
NODE_NAME     U21 1
 '@SCM_LIB.SCM(SCH_1):PAGE44_I296@PURE_QUANTA.IDTQS3VH257PAG(CHIPS)':
 'S': CDS_PINID='S';
NODE_NAME     R866 1
 '@SCM_LIB.SCM(SCH_1):PAGE44_I311@PURE_QUANTA.Q_RES(CHIPS)':
 'A': CDS_PINID='A';
NODE_NAME     R852 2
 '@SCM_LIB.SCM(SCH_1):PAGE44_I366@PURE_QUANTA.Q_RES(CHIPS)':
 'B': CDS_PINID='B';
NET_NAME
'FM_BMC_CPU_FBRK_OUT_N'
 '@SCM_LIB.SCM(SCH_1):FM_BMC_CPU_FBRK_OUT_N':
 C_SIGNAL='@scm_lib.scm(sch_1):fm_bmc_cpu_fbrk_out_n';
NODE_NAME     U5 H22
 '@SCM_LIB.SCM(SCH_1):PAGE13_I363@PURE_QUANTA.AST2600A3GP(CHIPS)':
 'RGMII3TXD0||RMII3TXD0||GPIOC2': CDS_PINID='\rgmii3txd0||rmii3txd0||gpioc2\';
NODE_NAME     R242 1
 '@SCM_LIB.SCM(SCH_1):PAGE13_I384@PURE_QUANTA.Q_RES(CHIPS)':
 'A': CDS_PINID='A';
NET_NAME
'FM_BMC_CPU_FBRK_OUT_R_N'
 '@SCM_LIB.SCM(SCH_1):FM_BMC_CPU_FBRK_OUT_R_N':
 C_SIGNAL='@scm_lib.scm(sch_1):fm_bmc_cpu_fbrk_out_r_n';
NODE_NAME     U25 L9
 '@SCM_LIB.SCM(SCH_1):PAGE36_I1@PURE_QUANTA.LCMXO3LF2100C5BG256C(CHIPS)':
 'PB12D': CDS_PINID='PB12D';
NODE_NAME     R242 2
 '@SCM_LIB.SCM(SCH_1):PAGE13_I384@PURE_QUANTA.Q_RES(CHIPS)':
 'B': CDS_PINID='B';
NET_NAME
'FM_BMC_CRASHLOG_TRIG_N'
 '@SCM_LIB.SCM(SCH_1):FM_BMC_CRASHLOG_TRIG_N':
 C_SIGNAL='@scm_lib.scm(sch_1):fm_bmc_crashlog_trig_n';
NODE_NAME     R747 1
 '@SCM_LIB.SCM(SCH_1):PAGE36_I9@PURE_QUANTA.Q_RES(CHIPS)':
 'A': CDS_PINID='A';
NODE_NAME     R749 2
 '@SCM_LIB.SCM(SCH_1):PAGE42_I61@PURE_QUANTA.Q_RES(CHIPS)':
 'B': CDS_PINID='B';
NODE_NAME     R760 1
 '@SCM_LIB.SCM(SCH_1):PAGE13_I400@PURE_QUANTA.Q_RES(CHIPS)':
 'A': CDS_PINID='A';
NET_NAME
'FM_BMC_CRASHLOG_TRIG_R1_N'
 '@SCM_LIB.SCM(SCH_1):FM_BMC_CRASHLOG_TRIG_R1_N':
 C_SIGNAL='@scm_lib.scm(sch_1):fm_bmc_crashlog_trig_r1_n';
NODE_NAME     U5 E26
 '@SCM_LIB.SCM(SCH_1):PAGE13_I363@PURE_QUANTA.AST2600A3GP(CHIPS)':
 'RGMII3RXD3||RMII3RXER||GPIOD3': CDS_PINID='\rgmii3rxd3||rmii3rxer||gpiod3\';
NODE_NAME     R760 2
 '@SCM_LIB.SCM(SCH_1):PAGE13_I400@PURE_QUANTA.Q_RES(CHIPS)':
 'B': CDS_PINID='B';
NET_NAME
'FM_BMC_CRASHLOG_TRIG_R2_N'
 '@SCM_LIB.SCM(SCH_1):FM_BMC_CRASHLOG_TRIG_R2_N':
 C_SIGNAL='@scm_lib.scm(sch_1):fm_bmc_crashlog_trig_r2_n';
NODE_NAME     U25 R6
 '@SCM_LIB.SCM(SCH_1):PAGE36_I1@PURE_QUANTA.LCMXO3LF2100C5BG256C(CHIPS)':
 'PB6B': CDS_PINID='PB6B';
NODE_NAME     R747 2
 '@SCM_LIB.SCM(SCH_1):PAGE36_I9@PURE_QUANTA.Q_RES(CHIPS)':
 'B': CDS_PINID='B';
NET_NAME
'FM_BMC_DBP_PRESENT_N'
 '@SCM_LIB.SCM(SCH_1):FM_BMC_DBP_PRESENT_N':
 C_SIGNAL='@scm_lib.scm(sch_1):fm_bmc_dbp_present_n';
NODE_NAME     R705 1
 '@SCM_LIB.SCM(SCH_1):PAGE12_I353@PURE_QUANTA.Q_RES(CHIPS)':
 'A': CDS_PINID='A';
NODE_NAME     R706 2
 '@SCM_LIB.SCM(SCH_1):PAGE12_I354@PURE_QUANTA.Q_RES(CHIPS)':
 'B': CDS_PINID='B';
NODE_NAME     U25 D6
 '@SCM_LIB.SCM(SCH_1):PAGE34_I1@PURE_QUANTA.LCMXO3LF2100C5BG256C(CHIPS)':
 'PT12A': CDS_PINID='PT12A';
NET_NAME
'FM_BMC_DBP_PRESENT_R_N'
 '@SCM_LIB.SCM(SCH_1):FM_BMC_DBP_PRESENT_R_N':
 C_SIGNAL='@scm_lib.scm(sch_1):fm_bmc_dbp_present_r_n';
NODE_NAME     R705 2
 '@SCM_LIB.SCM(SCH_1):PAGE12_I353@PURE_QUANTA.Q_RES(CHIPS)':
 'B': CDS_PINID='B';
NODE_NAME     U5 B21
 '@SCM_LIB.SCM(SCH_1):PAGE12_I436@PURE_QUANTA.AST2600A3GP(CHIPS)':
 'GPIOG7||RXD9||SD2WP#||SALT16': CDS_PINID='\gpiog7||rxd9||sd2wp#||salt16\';
NET_NAME
'FM_BMC_DEBUG_SW_N'
 '@SCM_LIB.SCM(SCH_1):FM_BMC_DEBUG_SW_N':
 C_SIGNAL='@scm_lib.scm(sch_1):fm_bmc_debug_sw_n';
NODE_NAME     U5 R26
 '@SCM_LIB.SCM(SCH_1):PAGE13_I363@PURE_QUANTA.AST2600A3GP(CHIPS)':
 'GPIOS4||TXD10': CDS_PINID='\gpios4||txd10\';
NODE_NAME     R624 2
 '@SCM_LIB.SCM(SCH_1):PAGE48_I48@PURE_QUANTA.Q_RES(CHIPS)':
 'B': CDS_PINID='B';
NODE_NAME     R506 1
 '@SCM_LIB.SCM(SCH_1):PAGE48_I53@PURE_QUANTA.Q_RES(CHIPS)':
 'A': CDS_PINID='A';
NODE_NAME     R750 1
 '@SCM_LIB.SCM(SCH_1):PAGE36_I82@PURE_QUANTA.Q_RES(CHIPS)':
 'A': CDS_PINID='A';
NET_NAME
'FM_BMC_DEBUG_SW_R2_N'
 '@SCM_LIB.SCM(SCH_1):FM_BMC_DEBUG_SW_R2_N':
 C_SIGNAL='@scm_lib.scm(sch_1):fm_bmc_debug_sw_r2_n';
NODE_NAME     U25 N6
 '@SCM_LIB.SCM(SCH_1):PAGE36_I1@PURE_QUANTA.LCMXO3LF2100C5BG256C(CHIPS)':
 'PB8C': CDS_PINID='PB8C';
NODE_NAME     R750 2
 '@SCM_LIB.SCM(SCH_1):PAGE36_I82@PURE_QUANTA.Q_RES(CHIPS)':
 'B': CDS_PINID='B';
NET_NAME
'FM_BMC_DISABLE'
 '@SCM_LIB.SCM(SCH_1):FM_BMC_DISABLE':
 C_SIGNAL='@scm_lib.scm(sch_1):fm_bmc_disable';
NODE_NAME     U11 3
 '@SCM_LIB.SCM(SCH_1):PAGE27_I185@PURE_QUANTA.BAT54C(CHIPS)':
 'C': CDS_PINID='C';
NODE_NAME     R615 2
 '@SCM_LIB.SCM(SCH_1):PAGE48_I33@PURE_QUANTA.Q_RES(CHIPS)':
 'B': CDS_PINID='B';
NODE_NAME     R431 1
 '@SCM_LIB.SCM(SCH_1):PAGE48_I56@PURE_QUANTA.Q_RES(CHIPS)':
 'A': CDS_PINID='A';
NET_NAME
'FM_BMC_EN_DET_R'
 '@SCM_LIB.SCM(SCH_1):FM_BMC_EN_DET_R':
 C_SIGNAL='@scm_lib.scm(sch_1):fm_bmc_en_det_r';
NODE_NAME     U5 AA16
 '@SCM_LIB.SCM(SCH_1):PAGE15_I350@PURE_QUANTA.AST2600A3GP(CHIPS)':
 'ADC13||GPIU5||SALT14': CDS_PINID='\adc13||gpiu5||salt14\';
NODE_NAME     R846 2
 '@SCM_LIB.SCM(SCH_1):PAGE27_I181@PURE_QUANTA.Q_RES(CHIPS)':
 'B': CDS_PINID='B';
NODE_NAME     U25 L12
 '@SCM_LIB.SCM(SCH_1):PAGE35_I1@PURE_QUANTA.LCMXO3LF2100C5BG256C(CHIPS)':
 'PR10D': CDS_PINID='PR10D';
NET_NAME
'FM_BMC_MUX_CS_SPI_SEL_0'
 '@SCM_LIB.SCM(SCH_1):FM_BMC_MUX_CS_SPI_SEL_0':
 C_SIGNAL='@scm_lib.scm(sch_1):fm_bmc_mux_cs_spi_sel_0';
NODE_NAME     U5 J23
 '@SCM_LIB.SCM(SCH_1):PAGE13_I363@PURE_QUANTA.AST2600A3GP(CHIPS)':
 'GPIOB4||MDC2': CDS_PINID='\gpiob4||mdc2\';
NODE_NAME     R852 1
 '@SCM_LIB.SCM(SCH_1):PAGE44_I366@PURE_QUANTA.Q_RES(CHIPS)':
 'A': CDS_PINID='A';
NET_NAME
'FM_BMC_ONCTL_R_N'
 '@SCM_LIB.SCM(SCH_1):FM_BMC_ONCTL_R_N':
 C_SIGNAL='@scm_lib.scm(sch_1):fm_bmc_onctl_r_n';
NODE_NAME     R821 2
 '@SCM_LIB.SCM(SCH_1):PAGE13_I220@PURE_QUANTA.Q_RES(CHIPS)':
 'B': CDS_PINID='B';
NODE_NAME     U5 AC15
 '@SCM_LIB.SCM(SCH_1):PAGE13_I363@PURE_QUANTA.AST2600A3GP(CHIPS)':
 'GPIOV3||SIOONCTRL#': CDS_PINID='\gpiov3||sioonctrl#\';
NODE_NAME     U11 1
 '@SCM_LIB.SCM(SCH_1):PAGE27_I185@PURE_QUANTA.BAT54C(CHIPS)':
 'B': CDS_PINID='B';
NODE_NAME     R430 2
 '@SCM_LIB.SCM(SCH_1):PAGE27_I188@PURE_QUANTA.Q_RES(CHIPS)':
 'B': CDS_PINID='B';
NODE_NAME     U25 L13
 '@SCM_LIB.SCM(SCH_1):PAGE35_I1@PURE_QUANTA.LCMXO3LF2100C5BG256C(CHIPS)':
 'PR12D': CDS_PINID='PR12D';
NET_NAME
'FM_BMC_READY_PLD_N'
 '@SCM_LIB.SCM(SCH_1):FM_BMC_READY_PLD_N':
 C_SIGNAL='@scm_lib.scm(sch_1):fm_bmc_ready_pld_n';
NODE_NAME     R111 2
 '@SCM_LIB.SCM(SCH_1):PAGE13_I266@PURE_QUANTA.Q_RES(CHIPS)':
 'B': CDS_PINID='B';
NODE_NAME     U25 K13
 '@SCM_LIB.SCM(SCH_1):PAGE35_I1@PURE_QUANTA.LCMXO3LF2100C5BG256C(CHIPS)':
 'PR11C': CDS_PINID='PR11C';
NET_NAME
'FM_BMC_READY_R_PLD_N'
 '@SCM_LIB.SCM(SCH_1):FM_BMC_READY_R_PLD_N':
 C_SIGNAL='@scm_lib.scm(sch_1):fm_bmc_ready_r_pld_n';
NODE_NAME     R111 1
 '@SCM_LIB.SCM(SCH_1):PAGE13_I266@PURE_QUANTA.Q_RES(CHIPS)':
 'A': CDS_PINID='A';
NODE_NAME     R55 2
 '@SCM_LIB.SCM(SCH_1):PAGE13_I278@PURE_QUANTA.Q_RES(CHIPS)':
 'B': CDS_PINID='B';
NODE_NAME     U5 AE14
 '@SCM_LIB.SCM(SCH_1):PAGE13_I363@PURE_QUANTA.AST2600A3GP(CHIPS)':
 'GPIOV5||LPCPD#': CDS_PINID='\gpiov5||lpcpd#\';
NET_NAME
'FM_BMC_SSPRST_N'
 '@SCM_LIB.SCM(SCH_1):FM_BMC_SSPRST_N':
 C_SIGNAL='@scm_lib.scm(sch_1):fm_bmc_ssprst_n';
NODE_NAME     R211 2
 '@SCM_LIB.SCM(SCH_1):PAGE15_I51@PURE_QUANTA.Q_RES(CHIPS)':
 'B': CDS_PINID='B';
NODE_NAME     U5 D7
 '@SCM_LIB.SCM(SCH_1):PAGE15_I350@PURE_QUANTA.AST2600A3GP(CHIPS)':
 'SSPRST#': CDS_PINID='\ssprst#\';
NET_NAME
'FM_BMC_SUSACK_N'
 '@SCM_LIB.SCM(SCH_1):FM_BMC_SUSACK_N':
 C_SIGNAL='@scm_lib.scm(sch_1):fm_bmc_susack_n';
NODE_NAME     R38 2
 '@SCM_LIB.SCM(SCH_1):PAGE13_I200@PURE_QUANTA.Q_RES(CHIPS)':
 'B': CDS_PINID='B';
NODE_NAME     R407 2
 '@SCM_LIB.SCM(SCH_1):PAGE13_I349@PURE_QUANTA.Q_RES(CHIPS)':
 'B': CDS_PINID='B';
NODE_NAME     R445 1
 '@SCM_LIB.SCM(SCH_1):PAGE36_I81@PURE_QUANTA.Q_RES(CHIPS)':
 'A': CDS_PINID='A';
NET_NAME
'FM_BMC_SUSACK_R1_N'
 '@SCM_LIB.SCM(SCH_1):FM_BMC_SUSACK_R1_N':
 C_SIGNAL='@scm_lib.scm(sch_1):fm_bmc_susack_r1_n';
NODE_NAME     R407 1
 '@SCM_LIB.SCM(SCH_1):PAGE13_I349@PURE_QUANTA.Q_RES(CHIPS)':
 'A': CDS_PINID='A';
NODE_NAME     U5 AD15
 '@SCM_LIB.SCM(SCH_1):PAGE13_I363@PURE_QUANTA.AST2600A3GP(CHIPS)':
 'GPIOV6||LPCPME#': CDS_PINID='\gpiov6||lpcpme#\';
NET_NAME
'FM_BMC_SUSACK_R2_N'
 '@SCM_LIB.SCM(SCH_1):FM_BMC_SUSACK_R2_N':
 C_SIGNAL='@scm_lib.scm(sch_1):fm_bmc_susack_r2_n';
NODE_NAME     U25 R4
 '@SCM_LIB.SCM(SCH_1):PAGE36_I1@PURE_QUANTA.LCMXO3LF2100C5BG256C(CHIPS)':
 'PB6D': CDS_PINID='PB6D';
NODE_NAME     R445 2
 '@SCM_LIB.SCM(SCH_1):PAGE36_I81@PURE_QUANTA.Q_RES(CHIPS)':
 'B': CDS_PINID='B';
NET_NAME
'FM_BMC_UARTSW_LSB_N'
 '@SCM_LIB.SCM(SCH_1):FM_BMC_UARTSW_LSB_N':
 C_SIGNAL='@scm_lib.scm(sch_1):fm_bmc_uartsw_lsb_n';
NODE_NAME     GF1 A55
 '@SCM_LIB.SCM(SCH_1):PAGE10_I553@PURE_QUANTA.FCONN168_ME1016810202011_SCM(CHIPS)':
 'SPARE0': CDS_PINID='SPARE0';
NODE_NAME     R134 1
 '@SCM_LIB.SCM(SCH_1):PAGE36_I47@PURE_QUANTA.Q_RES(CHIPS)':
 'A': CDS_PINID='A';
NET_NAME
'FM_BMC_UARTSW_MSB_N'
 '@SCM_LIB.SCM(SCH_1):FM_BMC_UARTSW_MSB_N':
 C_SIGNAL='@scm_lib.scm(sch_1):fm_bmc_uartsw_msb_n';
NODE_NAME     GF1 A52
 '@SCM_LIB.SCM(SCH_1):PAGE10_I553@PURE_QUANTA.FCONN168_ME1016810202011_SCM(CHIPS)':
 'SPARE1': CDS_PINID='SPARE1';
NODE_NAME     R220 1
 '@SCM_LIB.SCM(SCH_1):PAGE36_I46@PURE_QUANTA.Q_RES(CHIPS)':
 'A': CDS_PINID='A';
NET_NAME
'FM_BOARD_BMC_REV_ID0'
 '@SCM_LIB.SCM(SCH_1):FM_BOARD_BMC_REV_ID0':
 C_SIGNAL='@scm_lib.scm(sch_1):fm_board_bmc_rev_id0';
NODE_NAME     U5 D3
 '@SCM_LIB.SCM(SCH_1):PAGE14_I149@PURE_QUANTA.AST2600A3GP(CHIPS)':
 'RGMII2TXD1||RMII2TXD1||GPIO18B7': CDS_PINID='\rgmii2txd1||rmii2txd1||gpio18b7\';
NODE_NAME     R858 2
 '@SCM_LIB.SCM(SCH_1):PAGE14_I222@PURE_QUANTA.Q_RES(CHIPS)':
 'B': CDS_PINID='B';
NODE_NAME     R865 1
 '@SCM_LIB.SCM(SCH_1):PAGE14_I225@PURE_QUANTA.Q_RES(CHIPS)':
 'A': CDS_PINID='A';
NET_NAME
'FM_BOARD_BMC_REV_ID1'
 '@SCM_LIB.SCM(SCH_1):FM_BOARD_BMC_REV_ID1':
 C_SIGNAL='@scm_lib.scm(sch_1):fm_board_bmc_rev_id1';
NODE_NAME     U5 E4
 '@SCM_LIB.SCM(SCH_1):PAGE14_I149@PURE_QUANTA.AST2600A3GP(CHIPS)':
 'RGMII2TXD2||GPIO18C0': CDS_PINID='\rgmii2txd2||gpio18c0\';
NODE_NAME     R856 2
 '@SCM_LIB.SCM(SCH_1):PAGE14_I220@PURE_QUANTA.Q_RES(CHIPS)':
 'B': CDS_PINID='B';
NODE_NAME     R857 1
 '@SCM_LIB.SCM(SCH_1):PAGE14_I224@PURE_QUANTA.Q_RES(CHIPS)':
 'A': CDS_PINID='A';
NET_NAME
'FM_BOARD_BMC_REV_ID2'
 '@SCM_LIB.SCM(SCH_1):FM_BOARD_BMC_REV_ID2':
 C_SIGNAL='@scm_lib.scm(sch_1):fm_board_bmc_rev_id2';
NODE_NAME     U5 F5
 '@SCM_LIB.SCM(SCH_1):PAGE14_I149@PURE_QUANTA.AST2600A3GP(CHIPS)':
 'RGMII2TXD3||GPIO18C1': CDS_PINID='\rgmii2txd3||gpio18c1\';
NODE_NAME     R854 2
 '@SCM_LIB.SCM(SCH_1):PAGE14_I221@PURE_QUANTA.Q_RES(CHIPS)':
 'B': CDS_PINID='B';
NODE_NAME     R855 1
 '@SCM_LIB.SCM(SCH_1):PAGE14_I223@PURE_QUANTA.Q_RES(CHIPS)':
 'A': CDS_PINID='A';
NET_NAME
'FM_CPU_MSMI_CATERR_LVT3_N'
 '@SCM_LIB.SCM(SCH_1):FM_CPU_MSMI_CATERR_LVT3_N':
 C_SIGNAL='@scm_lib.scm(sch_1):fm_cpu_msmi_caterr_lvt3_n';
NODE_NAME     R163 2
 '@SCM_LIB.SCM(SCH_1):PAGE11_I212@PURE_QUANTA.Q_RES(CHIPS)':
 'B': CDS_PINID='B';
NODE_NAME     R720 1
 '@SCM_LIB.SCM(SCH_1):PAGE28_I144@PURE_QUANTA.Q_RES(CHIPS)':
 'A': CDS_PINID='A';
NODE_NAME     R121 2
 '@SCM_LIB.SCM(SCH_1):PAGE13_I381@PURE_QUANTA.Q_RES(CHIPS)':
 'B': CDS_PINID='B';
NODE_NAME     R270 2
 '@SCM_LIB.SCM(SCH_1):PAGE34_I164@PURE_QUANTA.Q_RES(CHIPS)':
 'B': CDS_PINID='B';
NET_NAME
'FM_CPU_MSMI_CATERR_LVT3_PLD_N'
 '@SCM_LIB.SCM(SCH_1):FM_CPU_MSMI_CATERR_LVT3_PLD_N':
 C_SIGNAL='@scm_lib.scm(sch_1):fm_cpu_msmi_caterr_lvt3_pld_n';
NODE_NAME     U25 E10
 '@SCM_LIB.SCM(SCH_1):PAGE34_I1@PURE_QUANTA.LCMXO3LF2100C5BG256C(CHIPS)':
 'PT20B': CDS_PINID='PT20B';
NODE_NAME     R270 1
 '@SCM_LIB.SCM(SCH_1):PAGE34_I164@PURE_QUANTA.Q_RES(CHIPS)':
 'A': CDS_PINID='A';
NET_NAME
'FM_CPU_MSMI_CATERR_LVT3_R3_N'
 '@SCM_LIB.SCM(SCH_1):FM_CPU_MSMI_CATERR_LVT3_R3_N':
 C_SIGNAL='@scm_lib.scm(sch_1):fm_cpu_msmi_caterr_lvt3_r3_n';
NODE_NAME     U40 18
 '@SCM_LIB.SCM(SCH_1):PAGE28_I141@PURE_QUANTA.PCA9555PW(CHIPS)':
 'P15': CDS_PINID='P15';
NODE_NAME     R720 2
 '@SCM_LIB.SCM(SCH_1):PAGE28_I144@PURE_QUANTA.Q_RES(CHIPS)':
 'B': CDS_PINID='B';
NET_NAME
'FM_CPU_RMCA_CATERR_LVT3_R_N'
 '@SCM_LIB.SCM(SCH_1):FM_CPU_RMCA_CATERR_LVT3_R_N':
 C_SIGNAL='@scm_lib.scm(sch_1):fm_cpu_rmca_caterr_lvt3_r_n';
NODE_NAME     U5 J22
 '@SCM_LIB.SCM(SCH_1):PAGE13_I363@PURE_QUANTA.AST2600A3GP(CHIPS)':
 'RGMII3TXCTL||RMII3TXEN||GPIOC1': CDS_PINID='\rgmii3txctl||rmii3txen||gpioc1\';
NODE_NAME     R121 1
 '@SCM_LIB.SCM(SCH_1):PAGE13_I381@PURE_QUANTA.Q_RES(CHIPS)':
 'A': CDS_PINID='A';
NET_NAME
'FM_DBG_SW_N'
 '@SCM_LIB.SCM(SCH_1):FM_DBG_SW_N':
 C_SIGNAL='@scm_lib.scm(sch_1):fm_dbg_sw_n';
NODE_NAME     U7 6
 '@SCM_LIB.SCM(SCH_1):PAGE31_I27@PURE_QUANTA.NC7SB3157(CHIPS)':
 'S': CDS_PINID='S';
NODE_NAME     U20 6
 '@SCM_LIB.SCM(SCH_1):PAGE31_I38@PURE_QUANTA.NC7SB3157(CHIPS)':
 'S': CDS_PINID='S';
NODE_NAME     J13 2
 '@SCM_LIB.SCM(SCH_1):PAGE31_I61@PURE_QUANTA.SCONN3_212H9103GBR1(CHIPS)':
 '2': CDS_PINID='\2\';
NODE_NAME     R629 2
 '@SCM_LIB.SCM(SCH_1):PAGE31_I78@PURE_QUANTA.Q_RES(CHIPS)':
 'B': CDS_PINID='B';
NET_NAME
'FM_DBP_BMC_PRDY_N'
 '@SCM_LIB.SCM(SCH_1):FM_DBP_BMC_PRDY_N':
 C_SIGNAL='@scm_lib.scm(sch_1):fm_dbp_bmc_prdy_n';
NODE_NAME     GF1 A50
 '@SCM_LIB.SCM(SCH_1):PAGE10_I553@PURE_QUANTA.FCONN168_ME1016810202011_SCM(CHIPS)':
 'DBP_PRDY_N': CDS_PINID='DBP_PRDY_N';
NODE_NAME     R237 1
 '@SCM_LIB.SCM(SCH_1):PAGE13_I156@PURE_QUANTA.Q_RES(CHIPS)':
 'A': CDS_PINID='A';
NET_NAME
'FM_DBP_BMC_PRDY_R_N'
 '@SCM_LIB.SCM(SCH_1):FM_DBP_BMC_PRDY_R_N':
 C_SIGNAL='@scm_lib.scm(sch_1):fm_dbp_bmc_prdy_r_n';
NODE_NAME     R237 2
 '@SCM_LIB.SCM(SCH_1):PAGE13_I156@PURE_QUANTA.Q_RES(CHIPS)':
 'B': CDS_PINID='B';
NODE_NAME     U5 C12
 '@SCM_LIB.SCM(SCH_1):PAGE13_I363@PURE_QUANTA.AST2600A3GP(CHIPS)':
 'GPIOM5||NRTS1': CDS_PINID='\gpiom5||nrts1\';
NET_NAME
'FM_DBP_CPU_PREQ_GF_N'
 '@SCM_LIB.SCM(SCH_1):FM_DBP_CPU_PREQ_GF_N':
 C_SIGNAL='@scm_lib.scm(sch_1):fm_dbp_cpu_preq_gf_n';
NODE_NAME     R158 2
 '@SCM_LIB.SCM(SCH_1):PAGE13_I16@PURE_QUANTA.Q_RES(CHIPS)':
 'B': CDS_PINID='B';
NODE_NAME     U5 C15
 '@SCM_LIB.SCM(SCH_1):PAGE13_I363@PURE_QUANTA.AST2600A3GP(CHIPS)':
 'GPIOL4||TXD3': CDS_PINID='\gpiol4||txd3\';
NET_NAME
'FM_DBP_CPU_PREQ_GF_R_N'
 '@SCM_LIB.SCM(SCH_1):FM_DBP_CPU_PREQ_GF_R_N':
 C_SIGNAL='@scm_lib.scm(sch_1):fm_dbp_cpu_preq_gf_r_n';
NODE_NAME     GF1 A49
 '@SCM_LIB.SCM(SCH_1):PAGE10_I553@PURE_QUANTA.FCONN168_ME1016810202011_SCM(CHIPS)':
 'DBP_PREQ_N': CDS_PINID='DBP_PREQ_N';
NODE_NAME     R158 1
 '@SCM_LIB.SCM(SCH_1):PAGE13_I16@PURE_QUANTA.Q_RES(CHIPS)':
 'A': CDS_PINID='A';
NET_NAME
'FM_DEBUG_PORT_PRSNT_N'
 '@SCM_LIB.SCM(SCH_1):FM_DEBUG_PORT_PRSNT_N':
 C_SIGNAL='@scm_lib.scm(sch_1):fm_debug_port_prsnt_n';
NODE_NAME     R707 2
 '@SCM_LIB.SCM(SCH_1):PAGE29_I201@PURE_QUANTA.Q_RES(CHIPS)':
 'B': CDS_PINID='B';
NODE_NAME     R579 1
 '@SCM_LIB.SCM(SCH_1):PAGE36_I7@PURE_QUANTA.Q_RES(CHIPS)':
 'A': CDS_PINID='A';
NODE_NAME     R458 2
 '@SCM_LIB.SCM(SCH_1):PAGE13_I407@PURE_QUANTA.Q_RES(CHIPS)':
 'B': CDS_PINID='B';
NET_NAME
'FM_DEBUG_PORT_PRSNT_R1_N'
 '@SCM_LIB.SCM(SCH_1):FM_DEBUG_PORT_PRSNT_R1_N':
 C_SIGNAL='@scm_lib.scm(sch_1):fm_debug_port_prsnt_r1_n';
NODE_NAME     U5 AD11
 '@SCM_LIB.SCM(SCH_1):PAGE13_I363@PURE_QUANTA.AST2600A3GP(CHIPS)':
 'GPIOZ6||SPI1DQ2||TXD13': CDS_PINID='\gpioz6||spi1dq2||txd13\';
NODE_NAME     R458 1
 '@SCM_LIB.SCM(SCH_1):PAGE13_I407@PURE_QUANTA.Q_RES(CHIPS)':
 'A': CDS_PINID='A';
NET_NAME
'FM_DEBUG_PORT_R2_PRSNT_N'
 '@SCM_LIB.SCM(SCH_1):FM_DEBUG_PORT_R2_PRSNT_N':
 C_SIGNAL='@scm_lib.scm(sch_1):fm_debug_port_r2_prsnt_n';
NODE_NAME     U25 R5
 '@SCM_LIB.SCM(SCH_1):PAGE36_I1@PURE_QUANTA.LCMXO3LF2100C5BG256C(CHIPS)':
 'PB5A||CSSPIN': CDS_PINID='\pb5a||csspin\';
NODE_NAME     R579 2
 '@SCM_LIB.SCM(SCH_1):PAGE36_I7@PURE_QUANTA.Q_RES(CHIPS)':
 'B': CDS_PINID='B';
NET_NAME
'FM_DEBUG_PORT_R_PRSNT_N'
 '@SCM_LIB.SCM(SCH_1):FM_DEBUG_PORT_R_PRSNT_N':
 C_SIGNAL='@scm_lib.scm(sch_1):fm_debug_port_r_prsnt_n';
NODE_NAME     R707 1
 '@SCM_LIB.SCM(SCH_1):PAGE29_I201@PURE_QUANTA.Q_RES(CHIPS)':
 'A': CDS_PINID='A';
NODE_NAME     Q6 D
 '@SCM_LIB.SCM(SCH_1):PAGE29_I202@PURE_QUANTA.2N7002A7(CHIPS)':
 'D': CDS_PINID='D';
NODE_NAME     R730 2
 '@SCM_LIB.SCM(SCH_1):PAGE29_I204@PURE_QUANTA.Q_RES(CHIPS)':
 'B': CDS_PINID='B';
NET_NAME
'FM_DEBUG_PWR_BTN_N'
 '@SCM_LIB.SCM(SCH_1):FM_DEBUG_PWR_BTN_N':
 C_SIGNAL='@scm_lib.scm(sch_1):fm_debug_pwr_btn_n';
NODE_NAME     U40 14
 '@SCM_LIB.SCM(SCH_1):PAGE28_I141@PURE_QUANTA.PCA9555PW(CHIPS)':
 'P11': CDS_PINID='P11';
NODE_NAME     R734 2
 '@SCM_LIB.SCM(SCH_1):PAGE50_I152@PURE_QUANTA.Q_RES(CHIPS)':
 'B': CDS_PINID='B';
NET_NAME
'FM_DEBUG_RST_BTN_N'
 '@SCM_LIB.SCM(SCH_1):FM_DEBUG_RST_BTN_N':
 C_SIGNAL='@scm_lib.scm(sch_1):fm_debug_rst_btn_n';
NODE_NAME     U40 13
 '@SCM_LIB.SCM(SCH_1):PAGE28_I141@PURE_QUANTA.PCA9555PW(CHIPS)':
 'P10': CDS_PINID='P10';
NODE_NAME     R733 2
 '@SCM_LIB.SCM(SCH_1):PAGE50_I154@PURE_QUANTA.Q_RES(CHIPS)':
 'B': CDS_PINID='B';
NET_NAME
'FM_ESPI_PLD_EN'
 '@SCM_LIB.SCM(SCH_1):FM_ESPI_PLD_EN':
 C_SIGNAL='@scm_lib.scm(sch_1):fm_espi_pld_en';
NODE_NAME     R444 1
 '@SCM_LIB.SCM(SCH_1):PAGE13_I306@PURE_QUANTA.Q_RES(CHIPS)':
 'A': CDS_PINID='A';
NODE_NAME     R833 1
 '@SCM_LIB.SCM(SCH_1):PAGE35_I139@PURE_QUANTA.Q_RES(CHIPS)':
 'A': CDS_PINID='A';
NET_NAME
'FM_ESPI_PLD_R1_EN'
 '@SCM_LIB.SCM(SCH_1):FM_ESPI_PLD_R1_EN':
 C_SIGNAL='@scm_lib.scm(sch_1):fm_espi_pld_r1_en';
NODE_NAME     R444 2
 '@SCM_LIB.SCM(SCH_1):PAGE13_I306@PURE_QUANTA.Q_RES(CHIPS)':
 'B': CDS_PINID='B';
NODE_NAME     U5 H25
 '@SCM_LIB.SCM(SCH_1):PAGE13_I363@PURE_QUANTA.AST2600A3GP(CHIPS)':
 'GPIOB6||TXD4': CDS_PINID='\gpiob6||txd4\';
NET_NAME
'FM_ESPI_PLD_R_EN'
 '@SCM_LIB.SCM(SCH_1):FM_ESPI_PLD_R_EN':
 C_SIGNAL='@scm_lib.scm(sch_1):fm_espi_pld_r_en';
NODE_NAME     U25 H13
 '@SCM_LIB.SCM(SCH_1):PAGE35_I1@PURE_QUANTA.LCMXO3LF2100C5BG256C(CHIPS)':
 'PR6C': CDS_PINID='PR6C';
NODE_NAME     R833 2
 '@SCM_LIB.SCM(SCH_1):PAGE35_I139@PURE_QUANTA.Q_RES(CHIPS)':
 'B': CDS_PINID='B';
NET_NAME
'FM_FLASH_LATCH_N'
 '@SCM_LIB.SCM(SCH_1):FM_FLASH_LATCH_N':
 C_SIGNAL='@scm_lib.scm(sch_1):fm_flash_latch_n';
NODE_NAME     U54 7
 '@SCM_LIB.SCM(SCH_1):PAGE25_I138@PURE_QUANTA.74LVC1G74DP(CHIPS)':
 'SD_N': CDS_PINID='SD_N';
NODE_NAME     R465 2
 '@SCM_LIB.SCM(SCH_1):PAGE13_I432@PURE_QUANTA.Q_RES(CHIPS)':
 'B': CDS_PINID='B';
NODE_NAME     R181 2
 '@SCM_LIB.SCM(SCH_1):PAGE25_I170@PURE_QUANTA.Q_RES(CHIPS)':
 'B': CDS_PINID='B';
NET_NAME
'FM_FLASH_LATCH_N_R1'
 '@SCM_LIB.SCM(SCH_1):FM_FLASH_LATCH_N_R1':
 C_SIGNAL='@scm_lib.scm(sch_1):fm_flash_latch_n_r1';
NODE_NAME     U5 AE11
 '@SCM_LIB.SCM(SCH_1):PAGE13_I363@PURE_QUANTA.AST2600A3GP(CHIPS)':
 'GPIOY2||SALT7||WDTRST3#': CDS_PINID='\gpioy2||salt7||wdtrst3#\';
NODE_NAME     R465 1
 '@SCM_LIB.SCM(SCH_1):PAGE13_I432@PURE_QUANTA.Q_RES(CHIPS)':
 'A': CDS_PINID='A';
NET_NAME
'FM_HDD_LED_N'
 '@SCM_LIB.SCM(SCH_1):FM_HDD_LED_N':
 C_SIGNAL='@scm_lib.scm(sch_1):fm_hdd_led_n';
NODE_NAME     U5 Y26
 '@SCM_LIB.SCM(SCH_1):PAGE15_I350@PURE_QUANTA.AST2600A3GP(CHIPS)':
 'GPIOQ4||TACH4': CDS_PINID='\gpioq4||tach4\';
NODE_NAME     U25 P6
 '@SCM_LIB.SCM(SCH_1):PAGE36_I1@PURE_QUANTA.LCMXO3LF2100C5BG256C(CHIPS)':
 'PB8A||MCLK||CCLK': CDS_PINID='\pb8a||mclk||cclk\';
NODE_NAME     R838 2
 '@SCM_LIB.SCM(SCH_1):PAGE10_I568@PURE_QUANTA.Q_RES(CHIPS)':
 'B': CDS_PINID='B';
NET_NAME
'FM_ID_LED'
 '@SCM_LIB.SCM(SCH_1):FM_ID_LED':
 C_SIGNAL='@scm_lib.scm(sch_1):fm_id_led';
NODE_NAME     U5 G26
 '@SCM_LIB.SCM(SCH_1):PAGE13_I363@PURE_QUANTA.AST2600A3GP(CHIPS)':
 'GPIOB5||MDIO2': CDS_PINID='\gpiob5||mdio2\';
NODE_NAME     R390 1
 '@SCM_LIB.SCM(SCH_1):PAGE49_I92@PURE_QUANTA.Q_RES(CHIPS)':
 'A': CDS_PINID='A';
NET_NAME
'FM_ID_R_LED'
 '@SCM_LIB.SCM(SCH_1):FM_ID_R_LED':
 C_SIGNAL='@scm_lib.scm(sch_1):fm_id_r_led';
NODE_NAME     U9 2
 '@SCM_LIB.SCM(SCH_1):PAGE49_I5@PURE_QUANTA.MC74VHC1G32DTT1G(CHIPS)':
 'IN_A': CDS_PINID='IN_A';
NODE_NAME     R390 2
 '@SCM_LIB.SCM(SCH_1):PAGE49_I92@PURE_QUANTA.Q_RES(CHIPS)':
 'B': CDS_PINID='B';
NET_NAME
'FM_INTRUDER_N'
 '@SCM_LIB.SCM(SCH_1):FM_INTRUDER_N':
 C_SIGNAL='@scm_lib.scm(sch_1):fm_intruder_n';
NODE_NAME     GF1 A54
 '@SCM_LIB.SCM(SCH_1):PAGE10_I553@PURE_QUANTA.FCONN168_ME1016810202011_SCM(CHIPS)':
 'CHASI_N': CDS_PINID='CHASI_N';
NODE_NAME     R853 2
 '@SCM_LIB.SCM(SCH_1):PAGE15_I387@PURE_QUANTA.Q_RES(CHIPS)':
 'B': CDS_PINID='B';
NET_NAME
'FM_INTRUDER_R_N'
 '@SCM_LIB.SCM(SCH_1):FM_INTRUDER_R_N':
 C_SIGNAL='@scm_lib.scm(sch_1):fm_intruder_r_n';
NODE_NAME     U5 AB21
 '@SCM_LIB.SCM(SCH_1):PAGE15_I350@PURE_QUANTA.AST2600A3GP(CHIPS)':
 'CHASI#': CDS_PINID='\chasi#\';
NODE_NAME     R853 1
 '@SCM_LIB.SCM(SCH_1):PAGE15_I387@PURE_QUANTA.Q_RES(CHIPS)':
 'A': CDS_PINID='A';
NET_NAME
'FM_JTAG_BMC_MUX_SEL'
 '@SCM_LIB.SCM(SCH_1):FM_JTAG_BMC_MUX_SEL':
 C_SIGNAL='@scm_lib.scm(sch_1):fm_jtag_bmc_mux_sel';
NODE_NAME     R644 1
 '@SCM_LIB.SCM(SCH_1):PAGE15_I345@PURE_QUANTA.Q_RES(CHIPS)':
 'A': CDS_PINID='A';
NODE_NAME     R634 1
 '@SCM_LIB.SCM(SCH_1):PAGE34_I37@PURE_QUANTA.Q_RES(CHIPS)':
 'A': CDS_PINID='A';
NODE_NAME     R640 2
 '@SCM_LIB.SCM(SCH_1):PAGE42_I56@PURE_QUANTA.Q_RES(CHIPS)':
 'B': CDS_PINID='B';
NODE_NAME     R642 2
 '@SCM_LIB.SCM(SCH_1):PAGE42_I58@PURE_QUANTA.Q_RES(CHIPS)':
 'B': CDS_PINID='B';
NET_NAME
'FM_JTAG_BMC_MUX_SEL_R1'
 '@SCM_LIB.SCM(SCH_1):FM_JTAG_BMC_MUX_SEL_R1':
 C_SIGNAL='@scm_lib.scm(sch_1):fm_jtag_bmc_mux_sel_r1';
NODE_NAME     R644 2
 '@SCM_LIB.SCM(SCH_1):PAGE15_I345@PURE_QUANTA.Q_RES(CHIPS)':
 'B': CDS_PINID='B';
NODE_NAME     U5 AD24
 '@SCM_LIB.SCM(SCH_1):PAGE15_I350@PURE_QUANTA.AST2600A3GP(CHIPS)':
 'GPIOO3||PWM3': CDS_PINID='\gpioo3||pwm3\';
NET_NAME
'FM_JTAG_BMC_MUX_SEL_R2'
 '@SCM_LIB.SCM(SCH_1):FM_JTAG_BMC_MUX_SEL_R2':
 C_SIGNAL='@scm_lib.scm(sch_1):fm_jtag_bmc_mux_sel_r2';
NODE_NAME     U25 B6
 '@SCM_LIB.SCM(SCH_1):PAGE34_I1@PURE_QUANTA.LCMXO3LF2100C5BG256C(CHIPS)':
 'PT11B': CDS_PINID='PT11B';
NODE_NAME     R634 2
 '@SCM_LIB.SCM(SCH_1):PAGE34_I37@PURE_QUANTA.Q_RES(CHIPS)':
 'B': CDS_PINID='B';
NET_NAME
'FM_JTAG_SEL'
 '@SCM_LIB.SCM(SCH_1):FM_JTAG_SEL':
 C_SIGNAL='@scm_lib.scm(sch_1):fm_jtag_sel';
NODE_NAME     GF1 A43
 '@SCM_LIB.SCM(SCH_1):PAGE10_I553@PURE_QUANTA.FCONN168_ME1016810202011_SCM(CHIPS)':
 'HPM_FW_RECOVERY': CDS_PINID='HPM_FW_RECOVERY';
NODE_NAME     U5 G23
 '@SCM_LIB.SCM(SCH_1):PAGE13_I363@PURE_QUANTA.AST2600A3GP(CHIPS)':
 'RGMII3RXCK||RMII3RCLKI||GPIOC6': CDS_PINID='\rgmii3rxck||rmii3rclki||gpioc6\';
NET_NAME
'FM_JTAG_TCK_MUX_BMC_SEL'
 '@SCM_LIB.SCM(SCH_1):FM_JTAG_TCK_MUX_BMC_SEL':
 C_SIGNAL='@scm_lib.scm(sch_1):fm_jtag_tck_mux_bmc_sel';
NODE_NAME     R159 1
 '@SCM_LIB.SCM(SCH_1):PAGE13_I17@PURE_QUANTA.Q_RES(CHIPS)':
 'A': CDS_PINID='A';
NODE_NAME     U25 T8
 '@SCM_LIB.SCM(SCH_1):PAGE36_I1@PURE_QUANTA.LCMXO3LF2100C5BG256C(CHIPS)':
 'PB12B': CDS_PINID='PB12B';
NODE_NAME     R620 1
 '@SCM_LIB.SCM(SCH_1):PAGE48_I39@PURE_QUANTA.Q_RES(CHIPS)':
 'A': CDS_PINID='A';
NODE_NAME     R616 2
 '@SCM_LIB.SCM(SCH_1):PAGE48_I40@PURE_QUANTA.Q_RES(CHIPS)':
 'B': CDS_PINID='B';
NET_NAME
'FM_JTAG_TCK_MUX_BMC_SEL_R'
 '@SCM_LIB.SCM(SCH_1):FM_JTAG_TCK_MUX_BMC_SEL_R':
 C_SIGNAL='@scm_lib.scm(sch_1):fm_jtag_tck_mux_bmc_sel_r';
NODE_NAME     R616 1
 '@SCM_LIB.SCM(SCH_1):PAGE48_I40@PURE_QUANTA.Q_RES(CHIPS)':
 'A': CDS_PINID='A';
NODE_NAME     R881 2
 '@SCM_LIB.SCM(SCH_1):PAGE48_I42@PURE_QUANTA.Q_RES(CHIPS)':
 'B': CDS_PINID='B';
NET_NAME
'FM_JTAG_TCK_MUX_BMC_SEL_R1'
 '@SCM_LIB.SCM(SCH_1):FM_JTAG_TCK_MUX_BMC_SEL_R1':
 C_SIGNAL='@scm_lib.scm(sch_1):fm_jtag_tck_mux_bmc_sel_r1';
NODE_NAME     R159 2
 '@SCM_LIB.SCM(SCH_1):PAGE13_I17@PURE_QUANTA.Q_RES(CHIPS)':
 'B': CDS_PINID='B';
NODE_NAME     U5 F15
 '@SCM_LIB.SCM(SCH_1):PAGE13_I363@PURE_QUANTA.AST2600A3GP(CHIPS)':
 'GPIOL5||RXD3': CDS_PINID='\gpiol5||rxd3\';
NET_NAME
'FM_ME_BT_DONE'
 '@SCM_LIB.SCM(SCH_1):FM_ME_BT_DONE':
 C_SIGNAL='@scm_lib.scm(sch_1):fm_me_bt_done';
NODE_NAME     U5 J26
 '@SCM_LIB.SCM(SCH_1):PAGE13_I363@PURE_QUANTA.AST2600A3GP(CHIPS)':
 'GPIOB0||SALT1': CDS_PINID='\gpiob0||salt1\';
NODE_NAME     R266 2
 '@SCM_LIB.SCM(SCH_1):PAGE27_I95@PURE_QUANTA.Q_RES(CHIPS)':
 'B': CDS_PINID='B';
NODE_NAME     U25 D7
 '@SCM_LIB.SCM(SCH_1):PAGE34_I1@PURE_QUANTA.LCMXO3LF2100C5BG256C(CHIPS)':
 'PT13D': CDS_PINID='PT13D';
NET_NAME
'FM_P12V_HSC_ENABLE'
 '@SCM_LIB.SCM(SCH_1):FM_P12V_HSC_ENABLE':
 C_SIGNAL='@scm_lib.scm(sch_1):fm_p12v_hsc_enable';
NODE_NAME     R479 1
 '@SCM_LIB.SCM(SCH_1):PAGE15_I330@PURE_QUANTA.Q_RES(CHIPS)':
 'A': CDS_PINID='A';
NODE_NAME     R575 1
 '@SCM_LIB.SCM(SCH_1):PAGE36_I2@PURE_QUANTA.Q_RES(CHIPS)':
 'A': CDS_PINID='A';
NODE_NAME     R621 2
 '@SCM_LIB.SCM(SCH_1):PAGE42_I13@PURE_QUANTA.Q_RES(CHIPS)':
 'B': CDS_PINID='B';
NET_NAME
'FM_P12V_HSC_ENABLE_R1'
 '@SCM_LIB.SCM(SCH_1):FM_P12V_HSC_ENABLE_R1':
 C_SIGNAL='@scm_lib.scm(sch_1):fm_p12v_hsc_enable_r1';
NODE_NAME     R479 2
 '@SCM_LIB.SCM(SCH_1):PAGE15_I330@PURE_QUANTA.Q_RES(CHIPS)':
 'B': CDS_PINID='B';
NODE_NAME     U5 AC26
 '@SCM_LIB.SCM(SCH_1):PAGE15_I350@PURE_QUANTA.AST2600A3GP(CHIPS)':
 'GPIOQ5||TACH5': CDS_PINID='\gpioq5||tach5\';
NET_NAME
'FM_P12V_HSC_ENABLE_R2'
 '@SCM_LIB.SCM(SCH_1):FM_P12V_HSC_ENABLE_R2':
 C_SIGNAL='@scm_lib.scm(sch_1):fm_p12v_hsc_enable_r2';
NODE_NAME     U25 P4
 '@SCM_LIB.SCM(SCH_1):PAGE36_I1@PURE_QUANTA.LCMXO3LF2100C5BG256C(CHIPS)':
 'PB3A': CDS_PINID='PB3A';
NODE_NAME     R575 2
 '@SCM_LIB.SCM(SCH_1):PAGE36_I2@PURE_QUANTA.Q_RES(CHIPS)':
 'B': CDS_PINID='B';
NET_NAME
'FM_PCHHOT_R_N'
 '@SCM_LIB.SCM(SCH_1):FM_PCHHOT_R_N':
 C_SIGNAL='@scm_lib.scm(sch_1):fm_pchhot_r_n';
NODE_NAME     U5 AD16
 '@SCM_LIB.SCM(SCH_1):PAGE15_I350@PURE_QUANTA.AST2600A3GP(CHIPS)':
 'ADC14||GPIU6||SALT15': CDS_PINID='\adc14||gpiu6||salt15\';
NODE_NAME     U25 K11
 '@SCM_LIB.SCM(SCH_1):PAGE35_I1@PURE_QUANTA.LCMXO3LF2100C5BG256C(CHIPS)':
 'PR12C': CDS_PINID='PR12C';
NET_NAME
'FM_PCH_BEEP_LED'
 '@SCM_LIB.SCM(SCH_1):FM_PCH_BEEP_LED':
 C_SIGNAL='@scm_lib.scm(sch_1):fm_pch_beep_led';
NODE_NAME     U5 Y25
 '@SCM_LIB.SCM(SCH_1):PAGE15_I350@PURE_QUANTA.AST2600A3GP(CHIPS)':
 'GPIOQ6||TACH6': CDS_PINID='\gpioq6||tach6\';
NODE_NAME     U25 T6
 '@SCM_LIB.SCM(SCH_1):PAGE36_I1@PURE_QUANTA.LCMXO3LF2100C5BG256C(CHIPS)':
 'PB8B||SO||SPISO': CDS_PINID='\pb8b||so||spiso\';
NODE_NAME     R847 2
 '@SCM_LIB.SCM(SCH_1):PAGE10_I569@PURE_QUANTA.Q_RES(CHIPS)':
 'B': CDS_PINID='B';
NET_NAME
'FM_PCH_BMC_THERMTRIP_N'
 '@SCM_LIB.SCM(SCH_1):FM_PCH_BMC_THERMTRIP_N':
 C_SIGNAL='@scm_lib.scm(sch_1):fm_pch_bmc_thermtrip_n';
NODE_NAME     R62 2
 '@SCM_LIB.SCM(SCH_1):PAGE12_I350@PURE_QUANTA.Q_RES(CHIPS)':
 'B': CDS_PINID='B';
NODE_NAME     U25 D8
 '@SCM_LIB.SCM(SCH_1):PAGE34_I1@PURE_QUANTA.LCMXO3LF2100C5BG256C(CHIPS)':
 'PT17C': CDS_PINID='PT17C';
NODE_NAME     R763 1
 '@SCM_LIB.SCM(SCH_1):PAGE13_I402@PURE_QUANTA.Q_RES(CHIPS)':
 'A': CDS_PINID='A';
NET_NAME
'FM_PCIE_M2_SSD0_PRSNT_N'
 '@SCM_LIB.SCM(SCH_1):FM_PCIE_M2_SSD0_PRSNT_N':
 C_SIGNAL='@scm_lib.scm(sch_1):fm_pcie_m2_ssd0_prsnt_n';
NODE_NAME     U5 AD23
 '@SCM_LIB.SCM(SCH_1):PAGE15_I350@PURE_QUANTA.AST2600A3GP(CHIPS)':
 'GPIOO2||PWM2': CDS_PINID='\gpioo2||pwm2\';
NODE_NAME     U25 F7
 '@SCM_LIB.SCM(SCH_1):PAGE34_I1@PURE_QUANTA.LCMXO3LF2100C5BG256C(CHIPS)':
 'PT16A': CDS_PINID='PT16A';
NET_NAME
'FM_PECI_SEL_N'
 '@SCM_LIB.SCM(SCH_1):FM_PECI_SEL_N':
 C_SIGNAL='@scm_lib.scm(sch_1):fm_peci_sel_n';
NODE_NAME     R439 1
 '@SCM_LIB.SCM(SCH_1):PAGE13_I227@PURE_QUANTA.Q_RES(CHIPS)':
 'A': CDS_PINID='A';
NODE_NAME     R446 2
 '@SCM_LIB.SCM(SCH_1):PAGE13_I299@PURE_QUANTA.Q_RES(CHIPS)':
 'B': CDS_PINID='B';
NODE_NAME     U25 B16
 '@SCM_LIB.SCM(SCH_1):PAGE35_I1@PURE_QUANTA.LCMXO3LF2100C5BG256C(CHIPS)':
 'PR1D': CDS_PINID='PR1D';
NET_NAME
'FM_PECI_SEL_R_N'
 '@SCM_LIB.SCM(SCH_1):FM_PECI_SEL_R_N':
 C_SIGNAL='@scm_lib.scm(sch_1):fm_peci_sel_r_n';
NODE_NAME     R439 2
 '@SCM_LIB.SCM(SCH_1):PAGE13_I227@PURE_QUANTA.Q_RES(CHIPS)':
 'B': CDS_PINID='B';
NODE_NAME     U5 E14
 '@SCM_LIB.SCM(SCH_1):PAGE13_I363@PURE_QUANTA.AST2600A3GP(CHIPS)':
 'GPIOM3||NRI1': CDS_PINID='\gpiom3||nri1\';
NET_NAME
'FM_PFR_DSW_PWROK_N'
 '@SCM_LIB.SCM(SCH_1):FM_PFR_DSW_PWROK_N':
 C_SIGNAL='@scm_lib.scm(sch_1):fm_pfr_dsw_pwrok_n';
NODE_NAME     U5 M24
 '@SCM_LIB.SCM(SCH_1):PAGE12_I436@PURE_QUANTA.AST2600A3GP(CHIPS)':
 'GPIOA0||SCL11||MDC3': CDS_PINID='\gpioa0||scl11||mdc3\';
NODE_NAME     U25 L8
 '@SCM_LIB.SCM(SCH_1):PAGE36_I1@PURE_QUANTA.LCMXO3LF2100C5BG256C(CHIPS)':
 'PB11D': CDS_PINID='PB11D';
NET_NAME
'FM_PLT_BMC_THERMTRIP_N_R'
 '@SCM_LIB.SCM(SCH_1):FM_PLT_BMC_THERMTRIP_N_R':
 C_SIGNAL='@scm_lib.scm(sch_1):fm_plt_bmc_thermtrip_n_r';
NODE_NAME     U5 C26
 '@SCM_LIB.SCM(SCH_1):PAGE13_I363@PURE_QUANTA.AST2600A3GP(CHIPS)':
 'RGMII4RXCTL||NDCD4||GPIOE3': CDS_PINID='\rgmii4rxctl||ndcd4||gpioe3\';
NODE_NAME     R763 2
 '@SCM_LIB.SCM(SCH_1):PAGE13_I402@PURE_QUANTA.Q_RES(CHIPS)':
 'B': CDS_PINID='B';
NET_NAME
'FM_PMBUS_ALERT_EN'
 '@SCM_LIB.SCM(SCH_1):FM_PMBUS_ALERT_EN':
 C_SIGNAL='@scm_lib.scm(sch_1):fm_pmbus_alert_en';
NODE_NAME     U5 AD26
 '@SCM_LIB.SCM(SCH_1):PAGE15_I350@PURE_QUANTA.AST2600A3GP(CHIPS)':
 'GPIOO0||PWM0': CDS_PINID='\gpioo0||pwm0\';
NODE_NAME     U25 J16
 '@SCM_LIB.SCM(SCH_1):PAGE35_I1@PURE_QUANTA.LCMXO3LF2100C5BG256C(CHIPS)':
 'PR7C': CDS_PINID='PR7C';
NET_NAME
'FM_PRSNT_0_R_N'
 '@SCM_LIB.SCM(SCH_1):FM_PRSNT_0_R_N':
 C_SIGNAL='@scm_lib.scm(sch_1):fm_prsnt_0_r_n';
NODE_NAME     R822 2
 '@SCM_LIB.SCM(SCH_1):PAGE10_I456@PURE_QUANTA.Q_RES(CHIPS)':
 'B': CDS_PINID='B';
NODE_NAME     GF1 OB3
 '@SCM_LIB.SCM(SCH_1):PAGE10_I553@PURE_QUANTA.FCONN168_ME1016810202011_SCM(CHIPS)':
 'PRSNT0_N': CDS_PINID='PRSNT0_N';
NET_NAME
'FM_PRSNT_1_N'
 '@SCM_LIB.SCM(SCH_1):FM_PRSNT_1_N':
 C_SIGNAL='@scm_lib.scm(sch_1):fm_prsnt_1_n';
NODE_NAME     R822 1
 '@SCM_LIB.SCM(SCH_1):PAGE10_I456@PURE_QUANTA.Q_RES(CHIPS)':
 'A': CDS_PINID='A';
NODE_NAME     GF1 A57
 '@SCM_LIB.SCM(SCH_1):PAGE10_I553@PURE_QUANTA.FCONN168_ME1016810202011_SCM(CHIPS)':
 'PRSNT1_N': CDS_PINID='PRSNT1_N';
NET_NAME
'FM_PWR_BTN'
 '@SCM_LIB.SCM(SCH_1):FM_PWR_BTN':
 C_SIGNAL='@scm_lib.scm(sch_1):fm_pwr_btn';
NODE_NAME     U5 AB22
 '@SCM_LIB.SCM(SCH_1):PAGE15_I350@PURE_QUANTA.AST2600A3GP(CHIPS)':
 'GPIOP0||PWM8||THRUIN0': CDS_PINID='\gpiop0||pwm8||thruin0\';
NODE_NAME     R432 2
 '@SCM_LIB.SCM(SCH_1):PAGE35_I100@PURE_QUANTA.Q_RES(CHIPS)':
 'B': CDS_PINID='B';
NODE_NAME     R225 1
 '@SCM_LIB.SCM(SCH_1):PAGE15_I405@PURE_QUANTA.Q_RES(CHIPS)':
 'A': CDS_PINID='A';
NET_NAME
'FM_PWR_R_BTN'
 '@SCM_LIB.SCM(SCH_1):FM_PWR_R_BTN':
 C_SIGNAL='@scm_lib.scm(sch_1):fm_pwr_r_btn';
NODE_NAME     U25 K14
 '@SCM_LIB.SCM(SCH_1):PAGE35_I1@PURE_QUANTA.LCMXO3LF2100C5BG256C(CHIPS)':
 'PR10A': CDS_PINID='PR10A';
NODE_NAME     R432 1
 '@SCM_LIB.SCM(SCH_1):PAGE35_I100@PURE_QUANTA.Q_RES(CHIPS)':
 'A': CDS_PINID='A';
NET_NAME
'FM_SLPS3_GF_N'
 '@SCM_LIB.SCM(SCH_1):FM_SLPS3_GF_N':
 C_SIGNAL='@scm_lib.scm(sch_1):fm_slps3_gf_n';
NODE_NAME     R774 2
 '@SCM_LIB.SCM(SCH_1):PAGE13_I213@PURE_QUANTA.Q_RES(CHIPS)':
 'B': CDS_PINID='B';
NODE_NAME     R722 2
 '@SCM_LIB.SCM(SCH_1):PAGE13_I350@PURE_QUANTA.Q_RES(CHIPS)':
 'B': CDS_PINID='B';
NODE_NAME     R721 1
 '@SCM_LIB.SCM(SCH_1):PAGE28_I145@PURE_QUANTA.Q_RES(CHIPS)':
 'A': CDS_PINID='A';
NODE_NAME     R773 1
 '@SCM_LIB.SCM(SCH_1):PAGE35_I137@PURE_QUANTA.Q_RES(CHIPS)':
 'A': CDS_PINID='A';
NET_NAME
'FM_SLPS3_GF_R1_N'
 '@SCM_LIB.SCM(SCH_1):FM_SLPS3_GF_R1_N':
 C_SIGNAL='@scm_lib.scm(sch_1):fm_slps3_gf_r1_n';
NODE_NAME     R722 1
 '@SCM_LIB.SCM(SCH_1):PAGE13_I350@PURE_QUANTA.Q_RES(CHIPS)':
 'A': CDS_PINID='A';
NODE_NAME     U5 AB15
 '@SCM_LIB.SCM(SCH_1):PAGE13_I363@PURE_QUANTA.AST2600A3GP(CHIPS)':
 'GPIOV0||SIOS3#': CDS_PINID='\gpiov0||sios3#\';
NET_NAME
'FM_SLPS3_GF_R2_N'
 '@SCM_LIB.SCM(SCH_1):FM_SLPS3_GF_R2_N':
 C_SIGNAL='@scm_lib.scm(sch_1):fm_slps3_gf_r2_n';
NODE_NAME     U40 19
 '@SCM_LIB.SCM(SCH_1):PAGE28_I141@PURE_QUANTA.PCA9555PW(CHIPS)':
 'P16': CDS_PINID='P16';
NODE_NAME     R721 2
 '@SCM_LIB.SCM(SCH_1):PAGE28_I145@PURE_QUANTA.Q_RES(CHIPS)':
 'B': CDS_PINID='B';
NET_NAME
'FM_SLPS3_GF_R_N'
 '@SCM_LIB.SCM(SCH_1):FM_SLPS3_GF_R_N':
 C_SIGNAL='@scm_lib.scm(sch_1):fm_slps3_gf_r_n';
NODE_NAME     U25 G11
 '@SCM_LIB.SCM(SCH_1):PAGE35_I1@PURE_QUANTA.LCMXO3LF2100C5BG256C(CHIPS)':
 'PR5C': CDS_PINID='PR5C';
NODE_NAME     R773 2
 '@SCM_LIB.SCM(SCH_1):PAGE35_I137@PURE_QUANTA.Q_RES(CHIPS)':
 'B': CDS_PINID='B';
NET_NAME
'FM_SOL_UART_CH_SEL'
 '@SCM_LIB.SCM(SCH_1):FM_SOL_UART_CH_SEL':
 C_SIGNAL='@scm_lib.scm(sch_1):fm_sol_uart_ch_sel';
NODE_NAME     GF1 OB14
 '@SCM_LIB.SCM(SCH_1):PAGE10_I553@PURE_QUANTA.FCONN168_ME1016810202011_SCM(CHIPS)':
 'SPI0_MISO': CDS_PINID='SPI0_MISO';
NODE_NAME     R489 1
 '@SCM_LIB.SCM(SCH_1):PAGE15_I326@PURE_QUANTA.Q_RES(CHIPS)':
 'A': CDS_PINID='A';
NODE_NAME     R626 1
 '@SCM_LIB.SCM(SCH_1):PAGE28_I161@PURE_QUANTA.Q_RES(CHIPS)':
 'A': CDS_PINID='A';
NODE_NAME     R577 1
 '@SCM_LIB.SCM(SCH_1):PAGE36_I3@PURE_QUANTA.Q_RES(CHIPS)':
 'A': CDS_PINID='A';
NET_NAME
'FM_SOL_UART_CH_SEL_R1'
 '@SCM_LIB.SCM(SCH_1):FM_SOL_UART_CH_SEL_R1':
 C_SIGNAL='@scm_lib.scm(sch_1):fm_sol_uart_ch_sel_r1';
NODE_NAME     R489 2
 '@SCM_LIB.SCM(SCH_1):PAGE15_I326@PURE_QUANTA.Q_RES(CHIPS)':
 'B': CDS_PINID='B';
NODE_NAME     U5 AA26
 '@SCM_LIB.SCM(SCH_1):PAGE15_I350@PURE_QUANTA.AST2600A3GP(CHIPS)':
 'GPIOQ7||TACH7': CDS_PINID='\gpioq7||tach7\';
NET_NAME
'FM_SOL_UART_CH_SEL_R2'
 '@SCM_LIB.SCM(SCH_1):FM_SOL_UART_CH_SEL_R2':
 C_SIGNAL='@scm_lib.scm(sch_1):fm_sol_uart_ch_sel_r2';
NODE_NAME     U25 T2
 '@SCM_LIB.SCM(SCH_1):PAGE36_I1@PURE_QUANTA.LCMXO3LF2100C5BG256C(CHIPS)':
 'PB3C': CDS_PINID='PB3C';
NODE_NAME     R577 2
 '@SCM_LIB.SCM(SCH_1):PAGE36_I3@PURE_QUANTA.Q_RES(CHIPS)':
 'B': CDS_PINID='B';
NET_NAME
'FM_SOL_UART_CH_SEL_R3'
 '@SCM_LIB.SCM(SCH_1):FM_SOL_UART_CH_SEL_R3':
 C_SIGNAL='@scm_lib.scm(sch_1):fm_sol_uart_ch_sel_r3';
NODE_NAME     R626 2
 '@SCM_LIB.SCM(SCH_1):PAGE28_I161@PURE_QUANTA.Q_RES(CHIPS)':
 'B': CDS_PINID='B';
NODE_NAME     R736 2
 '@SCM_LIB.SCM(SCH_1):PAGE28_I162@PURE_QUANTA.Q_RES(CHIPS)':
 'B': CDS_PINID='B';
NODE_NAME     Q8 D
 '@SCM_LIB.SCM(SCH_1):PAGE28_I163@PURE_QUANTA.2N7002A7(CHIPS)':
 'D': CDS_PINID='D';
NET_NAME
'FM_SPD_REMOTE_EN_R'
 '@SCM_LIB.SCM(SCH_1):FM_SPD_REMOTE_EN_R':
 C_SIGNAL='@scm_lib.scm(sch_1):fm_spd_remote_en_r';
NODE_NAME     U5 AC23
 '@SCM_LIB.SCM(SCH_1):PAGE15_I350@PURE_QUANTA.AST2600A3GP(CHIPS)':
 'GPIOO7||PWM7': CDS_PINID='\gpioo7||pwm7\';
NODE_NAME     U25 E15
 '@SCM_LIB.SCM(SCH_1):PAGE35_I1@PURE_QUANTA.LCMXO3LF2100C5BG256C(CHIPS)':
 'PR1B': CDS_PINID='PR1B';
NET_NAME
'FM_THERMTRIP_DLY_LVC1_R_N'
 '@SCM_LIB.SCM(SCH_1):FM_THERMTRIP_DLY_LVC1_R_N':
 C_SIGNAL='@scm_lib.scm(sch_1):fm_thermtrip_dly_lvc1_r_n';
NODE_NAME     U5 T26
 '@SCM_LIB.SCM(SCH_1):PAGE12_I436@PURE_QUANTA.AST2600A3GP(CHIPS)':
 'GPIOS2||PEWAKE#': CDS_PINID='\gpios2||pewake#\';
NODE_NAME     U25 A15
 '@SCM_LIB.SCM(SCH_1):PAGE34_I1@PURE_QUANTA.LCMXO3LF2100C5BG256C(CHIPS)':
 'PT24B': CDS_PINID='PT24B';
NODE_NAME     R400 2
 '@SCM_LIB.SCM(SCH_1):PAGE12_I454@PURE_QUANTA.Q_RES(CHIPS)':
 'B': CDS_PINID='B';
NET_NAME
'FM_THROTTLE_N'
 '@SCM_LIB.SCM(SCH_1):FM_THROTTLE_N':
 C_SIGNAL='@scm_lib.scm(sch_1):fm_throttle_n';
NODE_NAME     R45 2
 '@SCM_LIB.SCM(SCH_1):PAGE11_I176@PURE_QUANTA.Q_RES(CHIPS)':
 'B': CDS_PINID='B';
NODE_NAME     U5 B16
 '@SCM_LIB.SCM(SCH_1):PAGE13_I363@PURE_QUANTA.AST2600A3GP(CHIPS)':
 'GPIOI6||SIOPBI#': CDS_PINID='\gpioi6||siopbi#\';
NODE_NAME     R769 1
 '@SCM_LIB.SCM(SCH_1):PAGE35_I140@PURE_QUANTA.Q_RES(CHIPS)':
 'A': CDS_PINID='A';
NET_NAME
'FM_THROTTLE_R_N'
 '@SCM_LIB.SCM(SCH_1):FM_THROTTLE_R_N':
 C_SIGNAL='@scm_lib.scm(sch_1):fm_throttle_r_n';
NODE_NAME     U25 J12
 '@SCM_LIB.SCM(SCH_1):PAGE35_I1@PURE_QUANTA.LCMXO3LF2100C5BG256C(CHIPS)':
 'PR6D': CDS_PINID='PR6D';
NODE_NAME     R769 2
 '@SCM_LIB.SCM(SCH_1):PAGE35_I140@PURE_QUANTA.Q_RES(CHIPS)':
 'B': CDS_PINID='B';
NET_NAME
'FM_TPM_PRSNT_0_N'
 '@SCM_LIB.SCM(SCH_1):FM_TPM_PRSNT_0_N':
 C_SIGNAL='@scm_lib.scm(sch_1):fm_tpm_prsnt_0_n';
NODE_NAME     U5 AC22
 '@SCM_LIB.SCM(SCH_1):PAGE15_I350@PURE_QUANTA.AST2600A3GP(CHIPS)':
 'GPIOO5||PWM5': CDS_PINID='\gpioo5||pwm5\';
NODE_NAME     J5 8
 '@SCM_LIB.SCM(SCH_1):PAGE46_I56@PURE_QUANTA.SCONN11_9192031111LF(CHIPS)':
 '8': CDS_PINID='\8\';
NODE_NAME     R464 2
 '@SCM_LIB.SCM(SCH_1):PAGE46_I75@PURE_QUANTA.Q_RES(CHIPS)':
 'B': CDS_PINID='B';
NODE_NAME     R767 1
 '@SCM_LIB.SCM(SCH_1):PAGE34_I150@PURE_QUANTA.Q_RES(CHIPS)':
 'A': CDS_PINID='A';
NET_NAME
'FM_TPM_PRSNT_0_R_N'
 '@SCM_LIB.SCM(SCH_1):FM_TPM_PRSNT_0_R_N':
 C_SIGNAL='@scm_lib.scm(sch_1):fm_tpm_prsnt_0_r_n';
NODE_NAME     U25 C4
 '@SCM_LIB.SCM(SCH_1):PAGE34_I1@PURE_QUANTA.LCMXO3LF2100C5BG256C(CHIPS)':
 'PT9A': CDS_PINID='PT9A';
NODE_NAME     R767 2
 '@SCM_LIB.SCM(SCH_1):PAGE34_I150@PURE_QUANTA.Q_RES(CHIPS)':
 'B': CDS_PINID='B';
NET_NAME
'FM_TPM_PRSNT_1_N'
 '@SCM_LIB.SCM(SCH_1):FM_TPM_PRSNT_1_N':
 C_SIGNAL='@scm_lib.scm(sch_1):fm_tpm_prsnt_1_n';
NODE_NAME     U5 R24
 '@SCM_LIB.SCM(SCH_1):PAGE12_I436@PURE_QUANTA.AST2600A3GP(CHIPS)':
 'GPIOS3||OSCCLK': CDS_PINID='\gpios3||oscclk\';
NODE_NAME     R50 2
 '@SCM_LIB.SCM(SCH_1):PAGE46_I104@PURE_QUANTA.Q_RES(CHIPS)':
 'B': CDS_PINID='B';
NODE_NAME     J10 8
 '@SCM_LIB.SCM(SCH_1):PAGE46_I113@PURE_QUANTA.SCONN11_9192031111LF(CHIPS)':
 '8': CDS_PINID='\8\';
NODE_NAME     R123 1
 '@SCM_LIB.SCM(SCH_1):PAGE34_I156@PURE_QUANTA.Q_RES(CHIPS)':
 'A': CDS_PINID='A';
NET_NAME
'FM_TPM_PRSNT_1_R_N'
 '@SCM_LIB.SCM(SCH_1):FM_TPM_PRSNT_1_R_N':
 C_SIGNAL='@scm_lib.scm(sch_1):fm_tpm_prsnt_1_r_n';
NODE_NAME     U25 B5
 '@SCM_LIB.SCM(SCH_1):PAGE34_I1@PURE_QUANTA.LCMXO3LF2100C5BG256C(CHIPS)':
 'PT9B': CDS_PINID='PT9B';
NODE_NAME     R123 2
 '@SCM_LIB.SCM(SCH_1):PAGE34_I156@PURE_QUANTA.Q_RES(CHIPS)':
 'B': CDS_PINID='B';
NET_NAME
'FM_UARTSW_LSB_N'
 '@SCM_LIB.SCM(SCH_1):FM_UARTSW_LSB_N':
 C_SIGNAL='@scm_lib.scm(sch_1):fm_uartsw_lsb_n';
NODE_NAME     U2 5
 '@SCM_LIB.SCM(SCH_1):PAGE30_I250@PURE_QUANTA.FSA3357K8X(CHIPS)':
 'S2': CDS_PINID='S2';
NODE_NAME     U3 5
 '@SCM_LIB.SCM(SCH_1):PAGE30_I251@PURE_QUANTA.FSA3357K8X(CHIPS)':
 'S2': CDS_PINID='S2';
NODE_NAME     R898 2
 '@SCM_LIB.SCM(SCH_1):PAGE36_I42@PURE_QUANTA.Q_RES(CHIPS)':
 'B': CDS_PINID='B';
NODE_NAME     R134 2
 '@SCM_LIB.SCM(SCH_1):PAGE36_I47@PURE_QUANTA.Q_RES(CHIPS)':
 'B': CDS_PINID='B';
NODE_NAME     R283 1
 '@SCM_LIB.SCM(SCH_1):PAGE49_I88@PURE_QUANTA.Q_RES(CHIPS)':
 'A': CDS_PINID='A';
NET_NAME
'FM_UARTSW_LSB_R1_N'
 '@SCM_LIB.SCM(SCH_1):FM_UARTSW_LSB_R1_N':
 C_SIGNAL='@scm_lib.scm(sch_1):fm_uartsw_lsb_r1_n';
NODE_NAME     D18 C
 '@SCM_LIB.SCM(SCH_1):PAGE49_I51@PURE_QUANTA.Q_LED(CHIPS)':
 'C': CDS_PINID='C';
NODE_NAME     R283 2
 '@SCM_LIB.SCM(SCH_1):PAGE49_I88@PURE_QUANTA.Q_RES(CHIPS)':
 'B': CDS_PINID='B';
NET_NAME
'FM_UARTSW_LSB_R_N'
 '@SCM_LIB.SCM(SCH_1):FM_UARTSW_LSB_R_N':
 C_SIGNAL='@scm_lib.scm(sch_1):fm_uartsw_lsb_r_n';
NODE_NAME     U25 M9
 '@SCM_LIB.SCM(SCH_1):PAGE36_I1@PURE_QUANTA.LCMXO3LF2100C5BG256C(CHIPS)':
 'PB18C': CDS_PINID='PB18C';
NODE_NAME     R898 1
 '@SCM_LIB.SCM(SCH_1):PAGE36_I42@PURE_QUANTA.Q_RES(CHIPS)':
 'A': CDS_PINID='A';
NET_NAME
'FM_UARTSW_MSB_N'
 '@SCM_LIB.SCM(SCH_1):FM_UARTSW_MSB_N':
 C_SIGNAL='@scm_lib.scm(sch_1):fm_uartsw_msb_n';
NODE_NAME     U2 6
 '@SCM_LIB.SCM(SCH_1):PAGE30_I250@PURE_QUANTA.FSA3357K8X(CHIPS)':
 'S1': CDS_PINID='S1';
NODE_NAME     U3 6
 '@SCM_LIB.SCM(SCH_1):PAGE30_I251@PURE_QUANTA.FSA3357K8X(CHIPS)':
 'S1': CDS_PINID='S1';
NODE_NAME     R899 2
 '@SCM_LIB.SCM(SCH_1):PAGE36_I43@PURE_QUANTA.Q_RES(CHIPS)':
 'B': CDS_PINID='B';
NODE_NAME     R220 2
 '@SCM_LIB.SCM(SCH_1):PAGE36_I46@PURE_QUANTA.Q_RES(CHIPS)':
 'B': CDS_PINID='B';
NODE_NAME     R284 1
 '@SCM_LIB.SCM(SCH_1):PAGE49_I89@PURE_QUANTA.Q_RES(CHIPS)':
 'A': CDS_PINID='A';
NET_NAME
'FM_UARTSW_MSB_R1_N'
 '@SCM_LIB.SCM(SCH_1):FM_UARTSW_MSB_R1_N':
 C_SIGNAL='@scm_lib.scm(sch_1):fm_uartsw_msb_r1_n';
NODE_NAME     D19 C
 '@SCM_LIB.SCM(SCH_1):PAGE49_I50@PURE_QUANTA.Q_LED(CHIPS)':
 'C': CDS_PINID='C';
NODE_NAME     R284 2
 '@SCM_LIB.SCM(SCH_1):PAGE49_I89@PURE_QUANTA.Q_RES(CHIPS)':
 'B': CDS_PINID='B';
NET_NAME
'FM_UARTSW_MSB_R_N'
 '@SCM_LIB.SCM(SCH_1):FM_UARTSW_MSB_R_N':
 C_SIGNAL='@scm_lib.scm(sch_1):fm_uartsw_msb_r_n';
NODE_NAME     U25 L10
 '@SCM_LIB.SCM(SCH_1):PAGE36_I1@PURE_QUANTA.LCMXO3LF2100C5BG256C(CHIPS)':
 'PB18D': CDS_PINID='PB18D';
NODE_NAME     R899 1
 '@SCM_LIB.SCM(SCH_1):PAGE36_I43@PURE_QUANTA.Q_RES(CHIPS)':
 'A': CDS_PINID='A';
NET_NAME
'FM_UART_SEL_N'
 '@SCM_LIB.SCM(SCH_1):FM_UART_SEL_N':
 C_SIGNAL='@scm_lib.scm(sch_1):fm_uart_sel_n';
NODE_NAME     Q8 G
 '@SCM_LIB.SCM(SCH_1):PAGE28_I163@PURE_QUANTA.2N7002A7(CHIPS)':
 'G': CDS_PINID='G';
NODE_NAME     R83 1
 '@SCM_LIB.SCM(SCH_1):PAGE28_I164@PURE_QUANTA.Q_RES(CHIPS)':
 'A': CDS_PINID='A';
NET_NAME
'FM_UART_SWITCH_N'
 '@SCM_LIB.SCM(SCH_1):FM_UART_SWITCH_N':
 C_SIGNAL='@scm_lib.scm(sch_1):fm_uart_switch_n';
NODE_NAME     U40 20
 '@SCM_LIB.SCM(SCH_1):PAGE28_I141@PURE_QUANTA.PCA9555PW(CHIPS)':
 'P17': CDS_PINID='P17';
NODE_NAME     R83 2
 '@SCM_LIB.SCM(SCH_1):PAGE28_I164@PURE_QUANTA.Q_RES(CHIPS)':
 'B': CDS_PINID='B';
NODE_NAME     R735 2
 '@SCM_LIB.SCM(SCH_1):PAGE28_I166@PURE_QUANTA.Q_RES(CHIPS)':
 'B': CDS_PINID='B';
NET_NAME
'FM_VIRTUAL_RESEAT'
 '@SCM_LIB.SCM(SCH_1):FM_VIRTUAL_RESEAT':
 C_SIGNAL='@scm_lib.scm(sch_1):fm_virtual_reseat';
NODE_NAME     GF1 OA14
 '@SCM_LIB.SCM(SCH_1):PAGE10_I553@PURE_QUANTA.FCONN168_ME1016810202011_SCM(CHIPS)':
 'VIRTUAL_RESEAT': CDS_PINID='VIRTUAL_RESEAT';
NODE_NAME     R823 2
 '@SCM_LIB.SCM(SCH_1):PAGE11_I234@PURE_QUANTA.Q_RES(CHIPS)':
 'B': CDS_PINID='B';
NODE_NAME     R824 1
 '@SCM_LIB.SCM(SCH_1):PAGE13_I223@PURE_QUANTA.Q_RES(CHIPS)':
 'A': CDS_PINID='A';
NET_NAME
'FM_VIRTUAL_RESEAT_BMC'
 '@SCM_LIB.SCM(SCH_1):FM_VIRTUAL_RESEAT_BMC':
 C_SIGNAL='@scm_lib.scm(sch_1):fm_virtual_reseat_bmc';
NODE_NAME     R824 2
 '@SCM_LIB.SCM(SCH_1):PAGE13_I223@PURE_QUANTA.Q_RES(CHIPS)':
 'B': CDS_PINID='B';
NODE_NAME     U5 B13
 '@SCM_LIB.SCM(SCH_1):PAGE13_I363@PURE_QUANTA.AST2600A3GP(CHIPS)':
 'GPIOM1||NDCD1': CDS_PINID='\gpiom1||ndcd1\';
NET_NAME
'FRU_E0'
 '@SCM_LIB.SCM(SCH_1):FRU_E0':
 C_SIGNAL='@scm_lib.scm(sch_1):fru_e0';
NODE_NAME     R411 1
 '@SCM_LIB.SCM(SCH_1):PAGE26_I6@PURE_QUANTA.Q_RES(CHIPS)':
 'A': CDS_PINID='A';
NODE_NAME     R12 2
 '@SCM_LIB.SCM(SCH_1):PAGE26_I9@PURE_QUANTA.Q_RES(CHIPS)':
 'B': CDS_PINID='B';
NODE_NAME     U19 1
 '@SCM_LIB.SCM(SCH_1):PAGE26_I15@PURE_QUANTA.M24128BWDW6TP(CHIPS)':
 'E0': CDS_PINID='E0';
NET_NAME
'FRU_E1'
 '@SCM_LIB.SCM(SCH_1):FRU_E1':
 C_SIGNAL='@scm_lib.scm(sch_1):fru_e1';
NODE_NAME     R412 1
 '@SCM_LIB.SCM(SCH_1):PAGE26_I8@PURE_QUANTA.Q_RES(CHIPS)':
 'A': CDS_PINID='A';
NODE_NAME     R13 2
 '@SCM_LIB.SCM(SCH_1):PAGE26_I11@PURE_QUANTA.Q_RES(CHIPS)':
 'B': CDS_PINID='B';
NODE_NAME     U19 2
 '@SCM_LIB.SCM(SCH_1):PAGE26_I15@PURE_QUANTA.M24128BWDW6TP(CHIPS)':
 'E1': CDS_PINID='E1';
NET_NAME
'FRU_E2'
 '@SCM_LIB.SCM(SCH_1):FRU_E2':
 C_SIGNAL='@scm_lib.scm(sch_1):fru_e2';
NODE_NAME     R413 1
 '@SCM_LIB.SCM(SCH_1):PAGE26_I12@PURE_QUANTA.Q_RES(CHIPS)':
 'A': CDS_PINID='A';
NODE_NAME     R14 2
 '@SCM_LIB.SCM(SCH_1):PAGE26_I14@PURE_QUANTA.Q_RES(CHIPS)':
 'B': CDS_PINID='B';
NODE_NAME     U19 3
 '@SCM_LIB.SCM(SCH_1):PAGE26_I15@PURE_QUANTA.M24128BWDW6TP(CHIPS)':
 'E2': CDS_PINID='E2';
NET_NAME
'GND'
 '@SCM_LIB.SCM(SCH_1):GND':
 C_SIGNAL='@scm_lib.scm(sch_1):gnd',
 CDS_GLOBAL_NET='TRUE';
NODE_NAME     C174 2
 '@SCM_LIB.SCM(SCH_1):PAGE10_I503@PURE_QUANTA.Q_CAP(CHIPS)':
 'B': CDS_PINID='B';
NODE_NAME     GF1 A13
 '@SCM_LIB.SCM(SCH_1):PAGE10_I553@PURE_QUANTA.FCONN168_ME1016810202011_SCM(CHIPS)':
 'GND_A13': CDS_PINID='GND_A13';
NODE_NAME     GF1 A16
 '@SCM_LIB.SCM(SCH_1):PAGE10_I553@PURE_QUANTA.FCONN168_ME1016810202011_SCM(CHIPS)':
 'GND_A16': CDS_PINID='GND_A16';
NODE_NAME     GF1 A19
 '@SCM_LIB.SCM(SCH_1):PAGE10_I553@PURE_QUANTA.FCONN168_ME1016810202011_SCM(CHIPS)':
 'GND_A19': CDS_PINID='GND_A19';
NODE_NAME     GF1 A22
 '@SCM_LIB.SCM(SCH_1):PAGE10_I553@PURE_QUANTA.FCONN168_ME1016810202011_SCM(CHIPS)':
 'GND_A22': CDS_PINID='GND_A22';
NODE_NAME     GF1 A33
 '@SCM_LIB.SCM(SCH_1):PAGE10_I553@PURE_QUANTA.FCONN168_ME1016810202011_SCM(CHIPS)':
 'GND_A33': CDS_PINID='GND_A33';
NODE_NAME     GF1 A42
 '@SCM_LIB.SCM(SCH_1):PAGE10_I553@PURE_QUANTA.FCONN168_ME1016810202011_SCM(CHIPS)':
 'GND_A42': CDS_PINID='GND_A42';
NODE_NAME     GF1 A58
 '@SCM_LIB.SCM(SCH_1):PAGE10_I553@PURE_QUANTA.FCONN168_ME1016810202011_SCM(CHIPS)':
 'GND_A58': CDS_PINID='GND_A58';
NODE_NAME     GF1 A61
 '@SCM_LIB.SCM(SCH_1):PAGE10_I553@PURE_QUANTA.FCONN168_ME1016810202011_SCM(CHIPS)':
 'GND_A61': CDS_PINID='GND_A61';
NODE_NAME     GF1 A64
 '@SCM_LIB.SCM(SCH_1):PAGE10_I553@PURE_QUANTA.FCONN168_ME1016810202011_SCM(CHIPS)':
 'GND_A64': CDS_PINID='GND_A64';
NODE_NAME     GF1 A67
 '@SCM_LIB.SCM(SCH_1):PAGE10_I553@PURE_QUANTA.FCONN168_ME1016810202011_SCM(CHIPS)':
 'GND_A67': CDS_PINID='GND_A67';
NODE_NAME     GF1 A70
 '@SCM_LIB.SCM(SCH_1):PAGE10_I553@PURE_QUANTA.FCONN168_ME1016810202011_SCM(CHIPS)':
 'GND_A70': CDS_PINID='GND_A70';
NODE_NAME     GF1 B10
 '@SCM_LIB.SCM(SCH_1):PAGE10_I553@PURE_QUANTA.FCONN168_ME1016810202011_SCM(CHIPS)':
 'GND_B10': CDS_PINID='GND_B10';
NODE_NAME     GF1 B17
 '@SCM_LIB.SCM(SCH_1):PAGE10_I553@PURE_QUANTA.FCONN168_ME1016810202011_SCM(CHIPS)':
 'GND_B17': CDS_PINID='GND_B17';
NODE_NAME     GF1 B26
 '@SCM_LIB.SCM(SCH_1):PAGE10_I553@PURE_QUANTA.FCONN168_ME1016810202011_SCM(CHIPS)':
 'GND_B26': CDS_PINID='GND_B26';
NODE_NAME     GF1 B33
 '@SCM_LIB.SCM(SCH_1):PAGE10_I553@PURE_QUANTA.FCONN168_ME1016810202011_SCM(CHIPS)':
 'GND_B33': CDS_PINID='GND_B33';
NODE_NAME     GF1 B38
 '@SCM_LIB.SCM(SCH_1):PAGE10_I553@PURE_QUANTA.FCONN168_ME1016810202011_SCM(CHIPS)':
 'GND_B38': CDS_PINID='GND_B38';
NODE_NAME     GF1 B49
 '@SCM_LIB.SCM(SCH_1):PAGE10_I553@PURE_QUANTA.FCONN168_ME1016810202011_SCM(CHIPS)':
 'GND_B49': CDS_PINID='GND_B49';
NODE_NAME     GF1 B52
 '@SCM_LIB.SCM(SCH_1):PAGE10_I553@PURE_QUANTA.FCONN168_ME1016810202011_SCM(CHIPS)':
 'GND_B52': CDS_PINID='GND_B52';
NODE_NAME     GF1 B55
 '@SCM_LIB.SCM(SCH_1):PAGE10_I553@PURE_QUANTA.FCONN168_ME1016810202011_SCM(CHIPS)':
 'GND_B55': CDS_PINID='GND_B55';
NODE_NAME     GF1 B58
 '@SCM_LIB.SCM(SCH_1):PAGE10_I553@PURE_QUANTA.FCONN168_ME1016810202011_SCM(CHIPS)':
 'GND_B58': CDS_PINID='GND_B58';
NODE_NAME     GF1 B61
 '@SCM_LIB.SCM(SCH_1):PAGE10_I553@PURE_QUANTA.FCONN168_ME1016810202011_SCM(CHIPS)':
 'GND_B61': CDS_PINID='GND_B61';
NODE_NAME     GF1 B64
 '@SCM_LIB.SCM(SCH_1):PAGE10_I553@PURE_QUANTA.FCONN168_ME1016810202011_SCM(CHIPS)':
 'GND_B64': CDS_PINID='GND_B64';
NODE_NAME     GF1 B67
 '@SCM_LIB.SCM(SCH_1):PAGE10_I553@PURE_QUANTA.FCONN168_ME1016810202011_SCM(CHIPS)':
 'GND_B67': CDS_PINID='GND_B67';
NODE_NAME     GF1 B70
 '@SCM_LIB.SCM(SCH_1):PAGE10_I553@PURE_QUANTA.FCONN168_ME1016810202011_SCM(CHIPS)':
 'GND_B70': CDS_PINID='GND_B70';
NODE_NAME     GF1 OA3
 '@SCM_LIB.SCM(SCH_1):PAGE10_I553@PURE_QUANTA.FCONN168_ME1016810202011_SCM(CHIPS)':
 'GND_OA3': CDS_PINID='GND_OA3';
NODE_NAME     GF1 OA4
 '@SCM_LIB.SCM(SCH_1):PAGE10_I553@PURE_QUANTA.FCONN168_ME1016810202011_SCM(CHIPS)':
 'GND_OA4': CDS_PINID='GND_OA4';
NODE_NAME     GF1 OA13
 '@SCM_LIB.SCM(SCH_1):PAGE10_I553@PURE_QUANTA.FCONN168_ME1016810202011_SCM(CHIPS)':
 'GND_OA13': CDS_PINID='GND_OA13';
NODE_NAME     GF1 OB4
 '@SCM_LIB.SCM(SCH_1):PAGE10_I553@PURE_QUANTA.FCONN168_ME1016810202011_SCM(CHIPS)':
 'GND_OB4': CDS_PINID='GND_OB4';
NODE_NAME     GF1 OB7
 '@SCM_LIB.SCM(SCH_1):PAGE10_I553@PURE_QUANTA.FCONN168_ME1016810202011_SCM(CHIPS)':
 'GND_OB7': CDS_PINID='GND_OB7';
NODE_NAME     GF1 OB10
 '@SCM_LIB.SCM(SCH_1):PAGE10_I553@PURE_QUANTA.FCONN168_ME1016810202011_SCM(CHIPS)':
 'GND_OB10': CDS_PINID='GND_OB10';
NODE_NAME     R40 1
 '@SCM_LIB.SCM(SCH_1):PAGE11_I171@PURE_QUANTA.Q_RES(CHIPS)':
 'A': CDS_PINID='A';
NODE_NAME     R66 1
 '@SCM_LIB.SCM(SCH_1):PAGE11_I181@PURE_QUANTA.Q_RES(CHIPS)':
 'A': CDS_PINID='A';
NODE_NAME     R63 2
 '@SCM_LIB.SCM(SCH_1):PAGE11_I231@PURE_QUANTA.Q_RES(CHIPS)':
 'B': CDS_PINID='B';
NODE_NAME     R64 2
 '@SCM_LIB.SCM(SCH_1):PAGE11_I233@PURE_QUANTA.Q_RES(CHIPS)':
 'B': CDS_PINID='B';
NODE_NAME     R823 1
 '@SCM_LIB.SCM(SCH_1):PAGE11_I234@PURE_QUANTA.Q_RES(CHIPS)':
 'A': CDS_PINID='A';
NODE_NAME     C21 2
 '@SCM_LIB.SCM(SCH_1):PAGE12_I24@PURE_QUANTA.Q_CAP(CHIPS)':
 'B': CDS_PINID='B';
NODE_NAME     C23 2
 '@SCM_LIB.SCM(SCH_1):PAGE12_I28@PURE_QUANTA.Q_CAP(CHIPS)':
 'B': CDS_PINID='B';
NODE_NAME     R127 1
 '@SCM_LIB.SCM(SCH_1):PAGE12_I46@PURE_QUANTA.Q_RES(CHIPS)':
 'A': CDS_PINID='A';
NODE_NAME     R118 1
 '@SCM_LIB.SCM(SCH_1):PAGE12_I53@PURE_QUANTA.Q_RES(CHIPS)':
 'A': CDS_PINID='A';
NODE_NAME     R820 2
 '@SCM_LIB.SCM(SCH_1):PAGE12_I390@PURE_QUANTA.Q_RES(CHIPS)':
 'B': CDS_PINID='B';
NODE_NAME     R819 2
 '@SCM_LIB.SCM(SCH_1):PAGE12_I391@PURE_QUANTA.Q_RES(CHIPS)':
 'B': CDS_PINID='B';
NODE_NAME     R818 2
 '@SCM_LIB.SCM(SCH_1):PAGE12_I392@PURE_QUANTA.Q_RES(CHIPS)':
 'B': CDS_PINID='B';
NODE_NAME     R817 2
 '@SCM_LIB.SCM(SCH_1):PAGE12_I393@PURE_QUANTA.Q_RES(CHIPS)':
 'B': CDS_PINID='B';
NODE_NAME     C30 2
 '@SCM_LIB.SCM(SCH_1):PAGE13_I29@PURE_QUANTA.Q_CAP(CHIPS)':
 'B': CDS_PINID='B';
NODE_NAME     C31 2
 '@SCM_LIB.SCM(SCH_1):PAGE13_I30@PURE_QUANTA.Q_CAP(CHIPS)':
 'B': CDS_PINID='B';
NODE_NAME     C32 2
 '@SCM_LIB.SCM(SCH_1):PAGE13_I31@PURE_QUANTA.Q_CAP(CHIPS)':
 'B': CDS_PINID='B';
NODE_NAME     C33 2
 '@SCM_LIB.SCM(SCH_1):PAGE13_I32@PURE_QUANTA.Q_CAP(CHIPS)':
 'B': CDS_PINID='B';
NODE_NAME     R273 2
 '@SCM_LIB.SCM(SCH_1):PAGE13_I340@PURE_QUANTA.Q_RES(CHIPS)':
 'B': CDS_PINID='B';
NODE_NAME     R684 2
 '@SCM_LIB.SCM(SCH_1):PAGE14_I163@PURE_QUANTA.Q_RES(CHIPS)':
 'B': CDS_PINID='B';
NODE_NAME     R685 2
 '@SCM_LIB.SCM(SCH_1):PAGE14_I165@PURE_QUANTA.Q_RES(CHIPS)':
 'B': CDS_PINID='B';
NODE_NAME     C35 2
 '@SCM_LIB.SCM(SCH_1):PAGE15_I14@PURE_QUANTA.Q_CAP(CHIPS)':
 'B': CDS_PINID='B';
NODE_NAME     C36 2
 '@SCM_LIB.SCM(SCH_1):PAGE15_I16@PURE_QUANTA.Q_CAP(CHIPS)':
 'B': CDS_PINID='B';
NODE_NAME     R209 2
 '@SCM_LIB.SCM(SCH_1):PAGE15_I19@PURE_QUANTA.Q_RES(CHIPS)':
 'B': CDS_PINID='B';
NODE_NAME     C37 2
 '@SCM_LIB.SCM(SCH_1):PAGE15_I24@PURE_QUANTA.Q_CAP(CHIPS)':
 'B': CDS_PINID='B';
NODE_NAME     C38 2
 '@SCM_LIB.SCM(SCH_1):PAGE15_I36@PURE_QUANTA.Q_CAP(CHIPS)':
 'B': CDS_PINID='B';
NODE_NAME     C39 2
 '@SCM_LIB.SCM(SCH_1):PAGE15_I37@PURE_QUANTA.Q_CAP(CHIPS)':
 'B': CDS_PINID='B';
NODE_NAME     OSC1 2
 '@SCM_LIB.SCM(SCH_1):PAGE15_I39@PURE_QUANTA.OSC4_7X25000018(CHIPS)':
 'GND': CDS_PINID='GND';
NODE_NAME     R210 1
 '@SCM_LIB.SCM(SCH_1):PAGE15_I47@PURE_QUANTA.Q_RES(CHIPS)':
 'A': CDS_PINID='A';
NODE_NAME     C41 2
 '@SCM_LIB.SCM(SCH_1):PAGE15_I68@PURE_QUANTA.Q_CAP(CHIPS)':
 'B': CDS_PINID='B';
NODE_NAME     C45 2
 '@SCM_LIB.SCM(SCH_1):PAGE15_I89@PURE_QUANTA.Q_CAP(CHIPS)':
 'B': CDS_PINID='B';
NODE_NAME     C42 2
 '@SCM_LIB.SCM(SCH_1):PAGE15_I117@PURE_QUANTA.Q_CAP(CHIPS)':
 'B': CDS_PINID='B';
NODE_NAME     C43 2
 '@SCM_LIB.SCM(SCH_1):PAGE15_I119@PURE_QUANTA.Q_CAP(CHIPS)':
 'B': CDS_PINID='B';
NODE_NAME     R25 2
 '@SCM_LIB.SCM(SCH_1):PAGE15_I149@PURE_QUANTA.Q_RES(CHIPS)':
 'B': CDS_PINID='B';
NODE_NAME     R23 2
 '@SCM_LIB.SCM(SCH_1):PAGE15_I150@PURE_QUANTA.Q_RES(CHIPS)':
 'B': CDS_PINID='B';
NODE_NAME     R22 2
 '@SCM_LIB.SCM(SCH_1):PAGE15_I151@PURE_QUANTA.Q_RES(CHIPS)':
 'B': CDS_PINID='B';
NODE_NAME     C275 2
 '@SCM_LIB.SCM(SCH_1):PAGE15_I180@PURE_QUANTA.Q_CAP(CHIPS)':
 'B': CDS_PINID='B';
NODE_NAME     R778 2
 '@SCM_LIB.SCM(SCH_1):PAGE15_I181@PURE_QUANTA.Q_RES(CHIPS)':
 'B': CDS_PINID='B';
NODE_NAME     R776 2
 '@SCM_LIB.SCM(SCH_1):PAGE15_I184@PURE_QUANTA.Q_RES(CHIPS)':
 'B': CDS_PINID='B';
NODE_NAME     C290 2
 '@SCM_LIB.SCM(SCH_1):PAGE15_I201@PURE_QUANTA.Q_CAP(CHIPS)':
 'B': CDS_PINID='B';
NODE_NAME     R786 2
 '@SCM_LIB.SCM(SCH_1):PAGE15_I203@PURE_QUANTA.Q_RES(CHIPS)':
 'B': CDS_PINID='B';
NODE_NAME     C295 2
 '@SCM_LIB.SCM(SCH_1):PAGE15_I207@PURE_QUANTA.Q_CAP(CHIPS)':
 'B': CDS_PINID='B';
NODE_NAME     R788 2
 '@SCM_LIB.SCM(SCH_1):PAGE15_I211@PURE_QUANTA.Q_RES(CHIPS)':
 'B': CDS_PINID='B';
NODE_NAME     C299 2
 '@SCM_LIB.SCM(SCH_1):PAGE15_I215@PURE_QUANTA.Q_CAP(CHIPS)':
 'B': CDS_PINID='B';
NODE_NAME     R790 2
 '@SCM_LIB.SCM(SCH_1):PAGE15_I220@PURE_QUANTA.Q_RES(CHIPS)':
 'B': CDS_PINID='B';
NODE_NAME     C303 2
 '@SCM_LIB.SCM(SCH_1):PAGE15_I235@PURE_QUANTA.Q_CAP(CHIPS)':
 'B': CDS_PINID='B';
NODE_NAME     R792 2
 '@SCM_LIB.SCM(SCH_1):PAGE15_I236@PURE_QUANTA.Q_RES(CHIPS)':
 'B': CDS_PINID='B';
NODE_NAME     C307 2
 '@SCM_LIB.SCM(SCH_1):PAGE15_I240@PURE_QUANTA.Q_CAP(CHIPS)':
 'B': CDS_PINID='B';
NODE_NAME     R794 2
 '@SCM_LIB.SCM(SCH_1):PAGE15_I242@PURE_QUANTA.Q_RES(CHIPS)':
 'B': CDS_PINID='B';
NODE_NAME     C309 2
 '@SCM_LIB.SCM(SCH_1):PAGE15_I247@PURE_QUANTA.Q_CAP(CHIPS)':
 'B': CDS_PINID='B';
NODE_NAME     C311 2
 '@SCM_LIB.SCM(SCH_1):PAGE15_I256@PURE_QUANTA.Q_CAP(CHIPS)':
 'B': CDS_PINID='B';
NODE_NAME     C314 2
 '@SCM_LIB.SCM(SCH_1):PAGE15_I259@PURE_QUANTA.Q_CAP(CHIPS)':
 'B': CDS_PINID='B';
NODE_NAME     R798 2
 '@SCM_LIB.SCM(SCH_1):PAGE15_I262@PURE_QUANTA.Q_RES(CHIPS)':
 'B': CDS_PINID='B';
NODE_NAME     C55 2
 '@SCM_LIB.SCM(SCH_1):PAGE16_I23@PURE_QUANTA.Q_CAP(CHIPS)':
 'B': CDS_PINID='B';
NODE_NAME     C52 2
 '@SCM_LIB.SCM(SCH_1):PAGE16_I31@PURE_QUANTA.Q_CAP(CHIPS)':
 'B': CDS_PINID='B';
NODE_NAME     C54 2
 '@SCM_LIB.SCM(SCH_1):PAGE16_I32@PURE_QUANTA.Q_CAP(CHIPS)':
 'B': CDS_PINID='B';
NODE_NAME     C56 2
 '@SCM_LIB.SCM(SCH_1):PAGE16_I33@PURE_QUANTA.Q_CAP(CHIPS)':
 'B': CDS_PINID='B';
NODE_NAME     C63 2
 '@SCM_LIB.SCM(SCH_1):PAGE16_I46@PURE_QUANTA.Q_CAP(CHIPS)':
 'B': CDS_PINID='B';
NODE_NAME     C67 2
 '@SCM_LIB.SCM(SCH_1):PAGE16_I48@PURE_QUANTA.Q_CAP(CHIPS)':
 'B': CDS_PINID='B';
NODE_NAME     C71 2
 '@SCM_LIB.SCM(SCH_1):PAGE16_I49@PURE_QUANTA.Q_CAP(CHIPS)':
 'B': CDS_PINID='B';
NODE_NAME     C73 2
 '@SCM_LIB.SCM(SCH_1):PAGE16_I51@PURE_QUANTA.Q_CAP(CHIPS)':
 'B': CDS_PINID='B';
NODE_NAME     C58 2
 '@SCM_LIB.SCM(SCH_1):PAGE16_I52@PURE_QUANTA.Q_CAP(CHIPS)':
 'B': CDS_PINID='B';
NODE_NAME     C62 2
 '@SCM_LIB.SCM(SCH_1):PAGE16_I53@PURE_QUANTA.Q_CAP(CHIPS)':
 'B': CDS_PINID='B';
NODE_NAME     C66 2
 '@SCM_LIB.SCM(SCH_1):PAGE16_I54@PURE_QUANTA.Q_CAP(CHIPS)':
 'B': CDS_PINID='B';
NODE_NAME     C61 2
 '@SCM_LIB.SCM(SCH_1):PAGE16_I55@PURE_QUANTA.Q_CAP(CHIPS)':
 'B': CDS_PINID='B';
NODE_NAME     C70 2
 '@SCM_LIB.SCM(SCH_1):PAGE16_I57@PURE_QUANTA.Q_CAP(CHIPS)':
 'B': CDS_PINID='B';
NODE_NAME     C72 2
 '@SCM_LIB.SCM(SCH_1):PAGE16_I58@PURE_QUANTA.Q_CAP(CHIPS)':
 'B': CDS_PINID='B';
NODE_NAME     C69 2
 '@SCM_LIB.SCM(SCH_1):PAGE16_I59@PURE_QUANTA.Q_CAP(CHIPS)':
 'B': CDS_PINID='B';
NODE_NAME     C74 2
 '@SCM_LIB.SCM(SCH_1):PAGE16_I66@PURE_QUANTA.Q_CAP(CHIPS)':
 'B': CDS_PINID='B';
NODE_NAME     C59 2
 '@SCM_LIB.SCM(SCH_1):PAGE16_I79@PURE_QUANTA.Q_CAP(CHIPS)':
 'B': CDS_PINID='B';
NODE_NAME     C64 2
 '@SCM_LIB.SCM(SCH_1):PAGE16_I81@PURE_QUANTA.Q_CAP(CHIPS)':
 'B': CDS_PINID='B';
NODE_NAME     C68 2
 '@SCM_LIB.SCM(SCH_1):PAGE16_I82@PURE_QUANTA.Q_CAP(CHIPS)':
 'B': CDS_PINID='B';
NODE_NAME     R234 1
 '@SCM_LIB.SCM(SCH_1):PAGE16_I86@PURE_QUANTA.Q_RES(CHIPS)':
 'A': CDS_PINID='A';
NODE_NAME     R233 1
 '@SCM_LIB.SCM(SCH_1):PAGE16_I87@PURE_QUANTA.Q_RES(CHIPS)':
 'A': CDS_PINID='A';
NODE_NAME     C75 2
 '@SCM_LIB.SCM(SCH_1):PAGE16_I93@PURE_QUANTA.Q_CAP(CHIPS)':
 'B': CDS_PINID='B';
NODE_NAME     C77 2
 '@SCM_LIB.SCM(SCH_1):PAGE16_I100@PURE_QUANTA.Q_CAP(CHIPS)':
 'B': CDS_PINID='B';
NODE_NAME     C83 2
 '@SCM_LIB.SCM(SCH_1):PAGE16_I106@PURE_QUANTA.Q_CAP(CHIPS)':
 'B': CDS_PINID='B';
NODE_NAME     C89 2
 '@SCM_LIB.SCM(SCH_1):PAGE16_I118@PURE_QUANTA.Q_CAP(CHIPS)':
 'B': CDS_PINID='B';
NODE_NAME     C95 2
 '@SCM_LIB.SCM(SCH_1):PAGE16_I119@PURE_QUANTA.Q_CAP(CHIPS)':
 'B': CDS_PINID='B';
NODE_NAME     C85 2
 '@SCM_LIB.SCM(SCH_1):PAGE16_I120@PURE_QUANTA.Q_CAP(CHIPS)':
 'B': CDS_PINID='B';
NODE_NAME     C88 2
 '@SCM_LIB.SCM(SCH_1):PAGE16_I123@PURE_QUANTA.Q_CAP(CHIPS)':
 'B': CDS_PINID='B';
NODE_NAME     C94 2
 '@SCM_LIB.SCM(SCH_1):PAGE16_I124@PURE_QUANTA.Q_CAP(CHIPS)':
 'B': CDS_PINID='B';
NODE_NAME     C102 2
 '@SCM_LIB.SCM(SCH_1):PAGE16_I126@PURE_QUANTA.Q_CAP(CHIPS)':
 'B': CDS_PINID='B';
NODE_NAME     C106 2
 '@SCM_LIB.SCM(SCH_1):PAGE16_I127@PURE_QUANTA.Q_CAP(CHIPS)':
 'B': CDS_PINID='B';
NODE_NAME     C111 2
 '@SCM_LIB.SCM(SCH_1):PAGE16_I128@PURE_QUANTA.Q_CAP(CHIPS)':
 'B': CDS_PINID='B';
NODE_NAME     C116 2
 '@SCM_LIB.SCM(SCH_1):PAGE16_I129@PURE_QUANTA.Q_CAP(CHIPS)':
 'B': CDS_PINID='B';
NODE_NAME     C121 2
 '@SCM_LIB.SCM(SCH_1):PAGE16_I131@PURE_QUANTA.Q_CAP(CHIPS)':
 'B': CDS_PINID='B';
NODE_NAME     C101 2
 '@SCM_LIB.SCM(SCH_1):PAGE16_I132@PURE_QUANTA.Q_CAP(CHIPS)':
 'B': CDS_PINID='B';
NODE_NAME     C110 2
 '@SCM_LIB.SCM(SCH_1):PAGE16_I133@PURE_QUANTA.Q_CAP(CHIPS)':
 'B': CDS_PINID='B';
NODE_NAME     C115 2
 '@SCM_LIB.SCM(SCH_1):PAGE16_I135@PURE_QUANTA.Q_CAP(CHIPS)':
 'B': CDS_PINID='B';
NODE_NAME     C126 2
 '@SCM_LIB.SCM(SCH_1):PAGE16_I143@PURE_QUANTA.Q_CAP(CHIPS)':
 'B': CDS_PINID='B';
NODE_NAME     C87 2
 '@SCM_LIB.SCM(SCH_1):PAGE16_I147@PURE_QUANTA.Q_CAP(CHIPS)':
 'B': CDS_PINID='B';
NODE_NAME     C93 2
 '@SCM_LIB.SCM(SCH_1):PAGE16_I148@PURE_QUANTA.Q_CAP(CHIPS)':
 'B': CDS_PINID='B';
NODE_NAME     C86 2
 '@SCM_LIB.SCM(SCH_1):PAGE16_I149@PURE_QUANTA.Q_CAP(CHIPS)':
 'B': CDS_PINID='B';
NODE_NAME     C92 2
 '@SCM_LIB.SCM(SCH_1):PAGE16_I150@PURE_QUANTA.Q_CAP(CHIPS)':
 'B': CDS_PINID='B';
NODE_NAME     C91 2
 '@SCM_LIB.SCM(SCH_1):PAGE16_I151@PURE_QUANTA.Q_CAP(CHIPS)':
 'B': CDS_PINID='B';
NODE_NAME     C100 2
 '@SCM_LIB.SCM(SCH_1):PAGE16_I152@PURE_QUANTA.Q_CAP(CHIPS)':
 'B': CDS_PINID='B';
NODE_NAME     C105 2
 '@SCM_LIB.SCM(SCH_1):PAGE16_I153@PURE_QUANTA.Q_CAP(CHIPS)':
 'B': CDS_PINID='B';
NODE_NAME     C99 2
 '@SCM_LIB.SCM(SCH_1):PAGE16_I154@PURE_QUANTA.Q_CAP(CHIPS)':
 'B': CDS_PINID='B';
NODE_NAME     C104 2
 '@SCM_LIB.SCM(SCH_1):PAGE16_I155@PURE_QUANTA.Q_CAP(CHIPS)':
 'B': CDS_PINID='B';
NODE_NAME     C109 2
 '@SCM_LIB.SCM(SCH_1):PAGE16_I156@PURE_QUANTA.Q_CAP(CHIPS)':
 'B': CDS_PINID='B';
NODE_NAME     C108 2
 '@SCM_LIB.SCM(SCH_1):PAGE16_I157@PURE_QUANTA.Q_CAP(CHIPS)':
 'B': CDS_PINID='B';
NODE_NAME     C114 2
 '@SCM_LIB.SCM(SCH_1):PAGE16_I158@PURE_QUANTA.Q_CAP(CHIPS)':
 'B': CDS_PINID='B';
NODE_NAME     C119 2
 '@SCM_LIB.SCM(SCH_1):PAGE16_I159@PURE_QUANTA.Q_CAP(CHIPS)':
 'B': CDS_PINID='B';
NODE_NAME     C118 2
 '@SCM_LIB.SCM(SCH_1):PAGE16_I162@PURE_QUANTA.Q_CAP(CHIPS)':
 'B': CDS_PINID='B';
NODE_NAME     C98 2
 '@SCM_LIB.SCM(SCH_1):PAGE16_I163@PURE_QUANTA.Q_CAP(CHIPS)':
 'B': CDS_PINID='B';
NODE_NAME     C103 2
 '@SCM_LIB.SCM(SCH_1):PAGE16_I164@PURE_QUANTA.Q_CAP(CHIPS)':
 'B': CDS_PINID='B';
NODE_NAME     C107 2
 '@SCM_LIB.SCM(SCH_1):PAGE16_I165@PURE_QUANTA.Q_CAP(CHIPS)':
 'B': CDS_PINID='B';
NODE_NAME     C112 2
 '@SCM_LIB.SCM(SCH_1):PAGE16_I166@PURE_QUANTA.Q_CAP(CHIPS)':
 'B': CDS_PINID='B';
NODE_NAME     C117 2
 '@SCM_LIB.SCM(SCH_1):PAGE16_I167@PURE_QUANTA.Q_CAP(CHIPS)':
 'B': CDS_PINID='B';
NODE_NAME     C122 2
 '@SCM_LIB.SCM(SCH_1):PAGE16_I168@PURE_QUANTA.Q_CAP(CHIPS)':
 'B': CDS_PINID='B';
NODE_NAME     C124 2
 '@SCM_LIB.SCM(SCH_1):PAGE16_I169@PURE_QUANTA.Q_CAP(CHIPS)':
 'B': CDS_PINID='B';
NODE_NAME     C123 2
 '@SCM_LIB.SCM(SCH_1):PAGE16_I171@PURE_QUANTA.Q_CAP(CHIPS)':
 'B': CDS_PINID='B';
NODE_NAME     C127 2
 '@SCM_LIB.SCM(SCH_1):PAGE16_I173@PURE_QUANTA.Q_CAP(CHIPS)':
 'B': CDS_PINID='B';
NODE_NAME     C129 2
 '@SCM_LIB.SCM(SCH_1):PAGE16_I174@PURE_QUANTA.Q_CAP(CHIPS)':
 'B': CDS_PINID='B';
NODE_NAME     C84 2
 '@SCM_LIB.SCM(SCH_1):PAGE16_I179@PURE_QUANTA.Q_CAP(CHIPS)':
 'B': CDS_PINID='B';
NODE_NAME     C82 2
 '@SCM_LIB.SCM(SCH_1):PAGE16_I180@PURE_QUANTA.Q_CAP(CHIPS)':
 'B': CDS_PINID='B';
NODE_NAME     C76 2
 '@SCM_LIB.SCM(SCH_1):PAGE16_I183@PURE_QUANTA.Q_CAP(CHIPS)':
 'B': CDS_PINID='B';
NODE_NAME     R235 1
 '@SCM_LIB.SCM(SCH_1):PAGE16_I187@PURE_QUANTA.Q_RES(CHIPS)':
 'A': CDS_PINID='A';
NODE_NAME     C140 2
 '@SCM_LIB.SCM(SCH_1):PAGE17_I97@PURE_QUANTA.Q_CAP(CHIPS)':
 'B': CDS_PINID='B';
NODE_NAME     C139 2
 '@SCM_LIB.SCM(SCH_1):PAGE17_I98@PURE_QUANTA.Q_CAP(CHIPS)':
 'B': CDS_PINID='B';
NODE_NAME     C133 1
 '@SCM_LIB.SCM(SCH_1):PAGE17_I104@PURE_QUANTA.Q_CAP(CHIPS)':
 'A': CDS_PINID='A';
NODE_NAME     C134 1
 '@SCM_LIB.SCM(SCH_1):PAGE17_I106@PURE_QUANTA.Q_CAP(CHIPS)':
 'A': CDS_PINID='A';
NODE_NAME     C135 1
 '@SCM_LIB.SCM(SCH_1):PAGE17_I107@PURE_QUANTA.Q_CAP(CHIPS)':
 'A': CDS_PINID='A';
NODE_NAME     C136 1
 '@SCM_LIB.SCM(SCH_1):PAGE17_I110@PURE_QUANTA.Q_CAP(CHIPS)':
 'A': CDS_PINID='A';
NODE_NAME     C49 2
 '@SCM_LIB.SCM(SCH_1):PAGE17_I118@PURE_QUANTA.Q_CAP(CHIPS)':
 'B': CDS_PINID='B';
NODE_NAME     C46 2
 '@SCM_LIB.SCM(SCH_1):PAGE17_I122@PURE_QUANTA.Q_CAP(CHIPS)':
 'B': CDS_PINID='B';
NODE_NAME     C50 2
 '@SCM_LIB.SCM(SCH_1):PAGE17_I126@PURE_QUANTA.Q_CAP(CHIPS)':
 'B': CDS_PINID='B';
NODE_NAME     C47 2
 '@SCM_LIB.SCM(SCH_1):PAGE17_I128@PURE_QUANTA.Q_CAP(CHIPS)':
 'B': CDS_PINID='B';
NODE_NAME     C57 2
 '@SCM_LIB.SCM(SCH_1):PAGE17_I133@PURE_QUANTA.Q_CAP(CHIPS)':
 'B': CDS_PINID='B';
NODE_NAME     C53 2
 '@SCM_LIB.SCM(SCH_1):PAGE17_I135@PURE_QUANTA.Q_CAP(CHIPS)':
 'B': CDS_PINID='B';
NODE_NAME     C65 2
 '@SCM_LIB.SCM(SCH_1):PAGE17_I139@PURE_QUANTA.Q_CAP(CHIPS)':
 'B': CDS_PINID='B';
NODE_NAME     C60 2
 '@SCM_LIB.SCM(SCH_1):PAGE17_I141@PURE_QUANTA.Q_CAP(CHIPS)':
 'B': CDS_PINID='B';
NODE_NAME     C51 2
 '@SCM_LIB.SCM(SCH_1):PAGE17_I145@PURE_QUANTA.Q_CAP(CHIPS)':
 'B': CDS_PINID='B';
NODE_NAME     C48 2
 '@SCM_LIB.SCM(SCH_1):PAGE17_I148@PURE_QUANTA.Q_CAP(CHIPS)':
 'B': CDS_PINID='B';
NODE_NAME     C81 2
 '@SCM_LIB.SCM(SCH_1):PAGE17_I151@PURE_QUANTA.Q_CAP(CHIPS)':
 'B': CDS_PINID='B';
NODE_NAME     C80 2
 '@SCM_LIB.SCM(SCH_1):PAGE17_I153@PURE_QUANTA.Q_CAP(CHIPS)':
 'B': CDS_PINID='B';
NODE_NAME     C79 2
 '@SCM_LIB.SCM(SCH_1):PAGE17_I157@PURE_QUANTA.Q_CAP(CHIPS)':
 'B': CDS_PINID='B';
NODE_NAME     C78 2
 '@SCM_LIB.SCM(SCH_1):PAGE17_I160@PURE_QUANTA.Q_CAP(CHIPS)':
 'B': CDS_PINID='B';
NODE_NAME     C130 2
 '@SCM_LIB.SCM(SCH_1):PAGE17_I163@PURE_QUANTA.Q_CAP(CHIPS)':
 'B': CDS_PINID='B';
NODE_NAME     C128 2
 '@SCM_LIB.SCM(SCH_1):PAGE17_I165@PURE_QUANTA.Q_CAP(CHIPS)':
 'B': CDS_PINID='B';
NODE_NAME     C97 2
 '@SCM_LIB.SCM(SCH_1):PAGE17_I169@PURE_QUANTA.Q_CAP(CHIPS)':
 'B': CDS_PINID='B';
NODE_NAME     C90 2
 '@SCM_LIB.SCM(SCH_1):PAGE17_I173@PURE_QUANTA.Q_CAP(CHIPS)':
 'B': CDS_PINID='B';
NODE_NAME     C96 2
 '@SCM_LIB.SCM(SCH_1):PAGE17_I178@PURE_QUANTA.Q_CAP(CHIPS)':
 'B': CDS_PINID='B';
NODE_NAME     C224 2
 '@SCM_LIB.SCM(SCH_1):PAGE17_I180@PURE_QUANTA.Q_CAP(CHIPS)':
 'B': CDS_PINID='B';
NODE_NAME     Q10 S
 '@SCM_LIB.SCM(SCH_1):PAGE17_I227@PURE_QUANTA.MOSFET_N_GSD(CHIPS)':
 'SOURCE': CDS_PINID='SOURCE';
NODE_NAME     C273 2
 '@SCM_LIB.SCM(SCH_1):PAGE17_I234@PURE_QUANTA.Q_CAP(CHIPS)':
 'B': CDS_PINID='B';
NODE_NAME     C270 2
 '@SCM_LIB.SCM(SCH_1):PAGE17_I239@PURE_QUANTA.Q_CAP(CHIPS)':
 'B': CDS_PINID='B';
NODE_NAME     C284 2
 '@SCM_LIB.SCM(SCH_1):PAGE17_I250@PURE_QUANTA.Q_CAP(CHIPS)':
 'B': CDS_PINID='B';
NODE_NAME     C282 2
 '@SCM_LIB.SCM(SCH_1):PAGE17_I252@PURE_QUANTA.Q_CAP(CHIPS)':
 'B': CDS_PINID='B';
NODE_NAME     C277 2
 '@SCM_LIB.SCM(SCH_1):PAGE17_I253@PURE_QUANTA.Q_CAP(CHIPS)':
 'B': CDS_PINID='B';
NODE_NAME     C279 2
 '@SCM_LIB.SCM(SCH_1):PAGE17_I255@PURE_QUANTA.Q_CAP(CHIPS)':
 'B': CDS_PINID='B';
NODE_NAME     R493 2
 '@SCM_LIB.SCM(SCH_1):PAGE17_I284@PURE_QUANTA.Q_RES(CHIPS)':
 'B': CDS_PINID='B';
NODE_NAME     U5 A1
 '@SCM_LIB.SCM(SCH_1):PAGE17_I286@PURE_QUANTA.AST2600A3GP(CHIPS)':
 'GND_A1': CDS_PINID='GND_A1';
NODE_NAME     U5 A5
 '@SCM_LIB.SCM(SCH_1):PAGE17_I286@PURE_QUANTA.AST2600A3GP(CHIPS)':
 'GND_A5': CDS_PINID='GND_A5';
NODE_NAME     U5 A26
 '@SCM_LIB.SCM(SCH_1):PAGE17_I286@PURE_QUANTA.AST2600A3GP(CHIPS)':
 'GND_A26': CDS_PINID='GND_A26';
NODE_NAME     U5 AA1
 '@SCM_LIB.SCM(SCH_1):PAGE17_I286@PURE_QUANTA.AST2600A3GP(CHIPS)':
 'GND_AA1': CDS_PINID='GND_AA1';
NODE_NAME     U5 AA3
 '@SCM_LIB.SCM(SCH_1):PAGE17_I286@PURE_QUANTA.AST2600A3GP(CHIPS)':
 'GND_AA3': CDS_PINID='GND_AA3';
NODE_NAME     U5 AA6
 '@SCM_LIB.SCM(SCH_1):PAGE17_I286@PURE_QUANTA.AST2600A3GP(CHIPS)':
 'GND_AA6': CDS_PINID='GND_AA6';
NODE_NAME     U5 AA7
 '@SCM_LIB.SCM(SCH_1):PAGE17_I286@PURE_QUANTA.AST2600A3GP(CHIPS)':
 'GND_AA7': CDS_PINID='GND_AA7';
NODE_NAME     U5 AA8
 '@SCM_LIB.SCM(SCH_1):PAGE17_I286@PURE_QUANTA.AST2600A3GP(CHIPS)':
 'GND_AA8': CDS_PINID='GND_AA8';
NODE_NAME     U5 AA10
 '@SCM_LIB.SCM(SCH_1):PAGE17_I286@PURE_QUANTA.AST2600A3GP(CHIPS)':
 'GND_AA10': CDS_PINID='GND_AA10';
NODE_NAME     U5 AA14
 '@SCM_LIB.SCM(SCH_1):PAGE17_I286@PURE_QUANTA.AST2600A3GP(CHIPS)':
 'GND_AA14': CDS_PINID='GND_AA14';
NODE_NAME     U5 AA15
 '@SCM_LIB.SCM(SCH_1):PAGE17_I286@PURE_QUANTA.AST2600A3GP(CHIPS)':
 'GND_AA15': CDS_PINID='GND_AA15';
NODE_NAME     U5 AA19
 '@SCM_LIB.SCM(SCH_1):PAGE17_I286@PURE_QUANTA.AST2600A3GP(CHIPS)':
 'GND_AA19': CDS_PINID='GND_AA19';
NODE_NAME     U5 AA20
 '@SCM_LIB.SCM(SCH_1):PAGE17_I286@PURE_QUANTA.AST2600A3GP(CHIPS)':
 'GND_AA20': CDS_PINID='GND_AA20';
NODE_NAME     U5 AA22
 '@SCM_LIB.SCM(SCH_1):PAGE17_I286@PURE_QUANTA.AST2600A3GP(CHIPS)':
 'GND_AA22': CDS_PINID='GND_AA22';
NODE_NAME     U5 AC2
 '@SCM_LIB.SCM(SCH_1):PAGE17_I286@PURE_QUANTA.AST2600A3GP(CHIPS)':
 'GND_AC2': CDS_PINID='GND_AC2';
NODE_NAME     U5 AC6
 '@SCM_LIB.SCM(SCH_1):PAGE17_I286@PURE_QUANTA.AST2600A3GP(CHIPS)':
 'GND_AC6': CDS_PINID='GND_AC6';
NODE_NAME     U5 AC25
 '@SCM_LIB.SCM(SCH_1):PAGE17_I286@PURE_QUANTA.AST2600A3GP(CHIPS)':
 'GND_AC25': CDS_PINID='GND_AC25';
NODE_NAME     U5 AD1
 '@SCM_LIB.SCM(SCH_1):PAGE17_I286@PURE_QUANTA.AST2600A3GP(CHIPS)':
 'GND_AD1': CDS_PINID='GND_AD1';
NODE_NAME     U5 AD4
 '@SCM_LIB.SCM(SCH_1):PAGE17_I286@PURE_QUANTA.AST2600A3GP(CHIPS)':
 'GND_AD4': CDS_PINID='GND_AD4';
NODE_NAME     U5 AE3
 '@SCM_LIB.SCM(SCH_1):PAGE17_I286@PURE_QUANTA.AST2600A3GP(CHIPS)':
 'GND_AE3': CDS_PINID='GND_AE3';
NODE_NAME     U5 AE6
 '@SCM_LIB.SCM(SCH_1):PAGE17_I286@PURE_QUANTA.AST2600A3GP(CHIPS)':
 'GND_AE6': CDS_PINID='GND_AE6';
NODE_NAME     U5 AE9
 '@SCM_LIB.SCM(SCH_1):PAGE17_I286@PURE_QUANTA.AST2600A3GP(CHIPS)':
 'GND_AE9': CDS_PINID='GND_AE9';
NODE_NAME     U5 AE13
 '@SCM_LIB.SCM(SCH_1):PAGE17_I286@PURE_QUANTA.AST2600A3GP(CHIPS)':
 'GND_AE13': CDS_PINID='GND_AE13';
NODE_NAME     U5 AE17
 '@SCM_LIB.SCM(SCH_1):PAGE17_I286@PURE_QUANTA.AST2600A3GP(CHIPS)':
 'GND_AE17': CDS_PINID='GND_AE17';
NODE_NAME     U5 AE20
 '@SCM_LIB.SCM(SCH_1):PAGE17_I286@PURE_QUANTA.AST2600A3GP(CHIPS)':
 'GND_AE20': CDS_PINID='GND_AE20';
NODE_NAME     U5 AE23
 '@SCM_LIB.SCM(SCH_1):PAGE17_I286@PURE_QUANTA.AST2600A3GP(CHIPS)':
 'GND_AE23': CDS_PINID='GND_AE23';
NODE_NAME     U5 AF1
 '@SCM_LIB.SCM(SCH_1):PAGE17_I286@PURE_QUANTA.AST2600A3GP(CHIPS)':
 'GND_AF1': CDS_PINID='GND_AF1';
NODE_NAME     U5 AF4
 '@SCM_LIB.SCM(SCH_1):PAGE17_I286@PURE_QUANTA.AST2600A3GP(CHIPS)':
 'GND_AF4': CDS_PINID='GND_AF4';
NODE_NAME     U5 AF26
 '@SCM_LIB.SCM(SCH_1):PAGE17_I286@PURE_QUANTA.AST2600A3GP(CHIPS)':
 'GND_AF26': CDS_PINID='GND_AF26';
NODE_NAME     U5 B5
 '@SCM_LIB.SCM(SCH_1):PAGE17_I286@PURE_QUANTA.AST2600A3GP(CHIPS)':
 'GND_B5': CDS_PINID='GND_B5';
NODE_NAME     U5 B11
 '@SCM_LIB.SCM(SCH_1):PAGE17_I286@PURE_QUANTA.AST2600A3GP(CHIPS)':
 'GND_B11': CDS_PINID='GND_B11';
NODE_NAME     U5 B15
 '@SCM_LIB.SCM(SCH_1):PAGE17_I286@PURE_QUANTA.AST2600A3GP(CHIPS)':
 'GND_B15': CDS_PINID='GND_B15';
NODE_NAME     U5 B19
 '@SCM_LIB.SCM(SCH_1):PAGE17_I286@PURE_QUANTA.AST2600A3GP(CHIPS)':
 'GND_B19': CDS_PINID='GND_B19';
NODE_NAME     U5 B23
 '@SCM_LIB.SCM(SCH_1):PAGE17_I286@PURE_QUANTA.AST2600A3GP(CHIPS)':
 'GND_B23': CDS_PINID='GND_B23';
NODE_NAME     U5 C3
 '@SCM_LIB.SCM(SCH_1):PAGE17_I286@PURE_QUANTA.AST2600A3GP(CHIPS)':
 'GND_C3': CDS_PINID='GND_C3';
NODE_NAME     U5 D25
 '@SCM_LIB.SCM(SCH_1):PAGE17_I286@PURE_QUANTA.AST2600A3GP(CHIPS)':
 'GND_D25': CDS_PINID='GND_D25';
NODE_NAME     U5 E8
 '@SCM_LIB.SCM(SCH_1):PAGE17_I286@PURE_QUANTA.AST2600A3GP(CHIPS)':
 'GND_E8': CDS_PINID='GND_E8';
NODE_NAME     U5 F6
 '@SCM_LIB.SCM(SCH_1):PAGE17_I286@PURE_QUANTA.AST2600A3GP(CHIPS)':
 'GND_F6': CDS_PINID='GND_F6';
NODE_NAME     U5 F8
 '@SCM_LIB.SCM(SCH_1):PAGE17_I286@PURE_QUANTA.AST2600A3GP(CHIPS)':
 'GND_F8': CDS_PINID='GND_F8';
NODE_NAME     U5 F10
 '@SCM_LIB.SCM(SCH_1):PAGE17_I286@PURE_QUANTA.AST2600A3GP(CHIPS)':
 'GND_F10': CDS_PINID='GND_F10';
NODE_NAME     U5 F12
 '@SCM_LIB.SCM(SCH_1):PAGE17_I286@PURE_QUANTA.AST2600A3GP(CHIPS)':
 'GND_F12': CDS_PINID='GND_F12';
NODE_NAME     U5 F14
 '@SCM_LIB.SCM(SCH_1):PAGE17_I286@PURE_QUANTA.AST2600A3GP(CHIPS)':
 'GND_F14': CDS_PINID='GND_F14';
NODE_NAME     U5 F16
 '@SCM_LIB.SCM(SCH_1):PAGE17_I286@PURE_QUANTA.AST2600A3GP(CHIPS)':
 'GND_F16': CDS_PINID='GND_F16';
NODE_NAME     U5 F17
 '@SCM_LIB.SCM(SCH_1):PAGE17_I286@PURE_QUANTA.AST2600A3GP(CHIPS)':
 'GND_F17': CDS_PINID='GND_F17';
NODE_NAME     U5 F18
 '@SCM_LIB.SCM(SCH_1):PAGE17_I286@PURE_QUANTA.AST2600A3GP(CHIPS)':
 'GND_F18': CDS_PINID='GND_F18';
NODE_NAME     U5 F21
 '@SCM_LIB.SCM(SCH_1):PAGE17_I286@PURE_QUANTA.AST2600A3GP(CHIPS)':
 'GND_F21': CDS_PINID='GND_F21';
NODE_NAME     U5 G2
 '@SCM_LIB.SCM(SCH_1):PAGE17_I286@PURE_QUANTA.AST2600A3GP(CHIPS)':
 'GND_G2': CDS_PINID='GND_G2';
NODE_NAME     U5 G25
 '@SCM_LIB.SCM(SCH_1):PAGE17_I286@PURE_QUANTA.AST2600A3GP(CHIPS)':
 'GND_G25': CDS_PINID='GND_G25';
NODE_NAME     U5 H4
 '@SCM_LIB.SCM(SCH_1):PAGE17_I286@PURE_QUANTA.AST2600A3GP(CHIPS)':
 'GND_H4': CDS_PINID='GND_H4';
NODE_NAME     U5 H9
 '@SCM_LIB.SCM(SCH_1):PAGE17_I286@PURE_QUANTA.AST2600A3GP(CHIPS)':
 'GND_H9': CDS_PINID='GND_H9';
NODE_NAME     U5 H10
 '@SCM_LIB.SCM(SCH_1):PAGE17_I286@PURE_QUANTA.AST2600A3GP(CHIPS)':
 'GND_H10': CDS_PINID='GND_H10';
NODE_NAME     U5 H11
 '@SCM_LIB.SCM(SCH_1):PAGE17_I286@PURE_QUANTA.AST2600A3GP(CHIPS)':
 'GND_H11': CDS_PINID='GND_H11';
NODE_NAME     U5 H13
 '@SCM_LIB.SCM(SCH_1):PAGE17_I286@PURE_QUANTA.AST2600A3GP(CHIPS)':
 'GND_H13': CDS_PINID='GND_H13';
NODE_NAME     U5 J2
 '@SCM_LIB.SCM(SCH_1):PAGE17_I286@PURE_QUANTA.AST2600A3GP(CHIPS)':
 'GND_J2': CDS_PINID='GND_J2';
NODE_NAME     U5 J11
 '@SCM_LIB.SCM(SCH_1):PAGE17_I286@PURE_QUANTA.AST2600A3GP(CHIPS)':
 'GND_J11': CDS_PINID='GND_J11';
NODE_NAME     U5 J13
 '@SCM_LIB.SCM(SCH_1):PAGE17_I286@PURE_QUANTA.AST2600A3GP(CHIPS)':
 'GND_J13': CDS_PINID='GND_J13';
NODE_NAME     U5 J14
 '@SCM_LIB.SCM(SCH_1):PAGE17_I286@PURE_QUANTA.AST2600A3GP(CHIPS)':
 'GND_J14': CDS_PINID='GND_J14';
NODE_NAME     U5 J15
 '@SCM_LIB.SCM(SCH_1):PAGE17_I286@PURE_QUANTA.AST2600A3GP(CHIPS)':
 'GND_J15': CDS_PINID='GND_J15';
NODE_NAME     U5 J16
 '@SCM_LIB.SCM(SCH_1):PAGE17_I286@PURE_QUANTA.AST2600A3GP(CHIPS)':
 'GND_J16': CDS_PINID='GND_J16';
NODE_NAME     U5 J17
 '@SCM_LIB.SCM(SCH_1):PAGE17_I286@PURE_QUANTA.AST2600A3GP(CHIPS)':
 'GND_J17': CDS_PINID='GND_J17';
NODE_NAME     U5 J18
 '@SCM_LIB.SCM(SCH_1):PAGE17_I286@PURE_QUANTA.AST2600A3GP(CHIPS)':
 'GND_J18': CDS_PINID='GND_J18';
NODE_NAME     U5 J19
 '@SCM_LIB.SCM(SCH_1):PAGE17_I286@PURE_QUANTA.AST2600A3GP(CHIPS)':
 'GND_J19': CDS_PINID='GND_J19';
NODE_NAME     U5 K4
 '@SCM_LIB.SCM(SCH_1):PAGE17_I286@PURE_QUANTA.AST2600A3GP(CHIPS)':
 'GND_K4': CDS_PINID='GND_K4';
NODE_NAME     U5 K8
 '@SCM_LIB.SCM(SCH_1):PAGE17_I286@PURE_QUANTA.AST2600A3GP(CHIPS)':
 'GND_K8': CDS_PINID='GND_K8';
NODE_NAME     U5 K9
 '@SCM_LIB.SCM(SCH_1):PAGE17_I286@PURE_QUANTA.AST2600A3GP(CHIPS)':
 'GND_K9': CDS_PINID='GND_K9';
NODE_NAME     U5 K13
 '@SCM_LIB.SCM(SCH_1):PAGE17_I286@PURE_QUANTA.AST2600A3GP(CHIPS)':
 'GND_K13': CDS_PINID='GND_K13';
NODE_NAME     U5 K14
 '@SCM_LIB.SCM(SCH_1):PAGE17_I286@PURE_QUANTA.AST2600A3GP(CHIPS)':
 'GND_K14': CDS_PINID='GND_K14';
NODE_NAME     U5 K15
 '@SCM_LIB.SCM(SCH_1):PAGE17_I286@PURE_QUANTA.AST2600A3GP(CHIPS)':
 'GND_K15': CDS_PINID='GND_K15';
NODE_NAME     U5 K22
 '@SCM_LIB.SCM(SCH_1):PAGE17_I286@PURE_QUANTA.AST2600A3GP(CHIPS)':
 'GND_K22': CDS_PINID='GND_K22';
NODE_NAME     U5 L2
 '@SCM_LIB.SCM(SCH_1):PAGE17_I286@PURE_QUANTA.AST2600A3GP(CHIPS)':
 'GND_L2': CDS_PINID='GND_L2';
NODE_NAME     U5 L8
 '@SCM_LIB.SCM(SCH_1):PAGE17_I286@PURE_QUANTA.AST2600A3GP(CHIPS)':
 'GND_L8': CDS_PINID='GND_L8';
NODE_NAME     U5 L11
 '@SCM_LIB.SCM(SCH_1):PAGE17_I286@PURE_QUANTA.AST2600A3GP(CHIPS)':
 'GND_L11': CDS_PINID='GND_L11';
NODE_NAME     U5 L12
 '@SCM_LIB.SCM(SCH_1):PAGE17_I286@PURE_QUANTA.AST2600A3GP(CHIPS)':
 'GND_L12': CDS_PINID='GND_L12';
NODE_NAME     U5 L15
 '@SCM_LIB.SCM(SCH_1):PAGE17_I286@PURE_QUANTA.AST2600A3GP(CHIPS)':
 'GND_L15': CDS_PINID='GND_L15';
NODE_NAME     U5 L16
 '@SCM_LIB.SCM(SCH_1):PAGE17_I286@PURE_QUANTA.AST2600A3GP(CHIPS)':
 'GND_L16': CDS_PINID='GND_L16';
NODE_NAME     U5 L17
 '@SCM_LIB.SCM(SCH_1):PAGE17_I286@PURE_QUANTA.AST2600A3GP(CHIPS)':
 'GND_L17': CDS_PINID='GND_L17';
NODE_NAME     U5 L18
 '@SCM_LIB.SCM(SCH_1):PAGE17_I286@PURE_QUANTA.AST2600A3GP(CHIPS)':
 'GND_L18': CDS_PINID='GND_L18';
NODE_NAME     U5 L19
 '@SCM_LIB.SCM(SCH_1):PAGE17_I286@PURE_QUANTA.AST2600A3GP(CHIPS)':
 'GND_L19': CDS_PINID='GND_L19';
NODE_NAME     U5 L25
 '@SCM_LIB.SCM(SCH_1):PAGE17_I286@PURE_QUANTA.AST2600A3GP(CHIPS)':
 'GND_L25': CDS_PINID='GND_L25';
NODE_NAME     U5 M4
 '@SCM_LIB.SCM(SCH_1):PAGE17_I286@PURE_QUANTA.AST2600A3GP(CHIPS)':
 'GND_M4': CDS_PINID='GND_M4';
NODE_NAME     U5 M9
 '@SCM_LIB.SCM(SCH_1):PAGE17_I286@PURE_QUANTA.AST2600A3GP(CHIPS)':
 'GND_M9': CDS_PINID='GND_M9';
NODE_NAME     U5 M10
 '@SCM_LIB.SCM(SCH_1):PAGE17_I286@PURE_QUANTA.AST2600A3GP(CHIPS)':
 'GND_M10': CDS_PINID='GND_M10';
NODE_NAME     U5 M12
 '@SCM_LIB.SCM(SCH_1):PAGE17_I286@PURE_QUANTA.AST2600A3GP(CHIPS)':
 'GND_M12': CDS_PINID='GND_M12';
NODE_NAME     U5 M15
 '@SCM_LIB.SCM(SCH_1):PAGE17_I286@PURE_QUANTA.AST2600A3GP(CHIPS)':
 'GND_M15': CDS_PINID='GND_M15';
NODE_NAME     U5 M16
 '@SCM_LIB.SCM(SCH_1):PAGE17_I286@PURE_QUANTA.AST2600A3GP(CHIPS)':
 'GND_M16': CDS_PINID='GND_M16';
NODE_NAME     U5 M17
 '@SCM_LIB.SCM(SCH_1):PAGE17_I286@PURE_QUANTA.AST2600A3GP(CHIPS)':
 'GND_M17': CDS_PINID='GND_M17';
NODE_NAME     U5 M18
 '@SCM_LIB.SCM(SCH_1):PAGE17_I286@PURE_QUANTA.AST2600A3GP(CHIPS)':
 'GND_M18': CDS_PINID='GND_M18';
NODE_NAME     U5 M19
 '@SCM_LIB.SCM(SCH_1):PAGE17_I286@PURE_QUANTA.AST2600A3GP(CHIPS)':
 'GND_M19': CDS_PINID='GND_M19';
NODE_NAME     U5 N2
 '@SCM_LIB.SCM(SCH_1):PAGE17_I286@PURE_QUANTA.AST2600A3GP(CHIPS)':
 'GND_N2': CDS_PINID='GND_N2';
NODE_NAME     U5 N6
 '@SCM_LIB.SCM(SCH_1):PAGE17_I286@PURE_QUANTA.AST2600A3GP(CHIPS)':
 'GND_N6': CDS_PINID='GND_N6';
NODE_NAME     U5 N9
 '@SCM_LIB.SCM(SCH_1):PAGE17_I286@PURE_QUANTA.AST2600A3GP(CHIPS)':
 'GND_N9': CDS_PINID='GND_N9';
NODE_NAME     U5 N10
 '@SCM_LIB.SCM(SCH_1):PAGE17_I286@PURE_QUANTA.AST2600A3GP(CHIPS)':
 'GND_N10': CDS_PINID='GND_N10';
NODE_NAME     U5 N15
 '@SCM_LIB.SCM(SCH_1):PAGE17_I286@PURE_QUANTA.AST2600A3GP(CHIPS)':
 'GND_N15': CDS_PINID='GND_N15';
NODE_NAME     U5 N16
 '@SCM_LIB.SCM(SCH_1):PAGE17_I286@PURE_QUANTA.AST2600A3GP(CHIPS)':
 'GND_N16': CDS_PINID='GND_N16';
NODE_NAME     U5 N17
 '@SCM_LIB.SCM(SCH_1):PAGE17_I286@PURE_QUANTA.AST2600A3GP(CHIPS)':
 'GND_N17': CDS_PINID='GND_N17';
NODE_NAME     U5 N18
 '@SCM_LIB.SCM(SCH_1):PAGE17_I286@PURE_QUANTA.AST2600A3GP(CHIPS)':
 'GND_N18': CDS_PINID='GND_N18';
NODE_NAME     U5 N19
 '@SCM_LIB.SCM(SCH_1):PAGE17_I286@PURE_QUANTA.AST2600A3GP(CHIPS)':
 'GND_N19': CDS_PINID='GND_N19';
NODE_NAME     U5 P4
 '@SCM_LIB.SCM(SCH_1):PAGE17_I286@PURE_QUANTA.AST2600A3GP(CHIPS)':
 'GND_P4': CDS_PINID='GND_P4';
NODE_NAME     U5 P9
 '@SCM_LIB.SCM(SCH_1):PAGE17_I286@PURE_QUANTA.AST2600A3GP(CHIPS)':
 'GND_P9': CDS_PINID='GND_P9';
NODE_NAME     U5 P10
 '@SCM_LIB.SCM(SCH_1):PAGE17_I286@PURE_QUANTA.AST2600A3GP(CHIPS)':
 'GND_P10': CDS_PINID='GND_P10';
NODE_NAME     U5 P15
 '@SCM_LIB.SCM(SCH_1):PAGE17_I286@PURE_QUANTA.AST2600A3GP(CHIPS)':
 'GND_P15': CDS_PINID='GND_P15';
NODE_NAME     U5 P16
 '@SCM_LIB.SCM(SCH_1):PAGE17_I286@PURE_QUANTA.AST2600A3GP(CHIPS)':
 'GND_P16': CDS_PINID='GND_P16';
NODE_NAME     U5 P17
 '@SCM_LIB.SCM(SCH_1):PAGE17_I286@PURE_QUANTA.AST2600A3GP(CHIPS)':
 'GND_P17': CDS_PINID='GND_P17';
NODE_NAME     U5 P18
 '@SCM_LIB.SCM(SCH_1):PAGE17_I286@PURE_QUANTA.AST2600A3GP(CHIPS)':
 'GND_P18': CDS_PINID='GND_P18';
NODE_NAME     U5 P19
 '@SCM_LIB.SCM(SCH_1):PAGE17_I286@PURE_QUANTA.AST2600A3GP(CHIPS)':
 'GND_P19': CDS_PINID='GND_P19';
NODE_NAME     U5 R2
 '@SCM_LIB.SCM(SCH_1):PAGE17_I286@PURE_QUANTA.AST2600A3GP(CHIPS)':
 'GND_R2': CDS_PINID='GND_R2';
NODE_NAME     U5 R8
 '@SCM_LIB.SCM(SCH_1):PAGE17_I286@PURE_QUANTA.AST2600A3GP(CHIPS)':
 'GND_R8': CDS_PINID='GND_R8';
NODE_NAME     U5 R11
 '@SCM_LIB.SCM(SCH_1):PAGE17_I286@PURE_QUANTA.AST2600A3GP(CHIPS)':
 'GND_R11': CDS_PINID='GND_R11';
NODE_NAME     U5 R15
 '@SCM_LIB.SCM(SCH_1):PAGE17_I286@PURE_QUANTA.AST2600A3GP(CHIPS)':
 'GND_R15': CDS_PINID='GND_R15';
NODE_NAME     U5 R16
 '@SCM_LIB.SCM(SCH_1):PAGE17_I286@PURE_QUANTA.AST2600A3GP(CHIPS)':
 'GND_R16': CDS_PINID='GND_R16';
NODE_NAME     U5 R17
 '@SCM_LIB.SCM(SCH_1):PAGE17_I286@PURE_QUANTA.AST2600A3GP(CHIPS)':
 'GND_R17': CDS_PINID='GND_R17';
NODE_NAME     U5 R18
 '@SCM_LIB.SCM(SCH_1):PAGE17_I286@PURE_QUANTA.AST2600A3GP(CHIPS)':
 'GND_R18': CDS_PINID='GND_R18';
NODE_NAME     U5 R19
 '@SCM_LIB.SCM(SCH_1):PAGE17_I286@PURE_QUANTA.AST2600A3GP(CHIPS)':
 'GND_R19': CDS_PINID='GND_R19';
NODE_NAME     U5 R25
 '@SCM_LIB.SCM(SCH_1):PAGE17_I286@PURE_QUANTA.AST2600A3GP(CHIPS)':
 'GND_R25': CDS_PINID='GND_R25';
NODE_NAME     U5 T4
 '@SCM_LIB.SCM(SCH_1):PAGE17_I286@PURE_QUANTA.AST2600A3GP(CHIPS)':
 'GND_T4': CDS_PINID='GND_T4';
NODE_NAME     U5 T11
 '@SCM_LIB.SCM(SCH_1):PAGE17_I286@PURE_QUANTA.AST2600A3GP(CHIPS)':
 'GND_T11': CDS_PINID='GND_T11';
NODE_NAME     U5 T12
 '@SCM_LIB.SCM(SCH_1):PAGE17_I286@PURE_QUANTA.AST2600A3GP(CHIPS)':
 'GND_T12': CDS_PINID='GND_T12';
NODE_NAME     U5 T15
 '@SCM_LIB.SCM(SCH_1):PAGE17_I286@PURE_QUANTA.AST2600A3GP(CHIPS)':
 'GND_T15': CDS_PINID='GND_T15';
NODE_NAME     U5 T16
 '@SCM_LIB.SCM(SCH_1):PAGE17_I286@PURE_QUANTA.AST2600A3GP(CHIPS)':
 'GND_T16': CDS_PINID='GND_T16';
NODE_NAME     U5 T17
 '@SCM_LIB.SCM(SCH_1):PAGE17_I286@PURE_QUANTA.AST2600A3GP(CHIPS)':
 'GND_T17': CDS_PINID='GND_T17';
NODE_NAME     U5 T18
 '@SCM_LIB.SCM(SCH_1):PAGE17_I286@PURE_QUANTA.AST2600A3GP(CHIPS)':
 'GND_T18': CDS_PINID='GND_T18';
NODE_NAME     U5 T19
 '@SCM_LIB.SCM(SCH_1):PAGE17_I286@PURE_QUANTA.AST2600A3GP(CHIPS)':
 'GND_T19': CDS_PINID='GND_T19';
NODE_NAME     U5 U2
 '@SCM_LIB.SCM(SCH_1):PAGE17_I286@PURE_QUANTA.AST2600A3GP(CHIPS)':
 'GND_U2': CDS_PINID='GND_U2';
NODE_NAME     U5 U8
 '@SCM_LIB.SCM(SCH_1):PAGE17_I286@PURE_QUANTA.AST2600A3GP(CHIPS)':
 'GND_U8': CDS_PINID='GND_U8';
NODE_NAME     U5 U9
 '@SCM_LIB.SCM(SCH_1):PAGE17_I286@PURE_QUANTA.AST2600A3GP(CHIPS)':
 'GND_U9': CDS_PINID='GND_U9';
NODE_NAME     U5 U10
 '@SCM_LIB.SCM(SCH_1):PAGE17_I286@PURE_QUANTA.AST2600A3GP(CHIPS)':
 'GND_U10': CDS_PINID='GND_U10';
NODE_NAME     U5 U11
 '@SCM_LIB.SCM(SCH_1):PAGE17_I286@PURE_QUANTA.AST2600A3GP(CHIPS)':
 'GND_U11': CDS_PINID='GND_U11';
NODE_NAME     U5 U12
 '@SCM_LIB.SCM(SCH_1):PAGE17_I286@PURE_QUANTA.AST2600A3GP(CHIPS)':
 'GND_U12': CDS_PINID='GND_U12';
NODE_NAME     U5 U14
 '@SCM_LIB.SCM(SCH_1):PAGE17_I286@PURE_QUANTA.AST2600A3GP(CHIPS)':
 'GND_U14': CDS_PINID='GND_U14';
NODE_NAME     U5 U19
 '@SCM_LIB.SCM(SCH_1):PAGE17_I286@PURE_QUANTA.AST2600A3GP(CHIPS)':
 'GND_U19': CDS_PINID='GND_U19';
NODE_NAME     U5 U22
 '@SCM_LIB.SCM(SCH_1):PAGE17_I286@PURE_QUANTA.AST2600A3GP(CHIPS)':
 'GND_U22': CDS_PINID='GND_U22';
NODE_NAME     U5 U23
 '@SCM_LIB.SCM(SCH_1):PAGE17_I286@PURE_QUANTA.AST2600A3GP(CHIPS)':
 'GND_U23': CDS_PINID='GND_U23';
NODE_NAME     U5 V5
 '@SCM_LIB.SCM(SCH_1):PAGE17_I286@PURE_QUANTA.AST2600A3GP(CHIPS)':
 'GND_V5': CDS_PINID='GND_V5';
NODE_NAME     U5 V11
 '@SCM_LIB.SCM(SCH_1):PAGE17_I286@PURE_QUANTA.AST2600A3GP(CHIPS)':
 'GND_V11': CDS_PINID='GND_V11';
NODE_NAME     U5 V12
 '@SCM_LIB.SCM(SCH_1):PAGE17_I286@PURE_QUANTA.AST2600A3GP(CHIPS)':
 'GND_V12': CDS_PINID='GND_V12';
NODE_NAME     U5 V14
 '@SCM_LIB.SCM(SCH_1):PAGE17_I286@PURE_QUANTA.AST2600A3GP(CHIPS)':
 'GND_V14': CDS_PINID='GND_V14';
NODE_NAME     U5 V15
 '@SCM_LIB.SCM(SCH_1):PAGE17_I286@PURE_QUANTA.AST2600A3GP(CHIPS)':
 'GND_V15': CDS_PINID='GND_V15';
NODE_NAME     U5 V16
 '@SCM_LIB.SCM(SCH_1):PAGE17_I286@PURE_QUANTA.AST2600A3GP(CHIPS)':
 'GND_V16': CDS_PINID='GND_V16';
NODE_NAME     U5 V17
 '@SCM_LIB.SCM(SCH_1):PAGE17_I286@PURE_QUANTA.AST2600A3GP(CHIPS)':
 'GND_V17': CDS_PINID='GND_V17';
NODE_NAME     U5 V18
 '@SCM_LIB.SCM(SCH_1):PAGE17_I286@PURE_QUANTA.AST2600A3GP(CHIPS)':
 'GND_V18': CDS_PINID='GND_V18';
NODE_NAME     U5 V19
 '@SCM_LIB.SCM(SCH_1):PAGE17_I286@PURE_QUANTA.AST2600A3GP(CHIPS)':
 'GND_V19': CDS_PINID='GND_V19';
NODE_NAME     U5 W5
 '@SCM_LIB.SCM(SCH_1):PAGE17_I286@PURE_QUANTA.AST2600A3GP(CHIPS)':
 'GND_W5': CDS_PINID='GND_W5';
NODE_NAME     U5 W6
 '@SCM_LIB.SCM(SCH_1):PAGE17_I286@PURE_QUANTA.AST2600A3GP(CHIPS)':
 'GND_W6': CDS_PINID='GND_W6';
NODE_NAME     U5 W8
 '@SCM_LIB.SCM(SCH_1):PAGE17_I286@PURE_QUANTA.AST2600A3GP(CHIPS)':
 'GND_W8': CDS_PINID='GND_W8';
NODE_NAME     U5 W9
 '@SCM_LIB.SCM(SCH_1):PAGE17_I286@PURE_QUANTA.AST2600A3GP(CHIPS)':
 'GND_W9': CDS_PINID='GND_W9';
NODE_NAME     U5 W10
 '@SCM_LIB.SCM(SCH_1):PAGE17_I286@PURE_QUANTA.AST2600A3GP(CHIPS)':
 'GND_W10': CDS_PINID='GND_W10';
NODE_NAME     U5 W11
 '@SCM_LIB.SCM(SCH_1):PAGE17_I286@PURE_QUANTA.AST2600A3GP(CHIPS)':
 'GND_W11': CDS_PINID='GND_W11';
NODE_NAME     U5 W12
 '@SCM_LIB.SCM(SCH_1):PAGE17_I286@PURE_QUANTA.AST2600A3GP(CHIPS)':
 'GND_W12': CDS_PINID='GND_W12';
NODE_NAME     U5 W22
 '@SCM_LIB.SCM(SCH_1):PAGE17_I286@PURE_QUANTA.AST2600A3GP(CHIPS)':
 'GND_W22': CDS_PINID='GND_W22';
NODE_NAME     U5 W25
 '@SCM_LIB.SCM(SCH_1):PAGE17_I286@PURE_QUANTA.AST2600A3GP(CHIPS)':
 'GND_W25': CDS_PINID='GND_W25';
NODE_NAME     U5 Y6
 '@SCM_LIB.SCM(SCH_1):PAGE17_I286@PURE_QUANTA.AST2600A3GP(CHIPS)':
 'GND_Y6': CDS_PINID='GND_Y6';
NODE_NAME     U5 Y22
 '@SCM_LIB.SCM(SCH_1):PAGE17_I286@PURE_QUANTA.AST2600A3GP(CHIPS)':
 'GND_Y22': CDS_PINID='GND_Y22';
NODE_NAME     C1 2
 '@SCM_LIB.SCM(SCH_1):PAGE20_I4@PURE_QUANTA.Q_CAP(CHIPS)':
 'B': CDS_PINID='B';
NODE_NAME     C2 2
 '@SCM_LIB.SCM(SCH_1):PAGE20_I5@PURE_QUANTA.Q_CAP(CHIPS)':
 'B': CDS_PINID='B';
NODE_NAME     C3 2
 '@SCM_LIB.SCM(SCH_1):PAGE20_I6@PURE_QUANTA.Q_CAP(CHIPS)':
 'B': CDS_PINID='B';
NODE_NAME     C4 2
 '@SCM_LIB.SCM(SCH_1):PAGE20_I7@PURE_QUANTA.Q_CAP(CHIPS)':
 'B': CDS_PINID='B';
NODE_NAME     R2 2
 '@SCM_LIB.SCM(SCH_1):PAGE20_I13@PURE_QUANTA.Q_RES(CHIPS)':
 'B': CDS_PINID='B';
NODE_NAME     R3 2
 '@SCM_LIB.SCM(SCH_1):PAGE20_I17@PURE_QUANTA.Q_RES(CHIPS)':
 'B': CDS_PINID='B';
NODE_NAME     C6 2
 '@SCM_LIB.SCM(SCH_1):PAGE20_I19@PURE_QUANTA.Q_CAP(CHIPS)':
 'B': CDS_PINID='B';
NODE_NAME     C8 2
 '@SCM_LIB.SCM(SCH_1):PAGE20_I21@PURE_QUANTA.Q_CAP(CHIPS)':
 'B': CDS_PINID='B';
NODE_NAME     C5 2
 '@SCM_LIB.SCM(SCH_1):PAGE20_I23@PURE_QUANTA.Q_CAP(CHIPS)':
 'B': CDS_PINID='B';
NODE_NAME     C7 2
 '@SCM_LIB.SCM(SCH_1):PAGE20_I24@PURE_QUANTA.Q_CAP(CHIPS)':
 'B': CDS_PINID='B';
NODE_NAME     C9 2
 '@SCM_LIB.SCM(SCH_1):PAGE20_I25@PURE_QUANTA.Q_CAP(CHIPS)':
 'B': CDS_PINID='B';
NODE_NAME     R325 2
 '@SCM_LIB.SCM(SCH_1):PAGE20_I27@PURE_QUANTA.Q_RES(CHIPS)':
 'B': CDS_PINID='B';
NODE_NAME     C168 2
 '@SCM_LIB.SCM(SCH_1):PAGE20_I32@PURE_QUANTA.Q_CAP(CHIPS)':
 'B': CDS_PINID='B';
NODE_NAME     C170 2
 '@SCM_LIB.SCM(SCH_1):PAGE20_I33@PURE_QUANTA.Q_CAP(CHIPS)':
 'B': CDS_PINID='B';
NODE_NAME     C10 2
 '@SCM_LIB.SCM(SCH_1):PAGE20_I85@PURE_QUANTA.Q_CAP(CHIPS)':
 'B': CDS_PINID='B';
NODE_NAME     C12 2
 '@SCM_LIB.SCM(SCH_1):PAGE20_I106@PURE_QUANTA.Q_CAP(CHIPS)':
 'B': CDS_PINID='B';
NODE_NAME     C16 2
 '@SCM_LIB.SCM(SCH_1):PAGE20_I113@PURE_QUANTA.Q_CAP(CHIPS)':
 'B': CDS_PINID='B';
NODE_NAME     R350 1
 '@SCM_LIB.SCM(SCH_1):PAGE20_I114@PURE_QUANTA.Q_RES(CHIPS)':
 'A': CDS_PINID='A';
NODE_NAME     R349 1
 '@SCM_LIB.SCM(SCH_1):PAGE20_I116@PURE_QUANTA.Q_RES(CHIPS)':
 'A': CDS_PINID='A';
NODE_NAME     R347 1
 '@SCM_LIB.SCM(SCH_1):PAGE20_I117@PURE_QUANTA.Q_RES(CHIPS)':
 'A': CDS_PINID='A';
NODE_NAME     R348 1
 '@SCM_LIB.SCM(SCH_1):PAGE20_I118@PURE_QUANTA.Q_RES(CHIPS)':
 'A': CDS_PINID='A';
NODE_NAME     R345 1
 '@SCM_LIB.SCM(SCH_1):PAGE20_I119@PURE_QUANTA.Q_RES(CHIPS)':
 'A': CDS_PINID='A';
NODE_NAME     R346 1
 '@SCM_LIB.SCM(SCH_1):PAGE20_I120@PURE_QUANTA.Q_RES(CHIPS)':
 'A': CDS_PINID='A';
NODE_NAME     R344 1
 '@SCM_LIB.SCM(SCH_1):PAGE20_I121@PURE_QUANTA.Q_RES(CHIPS)':
 'A': CDS_PINID='A';
NODE_NAME     R342 1
 '@SCM_LIB.SCM(SCH_1):PAGE20_I122@PURE_QUANTA.Q_RES(CHIPS)':
 'A': CDS_PINID='A';
NODE_NAME     R343 1
 '@SCM_LIB.SCM(SCH_1):PAGE20_I123@PURE_QUANTA.Q_RES(CHIPS)':
 'A': CDS_PINID='A';
NODE_NAME     R340 1
 '@SCM_LIB.SCM(SCH_1):PAGE20_I124@PURE_QUANTA.Q_RES(CHIPS)':
 'A': CDS_PINID='A';
NODE_NAME     R341 1
 '@SCM_LIB.SCM(SCH_1):PAGE20_I125@PURE_QUANTA.Q_RES(CHIPS)':
 'A': CDS_PINID='A';
NODE_NAME     C15 2
 '@SCM_LIB.SCM(SCH_1):PAGE20_I134@PURE_QUANTA.Q_CAP(CHIPS)':
 'B': CDS_PINID='B';
NODE_NAME     R4 2
 '@SCM_LIB.SCM(SCH_1):PAGE20_I141@PURE_QUANTA.Q_RES(CHIPS)':
 'B': CDS_PINID='B';
NODE_NAME     R5 2
 '@SCM_LIB.SCM(SCH_1):PAGE20_I142@PURE_QUANTA.Q_RES(CHIPS)':
 'B': CDS_PINID='B';
NODE_NAME     R6 2
 '@SCM_LIB.SCM(SCH_1):PAGE20_I143@PURE_QUANTA.Q_RES(CHIPS)':
 'B': CDS_PINID='B';
NODE_NAME     R339 1
 '@SCM_LIB.SCM(SCH_1):PAGE20_I159@PURE_QUANTA.Q_RES(CHIPS)':
 'A': CDS_PINID='A';
NODE_NAME     R338 1
 '@SCM_LIB.SCM(SCH_1):PAGE20_I160@PURE_QUANTA.Q_RES(CHIPS)':
 'A': CDS_PINID='A';
NODE_NAME     R337 1
 '@SCM_LIB.SCM(SCH_1):PAGE20_I161@PURE_QUANTA.Q_RES(CHIPS)':
 'A': CDS_PINID='A';
NODE_NAME     R336 1
 '@SCM_LIB.SCM(SCH_1):PAGE20_I162@PURE_QUANTA.Q_RES(CHIPS)':
 'A': CDS_PINID='A';
NODE_NAME     R335 1
 '@SCM_LIB.SCM(SCH_1):PAGE20_I163@PURE_QUANTA.Q_RES(CHIPS)':
 'A': CDS_PINID='A';
NODE_NAME     R334 1
 '@SCM_LIB.SCM(SCH_1):PAGE20_I164@PURE_QUANTA.Q_RES(CHIPS)':
 'A': CDS_PINID='A';
NODE_NAME     R332 1
 '@SCM_LIB.SCM(SCH_1):PAGE20_I171@PURE_QUANTA.Q_RES(CHIPS)':
 'A': CDS_PINID='A';
NODE_NAME     R333 1
 '@SCM_LIB.SCM(SCH_1):PAGE20_I172@PURE_QUANTA.Q_RES(CHIPS)':
 'A': CDS_PINID='A';
NODE_NAME     R331 1
 '@SCM_LIB.SCM(SCH_1):PAGE20_I173@PURE_QUANTA.Q_RES(CHIPS)':
 'A': CDS_PINID='A';
NODE_NAME     R330 1
 '@SCM_LIB.SCM(SCH_1):PAGE20_I174@PURE_QUANTA.Q_RES(CHIPS)':
 'A': CDS_PINID='A';
NODE_NAME     R329 1
 '@SCM_LIB.SCM(SCH_1):PAGE20_I175@PURE_QUANTA.Q_RES(CHIPS)':
 'A': CDS_PINID='A';
NODE_NAME     R328 1
 '@SCM_LIB.SCM(SCH_1):PAGE20_I176@PURE_QUANTA.Q_RES(CHIPS)':
 'A': CDS_PINID='A';
NODE_NAME     R327 1
 '@SCM_LIB.SCM(SCH_1):PAGE20_I177@PURE_QUANTA.Q_RES(CHIPS)':
 'A': CDS_PINID='A';
NODE_NAME     C13 2
 '@SCM_LIB.SCM(SCH_1):PAGE20_I186@PURE_QUANTA.Q_CAP(CHIPS)':
 'B': CDS_PINID='B';
NODE_NAME     C14 2
 '@SCM_LIB.SCM(SCH_1):PAGE20_I187@PURE_QUANTA.Q_CAP(CHIPS)':
 'B': CDS_PINID='B';
NODE_NAME     C17 2
 '@SCM_LIB.SCM(SCH_1):PAGE20_I190@PURE_QUANTA.Q_CAP(CHIPS)':
 'B': CDS_PINID='B';
NODE_NAME     C18 2
 '@SCM_LIB.SCM(SCH_1):PAGE20_I192@PURE_QUANTA.Q_CAP(CHIPS)':
 'B': CDS_PINID='B';
NODE_NAME     R326 1
 '@SCM_LIB.SCM(SCH_1):PAGE20_I193@PURE_QUANTA.Q_RES(CHIPS)':
 'A': CDS_PINID='A';
NODE_NAME     U1 T7
 '@SCM_LIB.SCM(SCH_1):PAGE20_I196@PURE_QUANTA.K4A8G165WCBCTD(CHIPS)':
 'NC1': CDS_PINID='NC1';
NODE_NAME     U1 B2
 '@SCM_LIB.SCM(SCH_1):PAGE20_I196@PURE_QUANTA.K4A8G165WCBCTD(CHIPS)':
 'VSS0': CDS_PINID='VSS0';
NODE_NAME     U1 E1
 '@SCM_LIB.SCM(SCH_1):PAGE20_I196@PURE_QUANTA.K4A8G165WCBCTD(CHIPS)':
 'VSS1': CDS_PINID='VSS1';
NODE_NAME     U1 G8
 '@SCM_LIB.SCM(SCH_1):PAGE20_I196@PURE_QUANTA.K4A8G165WCBCTD(CHIPS)':
 'VSS3': CDS_PINID='VSS3';
NODE_NAME     U1 K1
 '@SCM_LIB.SCM(SCH_1):PAGE20_I196@PURE_QUANTA.K4A8G165WCBCTD(CHIPS)':
 'VSS4': CDS_PINID='VSS4';
NODE_NAME     U1 K9
 '@SCM_LIB.SCM(SCH_1):PAGE20_I196@PURE_QUANTA.K4A8G165WCBCTD(CHIPS)':
 'VSS5': CDS_PINID='VSS5';
NODE_NAME     U1 N1
 '@SCM_LIB.SCM(SCH_1):PAGE20_I196@PURE_QUANTA.K4A8G165WCBCTD(CHIPS)':
 'VSS7': CDS_PINID='VSS7';
NODE_NAME     U1 T1
 '@SCM_LIB.SCM(SCH_1):PAGE20_I196@PURE_QUANTA.K4A8G165WCBCTD(CHIPS)':
 'VSS8': CDS_PINID='VSS8';
NODE_NAME     U1 A2
 '@SCM_LIB.SCM(SCH_1):PAGE20_I196@PURE_QUANTA.K4A8G165WCBCTD(CHIPS)':
 'VSSQ0': CDS_PINID='VSSQ0';
NODE_NAME     U1 A8
 '@SCM_LIB.SCM(SCH_1):PAGE20_I196@PURE_QUANTA.K4A8G165WCBCTD(CHIPS)':
 'VSSQ1': CDS_PINID='VSSQ1';
NODE_NAME     U1 C9
 '@SCM_LIB.SCM(SCH_1):PAGE20_I196@PURE_QUANTA.K4A8G165WCBCTD(CHIPS)':
 'VSSQ2': CDS_PINID='VSSQ2';
NODE_NAME     U1 D2
 '@SCM_LIB.SCM(SCH_1):PAGE20_I196@PURE_QUANTA.K4A8G165WCBCTD(CHIPS)':
 'VSSQ3': CDS_PINID='VSSQ3';
NODE_NAME     U1 D8
 '@SCM_LIB.SCM(SCH_1):PAGE20_I196@PURE_QUANTA.K4A8G165WCBCTD(CHIPS)':
 'VSSQ4': CDS_PINID='VSSQ4';
NODE_NAME     U1 E3
 '@SCM_LIB.SCM(SCH_1):PAGE20_I196@PURE_QUANTA.K4A8G165WCBCTD(CHIPS)':
 'VSSQ5': CDS_PINID='VSSQ5';
NODE_NAME     U1 E8
 '@SCM_LIB.SCM(SCH_1):PAGE20_I196@PURE_QUANTA.K4A8G165WCBCTD(CHIPS)':
 'VSSQ6': CDS_PINID='VSSQ6';
NODE_NAME     U1 F1
 '@SCM_LIB.SCM(SCH_1):PAGE20_I196@PURE_QUANTA.K4A8G165WCBCTD(CHIPS)':
 'VSSQ7': CDS_PINID='VSSQ7';
NODE_NAME     U1 H1
 '@SCM_LIB.SCM(SCH_1):PAGE20_I196@PURE_QUANTA.K4A8G165WCBCTD(CHIPS)':
 'VSSQ8': CDS_PINID='VSSQ8';
NODE_NAME     U1 H9
 '@SCM_LIB.SCM(SCH_1):PAGE20_I196@PURE_QUANTA.K4A8G165WCBCTD(CHIPS)':
 'VSSQ9': CDS_PINID='VSSQ9';
NODE_NAME     C225 2
 '@SCM_LIB.SCM(SCH_1):PAGE20_I197@PURE_QUANTA.Q_CAP(CHIPS)':
 'B': CDS_PINID='B';
NODE_NAME     C222 2
 '@SCM_LIB.SCM(SCH_1):PAGE20_I198@PURE_QUANTA.Q_CAP(CHIPS)':
 'B': CDS_PINID='B';
NODE_NAME     C221 2
 '@SCM_LIB.SCM(SCH_1):PAGE20_I199@PURE_QUANTA.Q_CAP(CHIPS)':
 'B': CDS_PINID='B';
NODE_NAME     C228 2
 '@SCM_LIB.SCM(SCH_1):PAGE21_I21@PURE_QUANTA.Q_CAP(CHIPS)':
 'B': CDS_PINID='B';
NODE_NAME     C235 2
 '@SCM_LIB.SCM(SCH_1):PAGE21_I80@PURE_QUANTA.Q_CAP(CHIPS)':
 'B': CDS_PINID='B';
NODE_NAME     C234 2
 '@SCM_LIB.SCM(SCH_1):PAGE21_I81@PURE_QUANTA.Q_CAP(CHIPS)':
 'B': CDS_PINID='B';
NODE_NAME     Q1 E
 '@SCM_LIB.SCM(SCH_1):PAGE22_I2@PURE_QUANTA.MMBT39047F(CHIPS)':
 '2': CDS_PINID='\2\';
NODE_NAME     Q3 E
 '@SCM_LIB.SCM(SCH_1):PAGE22_I4@PURE_QUANTA.MMBT39047F(CHIPS)':
 '2': CDS_PINID='\2\';
NODE_NAME     U12 S
 '@SCM_LIB.SCM(SCH_1):PAGE22_I14@PURE_QUANTA.MOSFET_N(CHIPS)':
 'SOURCE': CDS_PINID='SOURCE';
NODE_NAME     C147 2
 '@SCM_LIB.SCM(SCH_1):PAGE22_I17@PURE_QUANTA.Q_CAP(CHIPS)':
 'B': CDS_PINID='B';
NODE_NAME     R314 2
 '@SCM_LIB.SCM(SCH_1):PAGE22_I26@PURE_QUANTA.Q_RES(CHIPS)':
 'B': CDS_PINID='B';
NODE_NAME     R313 2
 '@SCM_LIB.SCM(SCH_1):PAGE22_I30@PURE_QUANTA.Q_RES(CHIPS)':
 'B': CDS_PINID='B';
NODE_NAME     R614 2
 '@SCM_LIB.SCM(SCH_1):PAGE22_I35@PURE_QUANTA.Q_RES(CHIPS)':
 'B': CDS_PINID='B';
NODE_NAME     C34 2
 '@SCM_LIB.SCM(SCH_1):PAGE22_I42@PURE_QUANTA.Q_CAP(CHIPS)':
 'B': CDS_PINID='B';
NODE_NAME     C223 2
 '@SCM_LIB.SCM(SCH_1):PAGE22_I46@PURE_QUANTA.Q_CAP(CHIPS)':
 'B': CDS_PINID='B';
NODE_NAME     C253 2
 '@SCM_LIB.SCM(SCH_1):PAGE22_I57@PURE_QUANTA.Q_CAP(CHIPS)':
 'B': CDS_PINID='B';
NODE_NAME     C264 2
 '@SCM_LIB.SCM(SCH_1):PAGE22_I59@PURE_QUANTA.Q_CAP(CHIPS)':
 'B': CDS_PINID='B';
NODE_NAME     U6 2
 '@SCM_LIB.SCM(SCH_1):PAGE22_I87@PURE_QUANTA.74LVC2G07DW7(CHIPS)':
 'GND': CDS_PINID='GND';
NODE_NAME     U13 3
 '@SCM_LIB.SCM(SCH_1):PAGE22_I89@PURE_QUANTA.MC74VHC1G07DFT2G(CHIPS)':
 'GND': CDS_PINID='GND';
NODE_NAME     C202 2
 '@SCM_LIB.SCM(SCH_1):PAGE23_I11@PURE_QUANTA.Q_CAP(CHIPS)':
 'B': CDS_PINID='B';
NODE_NAME     C203 2
 '@SCM_LIB.SCM(SCH_1):PAGE23_I12@PURE_QUANTA.Q_CAP(CHIPS)':
 'B': CDS_PINID='B';
NODE_NAME     C205 2
 '@SCM_LIB.SCM(SCH_1):PAGE23_I25@PURE_QUANTA.Q_CAP(CHIPS)':
 'B': CDS_PINID='B';
NODE_NAME     C206 2
 '@SCM_LIB.SCM(SCH_1):PAGE23_I26@PURE_QUANTA.Q_CAP(CHIPS)':
 'B': CDS_PINID='B';
NODE_NAME     C207 2
 '@SCM_LIB.SCM(SCH_1):PAGE23_I29@PURE_QUANTA.Q_CAP(CHIPS)':
 'B': CDS_PINID='B';
NODE_NAME     U33 3
 '@SCM_LIB.SCM(SCH_1):PAGE23_I32@PURE_QUANTA.74HC1G126GW(CHIPS)':
 'GND': CDS_PINID='GND';
NODE_NAME     U26 3
 '@SCM_LIB.SCM(SCH_1):PAGE23_I33@PURE_QUANTA.74HC1G126GW(CHIPS)':
 'GND': CDS_PINID='GND';
NODE_NAME     C204 2
 '@SCM_LIB.SCM(SCH_1):PAGE23_I45@PURE_QUANTA.Q_CAP(CHIPS)':
 'B': CDS_PINID='B';
NODE_NAME     C209 2
 '@SCM_LIB.SCM(SCH_1):PAGE23_I54@PURE_QUANTA.Q_CAP(CHIPS)':
 'B': CDS_PINID='B';
NODE_NAME     R87 2
 '@SCM_LIB.SCM(SCH_1):PAGE23_I57@PURE_QUANTA.Q_RES(CHIPS)':
 'B': CDS_PINID='B';
NODE_NAME     R88 2
 '@SCM_LIB.SCM(SCH_1):PAGE23_I59@PURE_QUANTA.Q_RES(CHIPS)':
 'B': CDS_PINID='B';
NODE_NAME     R89 2
 '@SCM_LIB.SCM(SCH_1):PAGE23_I65@PURE_QUANTA.Q_RES(CHIPS)':
 'B': CDS_PINID='B';
NODE_NAME     C211 2
 '@SCM_LIB.SCM(SCH_1):PAGE23_I67@PURE_QUANTA.Q_CAP(CHIPS)':
 'B': CDS_PINID='B';
NODE_NAME     D12 2
 '@SCM_LIB.SCM(SCH_1):PAGE23_I74@PURE_QUANTA.BZA462A(CHIPS)':
 '2': CDS_PINID='\2\';
NODE_NAME     D12 5
 '@SCM_LIB.SCM(SCH_1):PAGE23_I74@PURE_QUANTA.BZA462A(CHIPS)':
 '5': CDS_PINID='\5\';
NODE_NAME     C212 2
 '@SCM_LIB.SCM(SCH_1):PAGE23_I77@PURE_QUANTA.Q_CAP(CHIPS)':
 'B': CDS_PINID='B';
NODE_NAME     C213 2
 '@SCM_LIB.SCM(SCH_1):PAGE23_I83@PURE_QUANTA.Q_CAP(CHIPS)':
 'B': CDS_PINID='B';
NODE_NAME     C214 2
 '@SCM_LIB.SCM(SCH_1):PAGE23_I84@PURE_QUANTA.Q_CAP(CHIPS)':
 'B': CDS_PINID='B';
NODE_NAME     U35 3
 '@SCM_LIB.SCM(SCH_1):PAGE23_I155@PURE_QUANTA.DT1240E04LP7(CHIPS)':
 'VSS1': CDS_PINID='VSS1';
NODE_NAME     U35 8
 '@SCM_LIB.SCM(SCH_1):PAGE23_I155@PURE_QUANTA.DT1240E04LP7(CHIPS)':
 'VSS2': CDS_PINID='VSS2';
NODE_NAME     U34 3
 '@SCM_LIB.SCM(SCH_1):PAGE23_I156@PURE_QUANTA.DT1240E04LP7(CHIPS)':
 'VSS1': CDS_PINID='VSS1';
NODE_NAME     U34 8
 '@SCM_LIB.SCM(SCH_1):PAGE23_I156@PURE_QUANTA.DT1240E04LP7(CHIPS)':
 'VSS2': CDS_PINID='VSS2';
NODE_NAME     U44 3
 '@SCM_LIB.SCM(SCH_1):PAGE25_I61@PURE_QUANTA.SN74LVC1G07DCKR(CHIPS)':
 'GND': CDS_PINID='GND';
NODE_NAME     C304 2
 '@SCM_LIB.SCM(SCH_1):PAGE25_I65@PURE_QUANTA.Q_CAP(CHIPS)':
 'B': CDS_PINID='B';
NODE_NAME     R411 2
 '@SCM_LIB.SCM(SCH_1):PAGE26_I6@PURE_QUANTA.Q_RES(CHIPS)':
 'B': CDS_PINID='B';
NODE_NAME     R412 2
 '@SCM_LIB.SCM(SCH_1):PAGE26_I8@PURE_QUANTA.Q_RES(CHIPS)':
 'B': CDS_PINID='B';
NODE_NAME     R413 2
 '@SCM_LIB.SCM(SCH_1):PAGE26_I12@PURE_QUANTA.Q_RES(CHIPS)':
 'B': CDS_PINID='B';
NODE_NAME     U19 4
 '@SCM_LIB.SCM(SCH_1):PAGE26_I15@PURE_QUANTA.M24128BWDW6TP(CHIPS)':
 'VSS': CDS_PINID='VSS';
NODE_NAME     C192 2
 '@SCM_LIB.SCM(SCH_1):PAGE26_I17@PURE_QUANTA.Q_CAP(CHIPS)':
 'B': CDS_PINID='B';
NODE_NAME     R15 2
 '@SCM_LIB.SCM(SCH_1):PAGE26_I32@PURE_QUANTA.Q_RES(CHIPS)':
 'B': CDS_PINID='B';
NODE_NAME     R419 2
 '@SCM_LIB.SCM(SCH_1):PAGE26_I37@PURE_QUANTA.Q_RES(CHIPS)':
 'B': CDS_PINID='B';
NODE_NAME     R417 2
 '@SCM_LIB.SCM(SCH_1):PAGE26_I39@PURE_QUANTA.Q_RES(CHIPS)':
 'B': CDS_PINID='B';
NODE_NAME     C191 2
 '@SCM_LIB.SCM(SCH_1):PAGE26_I54@PURE_QUANTA.Q_CAP(CHIPS)':
 'B': CDS_PINID='B';
NODE_NAME     C267 2
 '@SCM_LIB.SCM(SCH_1):PAGE27_I166@PURE_QUANTA.Q_CAP(CHIPS)':
 'B': CDS_PINID='B';
NODE_NAME     R770 1
 '@SCM_LIB.SCM(SCH_1):PAGE27_I217@PURE_QUANTA.Q_RES(CHIPS)':
 'A': CDS_PINID='A';
NODE_NAME     C172 2
 '@SCM_LIB.SCM(SCH_1):PAGE28_I35@PURE_QUANTA.Q_CAP(CHIPS)':
 'B': CDS_PINID='B';
NODE_NAME     C171 2
 '@SCM_LIB.SCM(SCH_1):PAGE28_I38@PURE_QUANTA.Q_CAP(CHIPS)':
 'B': CDS_PINID='B';
NODE_NAME     R378 2
 '@SCM_LIB.SCM(SCH_1):PAGE28_I54@PURE_QUANTA.Q_RES(CHIPS)':
 'B': CDS_PINID='B';
NODE_NAME     R377 2
 '@SCM_LIB.SCM(SCH_1):PAGE28_I63@PURE_QUANTA.Q_RES(CHIPS)':
 'B': CDS_PINID='B';
NODE_NAME     C159 2
 '@SCM_LIB.SCM(SCH_1):PAGE28_I98@PURE_QUANTA.Q_CAP(CHIPS)':
 'B': CDS_PINID='B';
NODE_NAME     U37 4
 '@SCM_LIB.SCM(SCH_1):PAGE28_I99@PURE_QUANTA.PCA9517ADP(CHIPS)':
 'GND': CDS_PINID='GND';
NODE_NAME     C158 2
 '@SCM_LIB.SCM(SCH_1):PAGE28_I101@PURE_QUANTA.Q_CAP(CHIPS)':
 'B': CDS_PINID='B';
NODE_NAME     R296 2
 '@SCM_LIB.SCM(SCH_1):PAGE28_I105@PURE_QUANTA.Q_RES(CHIPS)':
 'B': CDS_PINID='B';
NODE_NAME     U40 12
 '@SCM_LIB.SCM(SCH_1):PAGE28_I141@PURE_QUANTA.PCA9555PW(CHIPS)':
 'VSS': CDS_PINID='VSS';
NODE_NAME     C300 2
 '@SCM_LIB.SCM(SCH_1):PAGE28_I146@PURE_QUANTA.Q_CAP(CHIPS)':
 'B': CDS_PINID='B';
NODE_NAME     Q8 S
 '@SCM_LIB.SCM(SCH_1):PAGE28_I163@PURE_QUANTA.2N7002A7(CHIPS)':
 'S': CDS_PINID='S';
NODE_NAME     R745 2
 '@SCM_LIB.SCM(SCH_1):PAGE28_I172@PURE_QUANTA.Q_RES(CHIPS)':
 'B': CDS_PINID='B';
NODE_NAME     R744 2
 '@SCM_LIB.SCM(SCH_1):PAGE28_I173@PURE_QUANTA.Q_RES(CHIPS)':
 'B': CDS_PINID='B';
NODE_NAME     R743 2
 '@SCM_LIB.SCM(SCH_1):PAGE28_I175@PURE_QUANTA.Q_RES(CHIPS)':
 'B': CDS_PINID='B';
NODE_NAME     U10 2
 '@SCM_LIB.SCM(SCH_1):PAGE28_I179@PURE_QUANTA.NCP380HSNAJAAT1G(CHIPS)':
 'GND': CDS_PINID='GND';
NODE_NAME     U23 3
 '@SCM_LIB.SCM(SCH_1):PAGE28_I180@PURE_QUANTA.74LVC1G07W57(CHIPS)':
 'GND': CDS_PINID='GND';
NODE_NAME     C157 2
 '@SCM_LIB.SCM(SCH_1):PAGE28_I181@PURE_QUANTA.Q_CAP(CHIPS)':
 'B': CDS_PINID='B';
NODE_NAME     U38 1
 '@SCM_LIB.SCM(SCH_1):PAGE29_I99@PURE_QUANTA.PRTR5V0U2X(CHIPS)':
 'GND': CDS_PINID='GND';
NODE_NAME     C237 2
 '@SCM_LIB.SCM(SCH_1):PAGE29_I146@PURE_QUANTA.Q_CAP(CHIPS)':
 'B': CDS_PINID='B';
NODE_NAME     C236 2
 '@SCM_LIB.SCM(SCH_1):PAGE29_I148@PURE_QUANTA.Q_CAP(CHIPS)':
 'B': CDS_PINID='B';
NODE_NAME     C219 2
 '@SCM_LIB.SCM(SCH_1):PAGE29_I150@PURE_QUANTA.Q_CAP(CHIPS)':
 'B': CDS_PINID='B';
NODE_NAME     R694 2
 '@SCM_LIB.SCM(SCH_1):PAGE29_I155@PURE_QUANTA.Q_RES(CHIPS)':
 'B': CDS_PINID='B';
NODE_NAME     C149 2
 '@SCM_LIB.SCM(SCH_1):PAGE29_I161@PURE_QUANTA.Q_CAP(CHIPS)':
 'B': CDS_PINID='B';
NODE_NAME     U36 3
 '@SCM_LIB.SCM(SCH_1):PAGE29_I164@PURE_QUANTA.74HC1G126GW(CHIPS)':
 'GND': CDS_PINID='GND';
NODE_NAME     R219 2
 '@SCM_LIB.SCM(SCH_1):PAGE29_I170@PURE_QUANTA.Q_RES(CHIPS)':
 'B': CDS_PINID='B';
NODE_NAME     C148 2
 '@SCM_LIB.SCM(SCH_1):PAGE29_I172@PURE_QUANTA.Q_CAP(CHIPS)':
 'B': CDS_PINID='B';
NODE_NAME     U29 3
 '@SCM_LIB.SCM(SCH_1):PAGE29_I174@PURE_QUANTA.74HC1G126GW(CHIPS)':
 'GND': CDS_PINID='GND';
NODE_NAME     R205 2
 '@SCM_LIB.SCM(SCH_1):PAGE29_I184@PURE_QUANTA.Q_RES(CHIPS)':
 'B': CDS_PINID='B';
NODE_NAME     C179 2
 '@SCM_LIB.SCM(SCH_1):PAGE29_I193@PURE_QUANTA.Q_CAP(CHIPS)':
 'B': CDS_PINID='B';
NODE_NAME     C178 2
 '@SCM_LIB.SCM(SCH_1):PAGE29_I194@PURE_QUANTA.Q_CAP(CHIPS)':
 'B': CDS_PINID='B';
NODE_NAME     Q6 S
 '@SCM_LIB.SCM(SCH_1):PAGE29_I202@PURE_QUANTA.2N7002A7(CHIPS)':
 'S': CDS_PINID='S';
NODE_NAME     U22 20
 '@SCM_LIB.SCM(SCH_1):PAGE29_I206@PURE_QUANTA.PI3PCIE3212ZBEX(CHIPS)':
 'GND0': CDS_PINID='GND0';
NODE_NAME     U22 5
 '@SCM_LIB.SCM(SCH_1):PAGE29_I206@PURE_QUANTA.PI3PCIE3212ZBEX(CHIPS)':
 'GND1': CDS_PINID='GND1';
NODE_NAME     U22 11
 '@SCM_LIB.SCM(SCH_1):PAGE29_I206@PURE_QUANTA.PI3PCIE3212ZBEX(CHIPS)':
 'GND2': CDS_PINID='GND2';
NODE_NAME     U27 3
 '@SCM_LIB.SCM(SCH_1):PAGE29_I211@PURE_QUANTA.DT1240E04LP7(CHIPS)':
 'VSS1': CDS_PINID='VSS1';
NODE_NAME     U27 8
 '@SCM_LIB.SCM(SCH_1):PAGE29_I211@PURE_QUANTA.DT1240E04LP7(CHIPS)':
 'VSS2': CDS_PINID='VSS2';
NODE_NAME     C175 2
 '@SCM_LIB.SCM(SCH_1):PAGE30_I151@PURE_QUANTA.Q_CAP(CHIPS)':
 'B': CDS_PINID='B';
NODE_NAME     J6 2
 '@SCM_LIB.SCM(SCH_1):PAGE30_I184@PURE_QUANTA.SCONN3_21291035BR2(CHIPS)':
 '2': CDS_PINID='\2\';
NODE_NAME     C268 2
 '@SCM_LIB.SCM(SCH_1):PAGE30_I229@PURE_QUANTA.Q_CAP(CHIPS)':
 'B': CDS_PINID='B';
NODE_NAME     U24 2
 '@SCM_LIB.SCM(SCH_1):PAGE30_I246@PURE_QUANTA.74LVC2G07DW7(CHIPS)':
 'GND': CDS_PINID='GND';
NODE_NAME     U47 2
 '@SCM_LIB.SCM(SCH_1):PAGE30_I247@PURE_QUANTA.74LVC2G07DW7(CHIPS)':
 'GND': CDS_PINID='GND';
NODE_NAME     U2 4
 '@SCM_LIB.SCM(SCH_1):PAGE30_I250@PURE_QUANTA.FSA3357K8X(CHIPS)':
 'GND': CDS_PINID='GND';
NODE_NAME     U3 4
 '@SCM_LIB.SCM(SCH_1):PAGE30_I251@PURE_QUANTA.FSA3357K8X(CHIPS)':
 'GND': CDS_PINID='GND';
NODE_NAME     C20 2
 '@SCM_LIB.SCM(SCH_1):PAGE30_I254@PURE_QUANTA.Q_CAP(CHIPS)':
 'B': CDS_PINID='B';
NODE_NAME     C19 2
 '@SCM_LIB.SCM(SCH_1):PAGE30_I261@PURE_QUANTA.Q_CAP(CHIPS)':
 'B': CDS_PINID='B';
NODE_NAME     C501 2
 '@SCM_LIB.SCM(SCH_1):PAGE31_I11@PURE_QUANTA.Q_CAP(CHIPS)':
 'B': CDS_PINID='B';
NODE_NAME     C500 2
 '@SCM_LIB.SCM(SCH_1):PAGE31_I17@PURE_QUANTA.Q_CAP(CHIPS)':
 'B': CDS_PINID='B';
NODE_NAME     U50 2
 '@SCM_LIB.SCM(SCH_1):PAGE31_I23@PURE_QUANTA.NC7SB3157(CHIPS)':
 'GND': CDS_PINID='GND';
NODE_NAME     U51 2
 '@SCM_LIB.SCM(SCH_1):PAGE31_I24@PURE_QUANTA.NC7SB3157(CHIPS)':
 'GND': CDS_PINID='GND';
NODE_NAME     C217 2
 '@SCM_LIB.SCM(SCH_1):PAGE32_I21@PURE_QUANTA.Q_CAP(CHIPS)':
 'B': CDS_PINID='B';
NODE_NAME     C215 2
 '@SCM_LIB.SCM(SCH_1):PAGE32_I22@PURE_QUANTA.Q_CAP(CHIPS)':
 'B': CDS_PINID='B';
NODE_NAME     R229 1
 '@SCM_LIB.SCM(SCH_1):PAGE32_I106@PURE_QUANTA.Q_RES(CHIPS)':
 'A': CDS_PINID='A';
NODE_NAME     R228 1
 '@SCM_LIB.SCM(SCH_1):PAGE32_I107@PURE_QUANTA.Q_RES(CHIPS)':
 'A': CDS_PINID='A';
NODE_NAME     J7 7
 '@SCM_LIB.SCM(SCH_1):PAGE32_I132@PURE_QUANTA.CONN8_210HP1080BR1(CHIPS)':
 '7': CDS_PINID='\7\';
NODE_NAME     C318 2
 '@SCM_LIB.SCM(SCH_1):PAGE34_I122@PURE_QUANTA.Q_CAP(CHIPS)':
 'B': CDS_PINID='B';
NODE_NAME     OSC2 2
 '@SCM_LIB.SCM(SCH_1):PAGE34_I127@PURE_QUANTA.OSC4_7X25000018(CHIPS)':
 'GND': CDS_PINID='GND';
NODE_NAME     U25 B2
 '@SCM_LIB.SCM(SCH_1):PAGE40_I1@PURE_QUANTA.LCMXO3LF2100C5BG256C(CHIPS)':
 'GND_B2': CDS_PINID='GND_B2';
NODE_NAME     U25 B15
 '@SCM_LIB.SCM(SCH_1):PAGE40_I1@PURE_QUANTA.LCMXO3LF2100C5BG256C(CHIPS)':
 'GND_B15': CDS_PINID='GND_B15';
NODE_NAME     U25 C3
 '@SCM_LIB.SCM(SCH_1):PAGE40_I1@PURE_QUANTA.LCMXO3LF2100C5BG256C(CHIPS)':
 'GND_C3': CDS_PINID='GND_C3';
NODE_NAME     U25 C14
 '@SCM_LIB.SCM(SCH_1):PAGE40_I1@PURE_QUANTA.LCMXO3LF2100C5BG256C(CHIPS)':
 'GND_C14': CDS_PINID='GND_C14';
NODE_NAME     U25 D4
 '@SCM_LIB.SCM(SCH_1):PAGE40_I1@PURE_QUANTA.LCMXO3LF2100C5BG256C(CHIPS)':
 'GND_D4': CDS_PINID='GND_D4';
NODE_NAME     U25 D13
 '@SCM_LIB.SCM(SCH_1):PAGE40_I1@PURE_QUANTA.LCMXO3LF2100C5BG256C(CHIPS)':
 'GND_D13': CDS_PINID='GND_D13';
NODE_NAME     U25 E5
 '@SCM_LIB.SCM(SCH_1):PAGE40_I1@PURE_QUANTA.LCMXO3LF2100C5BG256C(CHIPS)':
 'GND_E5': CDS_PINID='GND_E5';
NODE_NAME     U25 E12
 '@SCM_LIB.SCM(SCH_1):PAGE40_I1@PURE_QUANTA.LCMXO3LF2100C5BG256C(CHIPS)':
 'GND_E12': CDS_PINID='GND_E12';
NODE_NAME     U25 F6
 '@SCM_LIB.SCM(SCH_1):PAGE40_I1@PURE_QUANTA.LCMXO3LF2100C5BG256C(CHIPS)':
 'GND_F6': CDS_PINID='GND_F6';
NODE_NAME     U25 F11
 '@SCM_LIB.SCM(SCH_1):PAGE40_I1@PURE_QUANTA.LCMXO3LF2100C5BG256C(CHIPS)':
 'GND_F11': CDS_PINID='GND_F11';
NODE_NAME     U25 H8
 '@SCM_LIB.SCM(SCH_1):PAGE40_I1@PURE_QUANTA.LCMXO3LF2100C5BG256C(CHIPS)':
 'GND_H8': CDS_PINID='GND_H8';
NODE_NAME     U25 H9
 '@SCM_LIB.SCM(SCH_1):PAGE40_I1@PURE_QUANTA.LCMXO3LF2100C5BG256C(CHIPS)':
 'GND_H9': CDS_PINID='GND_H9';
NODE_NAME     U25 J8
 '@SCM_LIB.SCM(SCH_1):PAGE40_I1@PURE_QUANTA.LCMXO3LF2100C5BG256C(CHIPS)':
 'GND_J8': CDS_PINID='GND_J8';
NODE_NAME     U25 J9
 '@SCM_LIB.SCM(SCH_1):PAGE40_I1@PURE_QUANTA.LCMXO3LF2100C5BG256C(CHIPS)':
 'GND_J9': CDS_PINID='GND_J9';
NODE_NAME     U25 L6
 '@SCM_LIB.SCM(SCH_1):PAGE40_I1@PURE_QUANTA.LCMXO3LF2100C5BG256C(CHIPS)':
 'GND_L6': CDS_PINID='GND_L6';
NODE_NAME     U25 L11
 '@SCM_LIB.SCM(SCH_1):PAGE40_I1@PURE_QUANTA.LCMXO3LF2100C5BG256C(CHIPS)':
 'GND_L11': CDS_PINID='GND_L11';
NODE_NAME     U25 M5
 '@SCM_LIB.SCM(SCH_1):PAGE40_I1@PURE_QUANTA.LCMXO3LF2100C5BG256C(CHIPS)':
 'GND_M5': CDS_PINID='GND_M5';
NODE_NAME     U25 M12
 '@SCM_LIB.SCM(SCH_1):PAGE40_I1@PURE_QUANTA.LCMXO3LF2100C5BG256C(CHIPS)':
 'GND_M12': CDS_PINID='GND_M12';
NODE_NAME     U25 N4
 '@SCM_LIB.SCM(SCH_1):PAGE40_I1@PURE_QUANTA.LCMXO3LF2100C5BG256C(CHIPS)':
 'GND_N4': CDS_PINID='GND_N4';
NODE_NAME     U25 N13
 '@SCM_LIB.SCM(SCH_1):PAGE40_I1@PURE_QUANTA.LCMXO3LF2100C5BG256C(CHIPS)':
 'GND_N13': CDS_PINID='GND_N13';
NODE_NAME     U25 P3
 '@SCM_LIB.SCM(SCH_1):PAGE40_I1@PURE_QUANTA.LCMXO3LF2100C5BG256C(CHIPS)':
 'GND_P3': CDS_PINID='GND_P3';
NODE_NAME     U25 P14
 '@SCM_LIB.SCM(SCH_1):PAGE40_I1@PURE_QUANTA.LCMXO3LF2100C5BG256C(CHIPS)':
 'GND_P14': CDS_PINID='GND_P14';
NODE_NAME     U25 R2
 '@SCM_LIB.SCM(SCH_1):PAGE40_I1@PURE_QUANTA.LCMXO3LF2100C5BG256C(CHIPS)':
 'GND_R2': CDS_PINID='GND_R2';
NODE_NAME     U25 R15
 '@SCM_LIB.SCM(SCH_1):PAGE40_I1@PURE_QUANTA.LCMXO3LF2100C5BG256C(CHIPS)':
 'GND_R15': CDS_PINID='GND_R15';
NODE_NAME     C242 2
 '@SCM_LIB.SCM(SCH_1):PAGE41_I1@PURE_QUANTA.Q_CAP(CHIPS)':
 'B': CDS_PINID='B';
NODE_NAME     C166 2
 '@SCM_LIB.SCM(SCH_1):PAGE41_I8@PURE_QUANTA.Q_CAP(CHIPS)':
 'B': CDS_PINID='B';
NODE_NAME     C247 2
 '@SCM_LIB.SCM(SCH_1):PAGE41_I77@PURE_QUANTA.Q_CAP(CHIPS)':
 'B': CDS_PINID='B';
NODE_NAME     C189 2
 '@SCM_LIB.SCM(SCH_1):PAGE41_I78@PURE_QUANTA.Q_CAP(CHIPS)':
 'B': CDS_PINID='B';
NODE_NAME     C261 2
 '@SCM_LIB.SCM(SCH_1):PAGE41_I79@PURE_QUANTA.Q_CAP(CHIPS)':
 'B': CDS_PINID='B';
NODE_NAME     C167 2
 '@SCM_LIB.SCM(SCH_1):PAGE41_I80@PURE_QUANTA.Q_CAP(CHIPS)':
 'B': CDS_PINID='B';
NODE_NAME     C243 2
 '@SCM_LIB.SCM(SCH_1):PAGE41_I81@PURE_QUANTA.Q_CAP(CHIPS)':
 'B': CDS_PINID='B';
NODE_NAME     C254 2
 '@SCM_LIB.SCM(SCH_1):PAGE41_I82@PURE_QUANTA.Q_CAP(CHIPS)':
 'B': CDS_PINID='B';
NODE_NAME     C141 2
 '@SCM_LIB.SCM(SCH_1):PAGE41_I83@PURE_QUANTA.Q_CAP(CHIPS)':
 'B': CDS_PINID='B';
NODE_NAME     C187 2
 '@SCM_LIB.SCM(SCH_1):PAGE41_I84@PURE_QUANTA.Q_CAP(CHIPS)':
 'B': CDS_PINID='B';
NODE_NAME     C245 2
 '@SCM_LIB.SCM(SCH_1):PAGE41_I85@PURE_QUANTA.Q_CAP(CHIPS)':
 'B': CDS_PINID='B';
NODE_NAME     C188 2
 '@SCM_LIB.SCM(SCH_1):PAGE41_I86@PURE_QUANTA.Q_CAP(CHIPS)':
 'B': CDS_PINID='B';
NODE_NAME     C260 2
 '@SCM_LIB.SCM(SCH_1):PAGE41_I87@PURE_QUANTA.Q_CAP(CHIPS)':
 'B': CDS_PINID='B';
NODE_NAME     C152 2
 '@SCM_LIB.SCM(SCH_1):PAGE41_I88@PURE_QUANTA.Q_CAP(CHIPS)':
 'B': CDS_PINID='B';
NODE_NAME     C160 2
 '@SCM_LIB.SCM(SCH_1):PAGE41_I89@PURE_QUANTA.Q_CAP(CHIPS)':
 'B': CDS_PINID='B';
NODE_NAME     C220 2
 '@SCM_LIB.SCM(SCH_1):PAGE41_I90@PURE_QUANTA.Q_CAP(CHIPS)':
 'B': CDS_PINID='B';
NODE_NAME     C162 2
 '@SCM_LIB.SCM(SCH_1):PAGE41_I91@PURE_QUANTA.Q_CAP(CHIPS)':
 'B': CDS_PINID='B';
NODE_NAME     C164 2
 '@SCM_LIB.SCM(SCH_1):PAGE41_I92@PURE_QUANTA.Q_CAP(CHIPS)':
 'B': CDS_PINID='B';
NODE_NAME     C165 2
 '@SCM_LIB.SCM(SCH_1):PAGE41_I93@PURE_QUANTA.Q_CAP(CHIPS)':
 'B': CDS_PINID='B';
NODE_NAME     C216 2
 '@SCM_LIB.SCM(SCH_1):PAGE41_I94@PURE_QUANTA.Q_CAP(CHIPS)':
 'B': CDS_PINID='B';
NODE_NAME     C218 2
 '@SCM_LIB.SCM(SCH_1):PAGE41_I95@PURE_QUANTA.Q_CAP(CHIPS)':
 'B': CDS_PINID='B';
NODE_NAME     C195 2
 '@SCM_LIB.SCM(SCH_1):PAGE41_I96@PURE_QUANTA.Q_CAP(CHIPS)':
 'B': CDS_PINID='B';
NODE_NAME     C145 2
 '@SCM_LIB.SCM(SCH_1):PAGE41_I99@PURE_QUANTA.Q_CAP(CHIPS)':
 'B': CDS_PINID='B';
NODE_NAME     C194 2
 '@SCM_LIB.SCM(SCH_1):PAGE41_I101@PURE_QUANTA.Q_CAP(CHIPS)':
 'B': CDS_PINID='B';
NODE_NAME     C176 2
 '@SCM_LIB.SCM(SCH_1):PAGE41_I108@PURE_QUANTA.Q_CAP(CHIPS)':
 'B': CDS_PINID='B';
NODE_NAME     C193 2
 '@SCM_LIB.SCM(SCH_1):PAGE41_I109@PURE_QUANTA.Q_CAP(CHIPS)':
 'B': CDS_PINID='B';
NODE_NAME     C250 2
 '@SCM_LIB.SCM(SCH_1):PAGE41_I115@PURE_QUANTA.Q_CAP(CHIPS)':
 'B': CDS_PINID='B';
NODE_NAME     C190 2
 '@SCM_LIB.SCM(SCH_1):PAGE41_I116@PURE_QUANTA.Q_CAP(CHIPS)':
 'B': CDS_PINID='B';
NODE_NAME     C263 2
 '@SCM_LIB.SCM(SCH_1):PAGE41_I117@PURE_QUANTA.Q_CAP(CHIPS)':
 'B': CDS_PINID='B';
NODE_NAME     C269 2
 '@SCM_LIB.SCM(SCH_1):PAGE41_I118@PURE_QUANTA.Q_CAP(CHIPS)':
 'B': CDS_PINID='B';
NODE_NAME     C266 2
 '@SCM_LIB.SCM(SCH_1):PAGE41_I119@PURE_QUANTA.Q_CAP(CHIPS)':
 'B': CDS_PINID='B';
NODE_NAME     C163 2
 '@SCM_LIB.SCM(SCH_1):PAGE41_I122@PURE_QUANTA.Q_CAP(CHIPS)':
 'B': CDS_PINID='B';
NODE_NAME     C286 2
 '@SCM_LIB.SCM(SCH_1):PAGE41_I123@PURE_QUANTA.Q_CAP(CHIPS)':
 'B': CDS_PINID='B';
NODE_NAME     C285 2
 '@SCM_LIB.SCM(SCH_1):PAGE41_I124@PURE_QUANTA.Q_CAP(CHIPS)':
 'B': CDS_PINID='B';
NODE_NAME     C281 2
 '@SCM_LIB.SCM(SCH_1):PAGE41_I125@PURE_QUANTA.Q_CAP(CHIPS)':
 'B': CDS_PINID='B';
NODE_NAME     C283 2
 '@SCM_LIB.SCM(SCH_1):PAGE41_I126@PURE_QUANTA.Q_CAP(CHIPS)':
 'B': CDS_PINID='B';
NODE_NAME     R642 1
 '@SCM_LIB.SCM(SCH_1):PAGE42_I58@PURE_QUANTA.Q_RES(CHIPS)':
 'A': CDS_PINID='A';
NODE_NAME     U30 8
 '@SCM_LIB.SCM(SCH_1):PAGE44_I271@PURE_QUANTA.IDTQS3VH257PAG(CHIPS)':
 'GND': CDS_PINID='GND';
NODE_NAME     C255 2
 '@SCM_LIB.SCM(SCH_1):PAGE44_I278@PURE_QUANTA.Q_CAP(CHIPS)':
 'B': CDS_PINID='B';
NODE_NAME     C146 2
 '@SCM_LIB.SCM(SCH_1):PAGE44_I292@PURE_QUANTA.Q_CAP(CHIPS)':
 'B': CDS_PINID='B';
NODE_NAME     U21 8
 '@SCM_LIB.SCM(SCH_1):PAGE44_I296@PURE_QUANTA.IDTQS3VH257PAG(CHIPS)':
 'GND': CDS_PINID='GND';
NODE_NAME     R866 2
 '@SCM_LIB.SCM(SCH_1):PAGE44_I311@PURE_QUANTA.Q_RES(CHIPS)':
 'B': CDS_PINID='B';
NODE_NAME     R467 2
 '@SCM_LIB.SCM(SCH_1):PAGE44_I313@PURE_QUANTA.Q_RES(CHIPS)':
 'B': CDS_PINID='B';
NODE_NAME     C244 2
 '@SCM_LIB.SCM(SCH_1):PAGE45_I42@PURE_QUANTA.Q_CAP(CHIPS)':
 'B': CDS_PINID='B';
NODE_NAME     C246 2
 '@SCM_LIB.SCM(SCH_1):PAGE45_I45@PURE_QUANTA.Q_CAP(CHIPS)':
 'B': CDS_PINID='B';
NODE_NAME     R487 2
 '@SCM_LIB.SCM(SCH_1):PAGE45_I51@PURE_QUANTA.Q_RES(CHIPS)':
 'B': CDS_PINID='B';
NODE_NAME     J40 10
 '@SCM_LIB.SCM(SCH_1):PAGE45_I53@PURE_QUANTA.SCONN16_ACASPI006P06(CHIPS)':
 'GND': CDS_PINID='GND';
NODE_NAME     J5 11
 '@SCM_LIB.SCM(SCH_1):PAGE46_I56@PURE_QUANTA.SCONN11_9192031111LF(CHIPS)':
 '11': CDS_PINID='\11\';
NODE_NAME     J5 G1
 '@SCM_LIB.SCM(SCH_1):PAGE46_I56@PURE_QUANTA.SCONN11_9192031111LF(CHIPS)':
 'G1': CDS_PINID='G1';
NODE_NAME     J5 G2
 '@SCM_LIB.SCM(SCH_1):PAGE46_I56@PURE_QUANTA.SCONN11_9192031111LF(CHIPS)':
 'G2': CDS_PINID='G2';
NODE_NAME     C249 2
 '@SCM_LIB.SCM(SCH_1):PAGE46_I67@PURE_QUANTA.Q_CAP(CHIPS)':
 'B': CDS_PINID='B';
NODE_NAME     C248 2
 '@SCM_LIB.SCM(SCH_1):PAGE46_I69@PURE_QUANTA.Q_CAP(CHIPS)':
 'B': CDS_PINID='B';
NODE_NAME     C144 2
 '@SCM_LIB.SCM(SCH_1):PAGE46_I102@PURE_QUANTA.Q_CAP(CHIPS)':
 'B': CDS_PINID='B';
NODE_NAME     C143 2
 '@SCM_LIB.SCM(SCH_1):PAGE46_I108@PURE_QUANTA.Q_CAP(CHIPS)':
 'B': CDS_PINID='B';
NODE_NAME     J10 11
 '@SCM_LIB.SCM(SCH_1):PAGE46_I113@PURE_QUANTA.SCONN11_9192031111LF(CHIPS)':
 '11': CDS_PINID='\11\';
NODE_NAME     J10 G1
 '@SCM_LIB.SCM(SCH_1):PAGE46_I113@PURE_QUANTA.SCONN11_9192031111LF(CHIPS)':
 'G1': CDS_PINID='G1';
NODE_NAME     J10 G2
 '@SCM_LIB.SCM(SCH_1):PAGE46_I113@PURE_QUANTA.SCONN11_9192031111LF(CHIPS)':
 'G2': CDS_PINID='G2';
NODE_NAME     D7 C
 '@SCM_LIB.SCM(SCH_1):PAGE47_I5@PURE_QUANTA.Q_LED(CHIPS)':
 'C': CDS_PINID='C';
NODE_NAME     D0 C
 '@SCM_LIB.SCM(SCH_1):PAGE47_I7@PURE_QUANTA.Q_LED(CHIPS)':
 'C': CDS_PINID='C';
NODE_NAME     D1 C
 '@SCM_LIB.SCM(SCH_1):PAGE47_I9@PURE_QUANTA.Q_LED(CHIPS)':
 'C': CDS_PINID='C';
NODE_NAME     D4 C
 '@SCM_LIB.SCM(SCH_1):PAGE47_I10@PURE_QUANTA.Q_LED(CHIPS)':
 'C': CDS_PINID='C';
NODE_NAME     D2 C
 '@SCM_LIB.SCM(SCH_1):PAGE47_I11@PURE_QUANTA.Q_LED(CHIPS)':
 'C': CDS_PINID='C';
NODE_NAME     D5 C
 '@SCM_LIB.SCM(SCH_1):PAGE47_I12@PURE_QUANTA.Q_LED(CHIPS)':
 'C': CDS_PINID='C';
NODE_NAME     D3 C
 '@SCM_LIB.SCM(SCH_1):PAGE47_I13@PURE_QUANTA.Q_LED(CHIPS)':
 'C': CDS_PINID='C';
NODE_NAME     D6 C
 '@SCM_LIB.SCM(SCH_1):PAGE47_I14@PURE_QUANTA.Q_LED(CHIPS)':
 'C': CDS_PINID='C';
NODE_NAME     U9 3
 '@SCM_LIB.SCM(SCH_1):PAGE49_I5@PURE_QUANTA.MC74VHC1G32DTT1G(CHIPS)':
 'GND': CDS_PINID='GND';
NODE_NAME     Q9 1
 '@SCM_LIB.SCM(SCH_1):PAGE49_I6@PURE_QUANTA.MOSFET_NCH_DUAL(CHIPS)':
 'S1': CDS_PINID='S1';
NODE_NAME     R306 2
 '@SCM_LIB.SCM(SCH_1):PAGE49_I8@PURE_QUANTA.Q_RES(CHIPS)':
 'B': CDS_PINID='B';
NODE_NAME     U8 3
 '@SCM_LIB.SCM(SCH_1):PAGE49_I11@PURE_QUANTA.74LVC1G126SE7(CHIPS)':
 'GND': CDS_PINID='GND';
NODE_NAME     C274 2
 '@SCM_LIB.SCM(SCH_1):PAGE49_I13@PURE_QUANTA.Q_CAP(CHIPS)':
 'B': CDS_PINID='B';
NODE_NAME     R839 2
 '@SCM_LIB.SCM(SCH_1):PAGE49_I22@PURE_QUANTA.Q_RES(CHIPS)':
 'B': CDS_PINID='B';
NODE_NAME     Q12 1
 '@SCM_LIB.SCM(SCH_1):PAGE49_I24@PURE_QUANTA.MOSFET_DUAL_6P(CHIPS)':
 'S1': CDS_PINID='S1';
NODE_NAME     Q12 4
 '@SCM_LIB.SCM(SCH_1):PAGE49_I24@PURE_QUANTA.MOSFET_DUAL_6P(CHIPS)':
 'S2': CDS_PINID='S2';
NODE_NAME     R619 2
 '@SCM_LIB.SCM(SCH_1):PAGE49_I26@PURE_QUANTA.Q_RES(CHIPS)':
 'B': CDS_PINID='B';
NODE_NAME     C324 2
 '@SCM_LIB.SCM(SCH_1):PAGE49_I37@PURE_QUANTA.Q_CAP(CHIPS)':
 'B': CDS_PINID='B';
NODE_NAME     C326 2
 '@SCM_LIB.SCM(SCH_1):PAGE49_I38@PURE_QUANTA.Q_CAP(CHIPS)':
 'B': CDS_PINID='B';
NODE_NAME     C321 2
 '@SCM_LIB.SCM(SCH_1):PAGE49_I43@PURE_QUANTA.Q_CAP(CHIPS)':
 'B': CDS_PINID='B';
NODE_NAME     C197 2
 '@SCM_LIB.SCM(SCH_1):PAGE49_I45@PURE_QUANTA.Q_CAP(CHIPS)':
 'B': CDS_PINID='B';
NODE_NAME     C276 2
 '@SCM_LIB.SCM(SCH_1):PAGE49_I75@PURE_QUANTA.Q_CAP(CHIPS)':
 'B': CDS_PINID='B';
NODE_NAME     C200 2
 '@SCM_LIB.SCM(SCH_1):PAGE50_I43@PURE_QUANTA.Q_CAP(CHIPS)':
 'B': CDS_PINID='B';
NODE_NAME     C198 2
 '@SCM_LIB.SCM(SCH_1):PAGE50_I44@PURE_QUANTA.Q_CAP(CHIPS)':
 'B': CDS_PINID='B';
NODE_NAME     U32 3
 '@SCM_LIB.SCM(SCH_1):PAGE50_I49@PURE_QUANTA.74LVC1G17GW(CHIPS)':
 'GND': CDS_PINID='GND';
NODE_NAME     C201 2
 '@SCM_LIB.SCM(SCH_1):PAGE50_I51@PURE_QUANTA.Q_CAP(CHIPS)':
 'B': CDS_PINID='B';
NODE_NAME     C199 2
 '@SCM_LIB.SCM(SCH_1):PAGE50_I55@PURE_QUANTA.Q_CAP(CHIPS)':
 'B': CDS_PINID='B';
NODE_NAME     U31 3
 '@SCM_LIB.SCM(SCH_1):PAGE50_I151@PURE_QUANTA.74LVC1G07GW(CHIPS)':
 'GND': CDS_PINID='GND';
NODE_NAME     C196 2
 '@SCM_LIB.SCM(SCH_1):PAGE50_I165@PURE_QUANTA.Q_CAP(CHIPS)':
 'B': CDS_PINID='B';
NODE_NAME     PC205 2
 '@SCM_LIB.SCM(SCH_1):PAGE51_I1@PURE_QUANTA.Q_CAP(CHIPS)':
 'B': CDS_PINID='B';
NODE_NAME     PR522 2
 '@SCM_LIB.SCM(SCH_1):PAGE51_I3@PURE_QUANTA.Q_RES(CHIPS)':
 'B': CDS_PINID='B';
NODE_NAME     PR525 2
 '@SCM_LIB.SCM(SCH_1):PAGE51_I9@PURE_QUANTA.Q_RES(CHIPS)':
 'B': CDS_PINID='B';
NODE_NAME     PC208 2
 '@SCM_LIB.SCM(SCH_1):PAGE51_I13@PURE_QUANTA.Q_CAP(CHIPS)':
 'B': CDS_PINID='B';
NODE_NAME     PC271 2
 '@SCM_LIB.SCM(SCH_1):PAGE51_I22@PURE_QUANTA.Q_CAP(CHIPS)':
 'B': CDS_PINID='B';
NODE_NAME     PR526 2
 '@SCM_LIB.SCM(SCH_1):PAGE51_I26@PURE_QUANTA.Q_RES(CHIPS)':
 'B': CDS_PINID='B';
NODE_NAME     PC212 2
 '@SCM_LIB.SCM(SCH_1):PAGE51_I31@PURE_QUANTA.Q_CAP(CHIPS)':
 'B': CDS_PINID='B';
NODE_NAME     PC213 2
 '@SCM_LIB.SCM(SCH_1):PAGE51_I32@PURE_QUANTA.Q_CAP(CHIPS)':
 'B': CDS_PINID='B';
NODE_NAME     PC214 2
 '@SCM_LIB.SCM(SCH_1):PAGE51_I33@PURE_QUANTA.Q_CAP(CHIPS)':
 'B': CDS_PINID='B';
NODE_NAME     PC215 2
 '@SCM_LIB.SCM(SCH_1):PAGE51_I36@PURE_QUANTA.Q_CAP(CHIPS)':
 'B': CDS_PINID='B';
NODE_NAME     PC217 2
 '@SCM_LIB.SCM(SCH_1):PAGE51_I37@PURE_QUANTA.Q_CAP(CHIPS)':
 'B': CDS_PINID='B';
NODE_NAME     PU38 2
 '@SCM_LIB.SCM(SCH_1):PAGE51_I42@PURE_QUANTA.MPQ8633AGLEC807Z(CHIPS)':
 'AGND': CDS_PINID='AGND';
NODE_NAME     PU38 4
 '@SCM_LIB.SCM(SCH_1):PAGE51_I42@PURE_QUANTA.MPQ8633AGLEC807Z(CHIPS)':
 'MODE': CDS_PINID='MODE';
NODE_NAME     PU38 11_18
 '@SCM_LIB.SCM(SCH_1):PAGE51_I42@PURE_QUANTA.MPQ8633AGLEC807Z(CHIPS)':
 'PGND': CDS_PINID='PGND';
NODE_NAME     PU38 6
 '@SCM_LIB.SCM(SCH_1):PAGE51_I42@PURE_QUANTA.MPQ8633AGLEC807Z(CHIPS)':
 'RGND': CDS_PINID='RGND';
NODE_NAME     PR245 2
 '@SCM_LIB.SCM(SCH_1):PAGE51_I43@PURE_QUANTA.Q_RES(CHIPS)':
 'B': CDS_PINID='B';
NODE_NAME     PC210 2
 '@SCM_LIB.SCM(SCH_1):PAGE51_I45@PURE_QUANTA.Q_CAP(CHIPS)':
 'B': CDS_PINID='B';
NODE_NAME     PC206 2
 '@SCM_LIB.SCM(SCH_1):PAGE51_I47@PURE_QUANTA.Q_CAP(CHIPS)':
 'B': CDS_PINID='B';
NODE_NAME     PC207 2
 '@SCM_LIB.SCM(SCH_1):PAGE51_I48@PURE_QUANTA.Q_CAP(CHIPS)':
 'B': CDS_PINID='B';
NODE_NAME     C150 2
 '@SCM_LIB.SCM(SCH_1):PAGE51_I49@PURE_QUANTA.Q_CAP(CHIPS)':
 'B': CDS_PINID='B';
NODE_NAME     C241 2
 '@SCM_LIB.SCM(SCH_1):PAGE51_I52@PURE_QUANTA.Q_CAP(CHIPS)':
 'B': CDS_PINID='B';
NODE_NAME     PC221 2
 '@SCM_LIB.SCM(SCH_1):PAGE52_I9@PURE_QUANTA.Q_CAP(CHIPS)':
 'B': CDS_PINID='B';
NODE_NAME     PC223 2
 '@SCM_LIB.SCM(SCH_1):PAGE52_I11@PURE_QUANTA.Q_CAP(CHIPS)':
 'B': CDS_PINID='B';
NODE_NAME     PR530 1
 '@SCM_LIB.SCM(SCH_1):PAGE52_I17@PURE_QUANTA.Q_RES(CHIPS)':
 'A': CDS_PINID='A';
NODE_NAME     PC225 2
 '@SCM_LIB.SCM(SCH_1):PAGE52_I23@PURE_QUANTA.Q_CAP(CHIPS)':
 'B': CDS_PINID='B';
NODE_NAME     PC226 2
 '@SCM_LIB.SCM(SCH_1):PAGE52_I35@PURE_QUANTA.Q_CAP(CHIPS)':
 'B': CDS_PINID='B';
NODE_NAME     PC227 2
 '@SCM_LIB.SCM(SCH_1):PAGE52_I36@PURE_QUANTA.Q_CAP(CHIPS)':
 'B': CDS_PINID='B';
NODE_NAME     PC228 2
 '@SCM_LIB.SCM(SCH_1):PAGE52_I37@PURE_QUANTA.Q_CAP(CHIPS)':
 'B': CDS_PINID='B';
NODE_NAME     PC229 2
 '@SCM_LIB.SCM(SCH_1):PAGE52_I38@PURE_QUANTA.Q_CAP(CHIPS)':
 'B': CDS_PINID='B';
NODE_NAME     C240 2
 '@SCM_LIB.SCM(SCH_1):PAGE52_I63@PURE_QUANTA.Q_CAP(CHIPS)':
 'B': CDS_PINID='B';
NODE_NAME     C251 2
 '@SCM_LIB.SCM(SCH_1):PAGE52_I66@PURE_QUANTA.Q_CAP(CHIPS)':
 'B': CDS_PINID='B';
NODE_NAME     C252 2
 '@SCM_LIB.SCM(SCH_1):PAGE52_I73@PURE_QUANTA.Q_CAP(CHIPS)':
 'B': CDS_PINID='B';
NODE_NAME     U14 2
 '@SCM_LIB.SCM(SCH_1):PAGE52_I79@PURE_QUANTA.AP22811AW57(CHIPS)':
 'GND': CDS_PINID='GND';
NODE_NAME     PC219 2
 '@SCM_LIB.SCM(SCH_1):PAGE52_I80@PURE_QUANTA.Q_CAP(CHIPS)':
 'B': CDS_PINID='B';
NODE_NAME     PC218 2
 '@SCM_LIB.SCM(SCH_1):PAGE52_I81@PURE_QUANTA.Q_CAP(CHIPS)':
 'B': CDS_PINID='B';
NODE_NAME     PU1 7
 '@SCM_LIB.SCM(SCH_1):PAGE52_I82@PURE_QUANTA.MPQ8626GDZ(CHIPS)':
 'AGND': CDS_PINID='AGND';
NODE_NAME     PU1 1
 '@SCM_LIB.SCM(SCH_1):PAGE52_I82@PURE_QUANTA.MPQ8626GDZ(CHIPS)':
 'PGND1': CDS_PINID='PGND1';
NODE_NAME     PU1 14
 '@SCM_LIB.SCM(SCH_1):PAGE52_I82@PURE_QUANTA.MPQ8626GDZ(CHIPS)':
 'PGND2': CDS_PINID='PGND2';
NODE_NAME     PC273 2
 '@SCM_LIB.SCM(SCH_1):PAGE52_I86@PURE_QUANTA.Q_CAP(CHIPS)':
 'B': CDS_PINID='B';
NODE_NAME     PR276 1
 '@SCM_LIB.SCM(SCH_1):PAGE52_I87@PURE_QUANTA.Q_RES(CHIPS)':
 'A': CDS_PINID='A';
NODE_NAME     PR532 1
 '@SCM_LIB.SCM(SCH_1):PAGE52_I88@PURE_QUANTA.Q_RES(CHIPS)':
 'A': CDS_PINID='A';
NODE_NAME     C151 2
 '@SCM_LIB.SCM(SCH_1):PAGE52_I93@PURE_QUANTA.Q_CAP(CHIPS)':
 'B': CDS_PINID='B';
NODE_NAME     C262 2
 '@SCM_LIB.SCM(SCH_1):PAGE52_I101@PURE_QUANTA.Q_CAP(CHIPS)':
 'B': CDS_PINID='B';
NODE_NAME     C265 2
 '@SCM_LIB.SCM(SCH_1):PAGE52_I102@PURE_QUANTA.Q_CAP(CHIPS)':
 'B': CDS_PINID='B';
NODE_NAME     U39 TH
 '@SCM_LIB.SCM(SCH_1):PAGE53_I60@PURE_QUANTA.RT9059GQW(CHIPS)':
 'EP': CDS_PINID='EP';
NODE_NAME     R830 2
 '@SCM_LIB.SCM(SCH_1):PAGE53_I61@PURE_QUANTA.Q_RES(CHIPS)':
 'B': CDS_PINID='B';
NODE_NAME     C153 2
 '@SCM_LIB.SCM(SCH_1):PAGE53_I64@PURE_QUANTA.Q_CAP(CHIPS)':
 'B': CDS_PINID='B';
NODE_NAME     U41 TH
 '@SCM_LIB.SCM(SCH_1):PAGE54_I96@PURE_QUANTA.RT9059GQW(CHIPS)':
 'EP': CDS_PINID='EP';
NODE_NAME     R832 2
 '@SCM_LIB.SCM(SCH_1):PAGE54_I97@PURE_QUANTA.Q_RES(CHIPS)':
 'B': CDS_PINID='B';
NODE_NAME     C154 2
 '@SCM_LIB.SCM(SCH_1):PAGE54_I100@PURE_QUANTA.Q_CAP(CHIPS)':
 'B': CDS_PINID='B';
NODE_NAME     PR496 2
 '@SCM_LIB.SCM(SCH_1):PAGE55_I6@PURE_QUANTA.Q_RES(CHIPS)':
 'B': CDS_PINID='B';
NODE_NAME     PC250 2
 '@SCM_LIB.SCM(SCH_1):PAGE55_I7@PURE_QUANTA.Q_CAP(CHIPS)':
 'B': CDS_PINID='B';
NODE_NAME     PU41 11
 '@SCM_LIB.SCM(SCH_1):PAGE55_I15@PURE_QUANTA.NB695GDZ(CHIPS)':
 'AGND': CDS_PINID='AGND';
NODE_NAME     PU41 4
 '@SCM_LIB.SCM(SCH_1):PAGE55_I15@PURE_QUANTA.NB695GDZ(CHIPS)':
 'C0': CDS_PINID='C0';
NODE_NAME     PU41 3
 '@SCM_LIB.SCM(SCH_1):PAGE55_I15@PURE_QUANTA.NB695GDZ(CHIPS)':
 'C1': CDS_PINID='C1';
NODE_NAME     PU41 2
 '@SCM_LIB.SCM(SCH_1):PAGE55_I15@PURE_QUANTA.NB695GDZ(CHIPS)':
 'PGND': CDS_PINID='PGND';
NODE_NAME     PC253 2
 '@SCM_LIB.SCM(SCH_1):PAGE55_I16@PURE_QUANTA.Q_CAP(CHIPS)':
 'B': CDS_PINID='B';
NODE_NAME     PC255 2
 '@SCM_LIB.SCM(SCH_1):PAGE55_I23@PURE_QUANTA.Q_CAP(CHIPS)':
 'B': CDS_PINID='B';
NODE_NAME     PC256 2
 '@SCM_LIB.SCM(SCH_1):PAGE55_I24@PURE_QUANTA.Q_CAP(CHIPS)':
 'B': CDS_PINID='B';
NODE_NAME     PC257 2
 '@SCM_LIB.SCM(SCH_1):PAGE55_I25@PURE_QUANTA.Q_CAP(CHIPS)':
 'B': CDS_PINID='B';
NODE_NAME     PC258 2
 '@SCM_LIB.SCM(SCH_1):PAGE55_I28@PURE_QUANTA.Q_CAP(CHIPS)':
 'B': CDS_PINID='B';
NODE_NAME     PC259 2
 '@SCM_LIB.SCM(SCH_1):PAGE55_I29@PURE_QUANTA.Q_CAP(CHIPS)':
 'B': CDS_PINID='B';
NODE_NAME     PC252 2
 '@SCM_LIB.SCM(SCH_1):PAGE55_I42@PURE_QUANTA.Q_CAP(CHIPS)':
 'B': CDS_PINID='B';
NODE_NAME     PC251 2
 '@SCM_LIB.SCM(SCH_1):PAGE55_I43@PURE_QUANTA.Q_CAP(CHIPS)':
 'B': CDS_PINID='B';
NODE_NAME     C155 2
 '@SCM_LIB.SCM(SCH_1):PAGE55_I52@PURE_QUANTA.Q_CAP(CHIPS)':
 'B': CDS_PINID='B';
NODE_NAME     C278 2
 '@SCM_LIB.SCM(SCH_1):PAGE55_I54@PURE_QUANTA.Q_CAP(CHIPS)':
 'B': CDS_PINID='B';
NODE_NAME     PC260 2
 '@SCM_LIB.SCM(SCH_1):PAGE56_I7@PURE_QUANTA.Q_CAP(CHIPS)':
 'B': CDS_PINID='B';
NODE_NAME     PU42 11
 '@SCM_LIB.SCM(SCH_1):PAGE56_I15@PURE_QUANTA.NB695GDZ(CHIPS)':
 'AGND': CDS_PINID='AGND';
NODE_NAME     PU42 4
 '@SCM_LIB.SCM(SCH_1):PAGE56_I15@PURE_QUANTA.NB695GDZ(CHIPS)':
 'C0': CDS_PINID='C0';
NODE_NAME     PU42 2
 '@SCM_LIB.SCM(SCH_1):PAGE56_I15@PURE_QUANTA.NB695GDZ(CHIPS)':
 'PGND': CDS_PINID='PGND';
NODE_NAME     PC263 2
 '@SCM_LIB.SCM(SCH_1):PAGE56_I16@PURE_QUANTA.Q_CAP(CHIPS)':
 'B': CDS_PINID='B';
NODE_NAME     PC266 2
 '@SCM_LIB.SCM(SCH_1):PAGE56_I23@PURE_QUANTA.Q_CAP(CHIPS)':
 'B': CDS_PINID='B';
NODE_NAME     PC267 2
 '@SCM_LIB.SCM(SCH_1):PAGE56_I24@PURE_QUANTA.Q_CAP(CHIPS)':
 'B': CDS_PINID='B';
NODE_NAME     PC268 2
 '@SCM_LIB.SCM(SCH_1):PAGE56_I25@PURE_QUANTA.Q_CAP(CHIPS)':
 'B': CDS_PINID='B';
NODE_NAME     PC269 2
 '@SCM_LIB.SCM(SCH_1):PAGE56_I28@PURE_QUANTA.Q_CAP(CHIPS)':
 'B': CDS_PINID='B';
NODE_NAME     PC270 2
 '@SCM_LIB.SCM(SCH_1):PAGE56_I29@PURE_QUANTA.Q_CAP(CHIPS)':
 'B': CDS_PINID='B';
NODE_NAME     PC262 2
 '@SCM_LIB.SCM(SCH_1):PAGE56_I43@PURE_QUANTA.Q_CAP(CHIPS)':
 'B': CDS_PINID='B';
NODE_NAME     PC261 2
 '@SCM_LIB.SCM(SCH_1):PAGE56_I44@PURE_QUANTA.Q_CAP(CHIPS)':
 'B': CDS_PINID='B';
NODE_NAME     C156 2
 '@SCM_LIB.SCM(SCH_1):PAGE56_I51@PURE_QUANTA.Q_CAP(CHIPS)':
 'B': CDS_PINID='B';
NODE_NAME     C280 2
 '@SCM_LIB.SCM(SCH_1):PAGE56_I58@PURE_QUANTA.Q_CAP(CHIPS)':
 'B': CDS_PINID='B';
NODE_NAME     H5 1
 '@SCM_LIB.SCM(SCH_1):PAGE57_I35@PURE_QUANTA.HOLE(CHIPS)':
 '1': CDS_PINID='\1\';
NODE_NAME     H9 1
 '@SCM_LIB.SCM(SCH_1):PAGE57_I36@PURE_QUANTA.HOLE(CHIPS)':
 '1': CDS_PINID='\1\';
NODE_NAME     H3 1
 '@SCM_LIB.SCM(SCH_1):PAGE57_I38@PURE_QUANTA.HOLE(CHIPS)':
 '1': CDS_PINID='\1\';
NODE_NAME     H4 1
 '@SCM_LIB.SCM(SCH_1):PAGE57_I40@PURE_QUANTA.HOLE(CHIPS)':
 '1': CDS_PINID='\1\';
NODE_NAME     R53 2
 '@SCM_LIB.SCM(SCH_1):PAGE26_I66@PURE_QUANTA.Q_RES(CHIPS)':
 'B': CDS_PINID='B';
NODE_NAME     J8 2
 '@SCM_LIB.SCM(SCH_1):PAGE23_I165@PURE_QUANTA.SCONN13_502280130CV01(CHIPS)':
 '2': CDS_PINID='\2\';
NODE_NAME     J8 4
 '@SCM_LIB.SCM(SCH_1):PAGE23_I165@PURE_QUANTA.SCONN13_502280130CV01(CHIPS)':
 '4': CDS_PINID='\4\';
NODE_NAME     J8 6
 '@SCM_LIB.SCM(SCH_1):PAGE23_I165@PURE_QUANTA.SCONN13_502280130CV01(CHIPS)':
 '6': CDS_PINID='\6\';
NODE_NAME     J8 8
 '@SCM_LIB.SCM(SCH_1):PAGE23_I165@PURE_QUANTA.SCONN13_502280130CV01(CHIPS)':
 '8': CDS_PINID='\8\';
NODE_NAME     J8 10
 '@SCM_LIB.SCM(SCH_1):PAGE23_I165@PURE_QUANTA.SCONN13_502280130CV01(CHIPS)':
 '10': CDS_PINID='\10\';
NODE_NAME     J8 G1
 '@SCM_LIB.SCM(SCH_1):PAGE23_I165@PURE_QUANTA.SCONN13_502280130CV01(CHIPS)':
 'G1': CDS_PINID='G1';
NODE_NAME     J8 G2
 '@SCM_LIB.SCM(SCH_1):PAGE23_I165@PURE_QUANTA.SCONN13_502280130CV01(CHIPS)':
 'G2': CDS_PINID='G2';
NODE_NAME     R202 1
 '@SCM_LIB.SCM(SCH_1):PAGE32_I140@PURE_QUANTA.Q_RES(CHIPS)':
 'A': CDS_PINID='A';
NODE_NAME     R285 2
 '@SCM_LIB.SCM(SCH_1):PAGE32_I141@PURE_QUANTA.Q_RES(CHIPS)':
 'B': CDS_PINID='B';
NODE_NAME     C22 2
 '@SCM_LIB.SCM(SCH_1):PAGE12_I448@PURE_QUANTA.Q_CAP(CHIPS)':
 'B': CDS_PINID='B';
NODE_NAME     R312 2
 '@SCM_LIB.SCM(SCH_1):PAGE12_I456@PURE_QUANTA.Q_RES(CHIPS)':
 'B': CDS_PINID='B';
NODE_NAME     C142 2
 '@SCM_LIB.SCM(SCH_1):PAGE54_I104@PURE_QUANTA.Q_CAP(CHIPS)':
 'B': CDS_PINID='B';
NODE_NAME     C294 2
 '@SCM_LIB.SCM(SCH_1):PAGE54_I105@PURE_QUANTA.Q_CAP(CHIPS)':
 'B': CDS_PINID='B';
NODE_NAME     C293 2
 '@SCM_LIB.SCM(SCH_1):PAGE54_I106@PURE_QUANTA.Q_CAP(CHIPS)':
 'B': CDS_PINID='B';
NODE_NAME     C292 2
 '@SCM_LIB.SCM(SCH_1):PAGE54_I107@PURE_QUANTA.Q_CAP(CHIPS)':
 'B': CDS_PINID='B';
NODE_NAME     C287 2
 '@SCM_LIB.SCM(SCH_1):PAGE53_I67@PURE_QUANTA.Q_CAP(CHIPS)':
 'B': CDS_PINID='B';
NODE_NAME     C289 2
 '@SCM_LIB.SCM(SCH_1):PAGE53_I69@PURE_QUANTA.Q_CAP(CHIPS)':
 'B': CDS_PINID='B';
NODE_NAME     C291 2
 '@SCM_LIB.SCM(SCH_1):PAGE53_I70@PURE_QUANTA.Q_CAP(CHIPS)':
 'B': CDS_PINID='B';
NODE_NAME     C288 2
 '@SCM_LIB.SCM(SCH_1):PAGE53_I71@PURE_QUANTA.Q_CAP(CHIPS)':
 'B': CDS_PINID='B';
NODE_NAME     R206 1
 '@SCM_LIB.SCM(SCH_1):PAGE32_I143@PURE_QUANTA.Q_RES(CHIPS)':
 'A': CDS_PINID='A';
NODE_NAME     R441 2
 '@SCM_LIB.SCM(SCH_1):PAGE15_I353@PURE_QUANTA.Q_RES(CHIPS)':
 'B': CDS_PINID='B';
NODE_NAME     R440 2
 '@SCM_LIB.SCM(SCH_1):PAGE15_I354@PURE_QUANTA.Q_RES(CHIPS)':
 'B': CDS_PINID='B';
NODE_NAME     U17 10
 '@SCM_LIB.SCM(SCH_1):PAGE45_I54@PURE_QUANTA.MX25L51245GMI10G(CHIPS)':
 'GND': CDS_PINID='GND';
NODE_NAME     C298 2
 '@SCM_LIB.SCM(SCH_1):PAGE54_I112@PURE_QUANTA.Q_CAP(CHIPS)':
 'B': CDS_PINID='B';
NODE_NAME     U49 3
 '@SCM_LIB.SCM(SCH_1):PAGE54_I116@PURE_QUANTA.MC74VHC1G32DTT1G(CHIPS)':
 'GND': CDS_PINID='GND';
NODE_NAME     C302 2
 '@SCM_LIB.SCM(SCH_1):PAGE56_I64@PURE_QUANTA.Q_CAP(CHIPS)':
 'B': CDS_PINID='B';
NODE_NAME     U53 3
 '@SCM_LIB.SCM(SCH_1):PAGE56_I66@PURE_QUANTA.74LVC1G08GW(CHIPS)':
 'GND': CDS_PINID='GND';
NODE_NAME     C301 2
 '@SCM_LIB.SCM(SCH_1):PAGE55_I61@PURE_QUANTA.Q_CAP(CHIPS)':
 'B': CDS_PINID='B';
NODE_NAME     U52 3
 '@SCM_LIB.SCM(SCH_1):PAGE55_I63@PURE_QUANTA.74LVC1G08GW(CHIPS)':
 'GND': CDS_PINID='GND';
NODE_NAME     U42 3
 '@SCM_LIB.SCM(SCH_1):PAGE52_I104@PURE_QUANTA.MC74VHC1G32DTT1G(CHIPS)':
 'GND': CDS_PINID='GND';
NODE_NAME     C297 2
 '@SCM_LIB.SCM(SCH_1):PAGE52_I107@PURE_QUANTA.Q_CAP(CHIPS)':
 'B': CDS_PINID='B';
NODE_NAME     U18 3
 '@SCM_LIB.SCM(SCH_1):PAGE52_I114@PURE_QUANTA.74LVC1G08GW(CHIPS)':
 'GND': CDS_PINID='GND';
NODE_NAME     C296 2
 '@SCM_LIB.SCM(SCH_1):PAGE52_I119@PURE_QUANTA.Q_CAP(CHIPS)':
 'B': CDS_PINID='B';
NODE_NAME     C305 2
 '@SCM_LIB.SCM(SCH_1):PAGE52_I125@PURE_QUANTA.Q_CAP(CHIPS)':
 'B': CDS_PINID='B';
NODE_NAME     C310 2
 '@SCM_LIB.SCM(SCH_1):PAGE54_I130@PURE_QUANTA.Q_CAP(CHIPS)':
 'B': CDS_PINID='B';
NODE_NAME     U54 4
 '@SCM_LIB.SCM(SCH_1):PAGE25_I138@PURE_QUANTA.74LVC1G74DP(CHIPS)':
 'GND': CDS_PINID='GND';
NODE_NAME     R182 1
 '@SCM_LIB.SCM(SCH_1):PAGE25_I142@PURE_QUANTA.Q_RES(CHIPS)':
 'A': CDS_PINID='A';
NODE_NAME     R545 1
 '@SCM_LIB.SCM(SCH_1):PAGE25_I143@PURE_QUANTA.Q_RES(CHIPS)':
 'A': CDS_PINID='A';
NODE_NAME     C312 2
 '@SCM_LIB.SCM(SCH_1):PAGE25_I146@PURE_QUANTA.Q_CAP(CHIPS)':
 'B': CDS_PINID='B';
NODE_NAME     U55 3
 '@SCM_LIB.SCM(SCH_1):PAGE25_I150@PURE_QUANTA.SN74LVC1G14DCKR(CHIPS)':
 'GND': CDS_PINID='GND';
NODE_NAME     C313 2
 '@SCM_LIB.SCM(SCH_1):PAGE25_I154@PURE_QUANTA.Q_CAP(CHIPS)':
 'B': CDS_PINID='B';
NODE_NAME     U43 2
 '@SCM_LIB.SCM(SCH_1):PAGE22_I90@PURE_QUANTA.TPS3808G18DBVR(CHIPS)':
 'GND': CDS_PINID='GND';
NODE_NAME     J4 1
 '@SCM_LIB.SCM(SCH_1):PAGE21_I84@PURE_QUANTA.SCONN67_NASA0S6730TS67(CHIPS)':
 '1': CDS_PINID='\1\';
NODE_NAME     J4 7
 '@SCM_LIB.SCM(SCH_1):PAGE21_I84@PURE_QUANTA.SCONN67_NASA0S6730TS67(CHIPS)':
 '7': CDS_PINID='\7\';
NODE_NAME     J4 18
 '@SCM_LIB.SCM(SCH_1):PAGE21_I84@PURE_QUANTA.SCONN67_NASA0S6730TS67(CHIPS)':
 '18': CDS_PINID='\18\';
NODE_NAME     J4 23
 '@SCM_LIB.SCM(SCH_1):PAGE21_I84@PURE_QUANTA.SCONN67_NASA0S6730TS67(CHIPS)':
 '23': CDS_PINID='\23\';
NODE_NAME     J4 24
 '@SCM_LIB.SCM(SCH_1):PAGE21_I84@PURE_QUANTA.SCONN67_NASA0S6730TS67(CHIPS)':
 '24': CDS_PINID='\24\';
NODE_NAME     J4 29
 '@SCM_LIB.SCM(SCH_1):PAGE21_I84@PURE_QUANTA.SCONN67_NASA0S6730TS67(CHIPS)':
 '29': CDS_PINID='\29\';
NODE_NAME     J4 30
 '@SCM_LIB.SCM(SCH_1):PAGE21_I84@PURE_QUANTA.SCONN67_NASA0S6730TS67(CHIPS)':
 '30': CDS_PINID='\30\';
NODE_NAME     J4 33
 '@SCM_LIB.SCM(SCH_1):PAGE21_I84@PURE_QUANTA.SCONN67_NASA0S6730TS67(CHIPS)':
 '33': CDS_PINID='\33\';
NODE_NAME     J4 36
 '@SCM_LIB.SCM(SCH_1):PAGE21_I84@PURE_QUANTA.SCONN67_NASA0S6730TS67(CHIPS)':
 '36': CDS_PINID='\36\';
NODE_NAME     J4 39
 '@SCM_LIB.SCM(SCH_1):PAGE21_I84@PURE_QUANTA.SCONN67_NASA0S6730TS67(CHIPS)':
 '39': CDS_PINID='\39\';
NODE_NAME     J4 45
 '@SCM_LIB.SCM(SCH_1):PAGE21_I84@PURE_QUANTA.SCONN67_NASA0S6730TS67(CHIPS)':
 '45': CDS_PINID='\45\';
NODE_NAME     J4 51
 '@SCM_LIB.SCM(SCH_1):PAGE21_I84@PURE_QUANTA.SCONN67_NASA0S6730TS67(CHIPS)':
 '51': CDS_PINID='\51\';
NODE_NAME     J4 57
 '@SCM_LIB.SCM(SCH_1):PAGE21_I84@PURE_QUANTA.SCONN67_NASA0S6730TS67(CHIPS)':
 '57': CDS_PINID='\57\';
NODE_NAME     J4 63
 '@SCM_LIB.SCM(SCH_1):PAGE21_I84@PURE_QUANTA.SCONN67_NASA0S6730TS67(CHIPS)':
 '63': CDS_PINID='\63\';
NODE_NAME     J4 69
 '@SCM_LIB.SCM(SCH_1):PAGE21_I84@PURE_QUANTA.SCONN67_NASA0S6730TS67(CHIPS)':
 '69': CDS_PINID='\69\';
NODE_NAME     J4 75
 '@SCM_LIB.SCM(SCH_1):PAGE21_I84@PURE_QUANTA.SCONN67_NASA0S6730TS67(CHIPS)':
 '75': CDS_PINID='\75\';
NODE_NAME     J4 G1
 '@SCM_LIB.SCM(SCH_1):PAGE21_I84@PURE_QUANTA.SCONN67_NASA0S6730TS67(CHIPS)':
 'G1': CDS_PINID='G1';
NODE_NAME     J4 G2
 '@SCM_LIB.SCM(SCH_1):PAGE21_I84@PURE_QUANTA.SCONN67_NASA0S6730TS67(CHIPS)':
 'G2': CDS_PINID='G2';
NODE_NAME     SW7 1
 '@SCM_LIB.SCM(SCH_1):PAGE50_I204@PURE_QUANTA.SW_PUSHBUTTON4P_12_G34_H2(CHIPS)':
 '1': CDS_PINID='\1\';
NODE_NAME     SW7 3
 '@SCM_LIB.SCM(SCH_1):PAGE50_I204@PURE_QUANTA.SW_PUSHBUTTON4P_12_G34_H2(CHIPS)':
 '3': CDS_PINID='\3\';
NODE_NAME     SW7 4
 '@SCM_LIB.SCM(SCH_1):PAGE50_I204@PURE_QUANTA.SW_PUSHBUTTON4P_12_G34_H2(CHIPS)':
 '4': CDS_PINID='\4\';
NODE_NAME     R665 2
 '@SCM_LIB.SCM(SCH_1):PAGE21_I125@PURE_QUANTA.Q_RES(CHIPS)':
 'B': CDS_PINID='B';
NODE_NAME     R664 2
 '@SCM_LIB.SCM(SCH_1):PAGE21_I128@PURE_QUANTA.Q_RES(CHIPS)':
 'B': CDS_PINID='B';
NODE_NAME     U7 2
 '@SCM_LIB.SCM(SCH_1):PAGE31_I27@PURE_QUANTA.NC7SB3157(CHIPS)':
 'GND': CDS_PINID='GND';
NODE_NAME     C11 2
 '@SCM_LIB.SCM(SCH_1):PAGE31_I31@PURE_QUANTA.Q_CAP(CHIPS)':
 'B': CDS_PINID='B';
NODE_NAME     U20 2
 '@SCM_LIB.SCM(SCH_1):PAGE31_I38@PURE_QUANTA.NC7SB3157(CHIPS)':
 'GND': CDS_PINID='GND';
NODE_NAME     C231 2
 '@SCM_LIB.SCM(SCH_1):PAGE31_I45@PURE_QUANTA.Q_CAP(CHIPS)':
 'B': CDS_PINID='B';
NODE_NAME     C256 2
 '@SCM_LIB.SCM(SCH_1):PAGE34_I140@PURE_QUANTA.Q_CAP(CHIPS)':
 'B': CDS_PINID='B';
NODE_NAME     C257 2
 '@SCM_LIB.SCM(SCH_1):PAGE34_I144@PURE_QUANTA.Q_CAP(CHIPS)':
 'B': CDS_PINID='B';
NODE_NAME     PR543 2
 '@SCM_LIB.SCM(SCH_1):PAGE56_I71@PURE_QUANTA.Q_RES(CHIPS)':
 'B': CDS_PINID='B';
NODE_NAME     C40 2
 '@SCM_LIB.SCM(SCH_1):PAGE15_I368@PURE_QUANTA.Q_CAP(CHIPS)':
 'B': CDS_PINID='B';
NODE_NAME     C44 2
 '@SCM_LIB.SCM(SCH_1):PAGE15_I369@PURE_QUANTA.Q_CAP(CHIPS)':
 'B': CDS_PINID='B';
NODE_NAME     C113 2
 '@SCM_LIB.SCM(SCH_1):PAGE16_I189@PURE_QUANTA.Q_CAP(CHIPS)':
 'B': CDS_PINID='B';
NODE_NAME     C120 2
 '@SCM_LIB.SCM(SCH_1):PAGE16_I190@PURE_QUANTA.Q_CAP(CHIPS)':
 'B': CDS_PINID='B';
NODE_NAME     C125 2
 '@SCM_LIB.SCM(SCH_1):PAGE16_I191@PURE_QUANTA.Q_CAP(CHIPS)':
 'B': CDS_PINID='B';
NODE_NAME     C131 2
 '@SCM_LIB.SCM(SCH_1):PAGE16_I192@PURE_QUANTA.Q_CAP(CHIPS)':
 'B': CDS_PINID='B';
NODE_NAME     C132 2
 '@SCM_LIB.SCM(SCH_1):PAGE16_I193@PURE_QUANTA.Q_CAP(CHIPS)':
 'B': CDS_PINID='B';
NODE_NAME     C329 2
 '@SCM_LIB.SCM(SCH_1):PAGE10_I573@PURE_QUANTA.Q_CAP(CHIPS)':
 'B': CDS_PINID='B';
NODE_NAME     C330 2
 '@SCM_LIB.SCM(SCH_1):PAGE10_I574@PURE_QUANTA.Q_CAP(CHIPS)':
 'B': CDS_PINID='B';
NODE_NAME     C177 2
 '@SCM_LIB.SCM(SCH_1):PAGE29_I219@PURE_QUANTA.Q_CAP(CHIPS)':
 'B': CDS_PINID='B';
NODE_NAME     C327 2
 '@SCM_LIB.SCM(SCH_1):PAGE29_I220@PURE_QUANTA.Q_CAP(CHIPS)':
 'B': CDS_PINID='B';
NODE_NAME     J13 3
 '@SCM_LIB.SCM(SCH_1):PAGE31_I61@PURE_QUANTA.SCONN3_212H9103GBR1(CHIPS)':
 '3': CDS_PINID='\3\';
NODE_NAME     H1 1
 '@SCM_LIB.SCM(SCH_1):PAGE57_I49@PURE_QUANTA.HOLE(CHIPS)':
 '1': CDS_PINID='\1\';
NODE_NAME     H6 1
 '@SCM_LIB.SCM(SCH_1):PAGE57_I50@PURE_QUANTA.HOLE(CHIPS)':
 '1': CDS_PINID='\1\';
NODE_NAME     H7 1
 '@SCM_LIB.SCM(SCH_1):PAGE57_I51@PURE_QUANTA.HOLE(CHIPS)':
 '1': CDS_PINID='\1\';
NODE_NAME     R620 2
 '@SCM_LIB.SCM(SCH_1):PAGE48_I39@PURE_QUANTA.Q_RES(CHIPS)':
 'B': CDS_PINID='B';
NODE_NAME     R507 2
 '@SCM_LIB.SCM(SCH_1):PAGE48_I52@PURE_QUANTA.Q_RES(CHIPS)':
 'B': CDS_PINID='B';
NODE_NAME     R506 2
 '@SCM_LIB.SCM(SCH_1):PAGE48_I53@PURE_QUANTA.Q_RES(CHIPS)':
 'B': CDS_PINID='B';
NODE_NAME     R431 2
 '@SCM_LIB.SCM(SCH_1):PAGE48_I56@PURE_QUANTA.Q_RES(CHIPS)':
 'B': CDS_PINID='B';
NODE_NAME     R164 2
 '@SCM_LIB.SCM(SCH_1):PAGE27_I244@PURE_QUANTA.Q_RES(CHIPS)':
 'B': CDS_PINID='B';
NODE_NAME     U56 2
 '@SCM_LIB.SCM(SCH_1):PAGE51_I56@PURE_QUANTA.AP2205W57(CHIPS)':
 'GND': CDS_PINID='GND';
NODE_NAME     R677 2
 '@SCM_LIB.SCM(SCH_1):PAGE51_I57@PURE_QUANTA.Q_RES(CHIPS)':
 'B': CDS_PINID='B';
NODE_NAME     C226 2
 '@SCM_LIB.SCM(SCH_1):PAGE51_I60@PURE_QUANTA.Q_CAP(CHIPS)':
 'B': CDS_PINID='B';
NODE_NAME     R94 2
 '@SCM_LIB.SCM(SCH_1):PAGE27_I246@PURE_QUANTA.Q_RES(CHIPS)':
 'B': CDS_PINID='B';
NODE_NAME     R387 1
 '@SCM_LIB.SCM(SCH_1):PAGE12_I508@PURE_QUANTA.Q_RES(CHIPS)':
 'A': CDS_PINID='A';
NODE_NAME     U15 3
 '@SCM_LIB.SCM(SCH_1):PAGE15_I393@PURE_QUANTA.74LVC1G08GW(CHIPS)':
 'GND': CDS_PINID='GND';
NODE_NAME     C26 2
 '@SCM_LIB.SCM(SCH_1):PAGE15_I398@PURE_QUANTA.Q_CAP(CHIPS)':
 'B': CDS_PINID='B';
NODE_NAME     C27 2
 '@SCM_LIB.SCM(SCH_1):PAGE50_I212@PURE_QUANTA.Q_CAP(CHIPS)':
 'B': CDS_PINID='B';
NODE_NAME     Q13 1
 '@SCM_LIB.SCM(SCH_1):PAGE50_I218@PURE_QUANTA.MOSFET_NCH_DUAL(CHIPS)':
 'S1': CDS_PINID='S1';
NODE_NAME     U16 3
 '@SCM_LIB.SCM(SCH_1):PAGE50_I227@PURE_QUANTA.74LVC1G07GW(CHIPS)':
 'GND': CDS_PINID='GND';
NODE_NAME     C29 2
 '@SCM_LIB.SCM(SCH_1):PAGE50_I232@PURE_QUANTA.Q_CAP(CHIPS)':
 'B': CDS_PINID='B';
NODE_NAME     C28 2
 '@SCM_LIB.SCM(SCH_1):PAGE50_I236@PURE_QUANTA.Q_CAP(CHIPS)':
 'B': CDS_PINID='B';
NODE_NAME     R855 2
 '@SCM_LIB.SCM(SCH_1):PAGE14_I223@PURE_QUANTA.Q_RES(CHIPS)':
 'B': CDS_PINID='B';
NODE_NAME     R857 2
 '@SCM_LIB.SCM(SCH_1):PAGE14_I224@PURE_QUANTA.Q_RES(CHIPS)':
 'B': CDS_PINID='B';
NODE_NAME     R865 2
 '@SCM_LIB.SCM(SCH_1):PAGE14_I225@PURE_QUANTA.Q_RES(CHIPS)':
 'B': CDS_PINID='B';
NODE_NAME     U28 3
 '@SCM_LIB.SCM(SCH_1):PAGE13_I435@PURE_QUANTA.74LVC1G66GV(CHIPS)':
 'GND': CDS_PINID='GND';
NODE_NAME     C180 2
 '@SCM_LIB.SCM(SCH_1):PAGE13_I440@PURE_QUANTA.Q_CAP(CHIPS)':
 'B': CDS_PINID='B';
NODE_NAME     D10 C
 '@SCM_LIB.SCM(SCH_1):PAGE50_I244@PURE_QUANTA.DIODE_BIDIRECTIONAL(CHIPS)':
 'C':PIN_LENGTH='Short',
 CDS_PINID='C';
NODE_NAME     C181 2
 '@SCM_LIB.SCM(SCH_1):PAGE50_I246@PURE_QUANTA.Q_CAP(CHIPS)':
 'B': CDS_PINID='B';
NODE_NAME     J14 8
 '@SCM_LIB.SCM(SCH_1):PAGE26_I71@PURE_QUANTA.CONN8_TSW10407FD(CHIPS)':
 '8': CDS_PINID='\8\';
NODE_NAME     J2 G1
 '@SCM_LIB.SCM(SCH_1):PAGE29_I221@PURE_QUANTA.CONN9_GSB3111315HR(CHIPS)':
 'G1': CDS_PINID='G1';
NODE_NAME     J2 G2
 '@SCM_LIB.SCM(SCH_1):PAGE29_I221@PURE_QUANTA.CONN9_GSB3111315HR(CHIPS)':
 'G2': CDS_PINID='G2';
NODE_NAME     J2 4
 '@SCM_LIB.SCM(SCH_1):PAGE29_I221@PURE_QUANTA.CONN9_GSB3111315HR(CHIPS)':
 'GND': CDS_PINID='GND';
NODE_NAME     U57 3
 '@SCM_LIB.SCM(SCH_1):PAGE50_I278@PURE_QUANTA.74LVC1G07GW(CHIPS)':
 'GND': CDS_PINID='GND';
NODE_NAME     C336 2
 '@SCM_LIB.SCM(SCH_1):PAGE50_I281@PURE_QUANTA.Q_CAP(CHIPS)':
 'B': CDS_PINID='B';
NODE_NAME     C335 2
 '@SCM_LIB.SCM(SCH_1):PAGE50_I285@PURE_QUANTA.Q_CAP(CHIPS)':
 'B': CDS_PINID='B';
NODE_NAME     SW6 1
 '@SCM_LIB.SCM(SCH_1):PAGE50_I292@PURE_QUANTA.SW_PUSHBUTTON4P_12_G34_H2(CHIPS)':
 '1': CDS_PINID='\1\';
NODE_NAME     SW6 3
 '@SCM_LIB.SCM(SCH_1):PAGE50_I292@PURE_QUANTA.SW_PUSHBUTTON4P_12_G34_H2(CHIPS)':
 '3': CDS_PINID='\3\';
NODE_NAME     SW6 4
 '@SCM_LIB.SCM(SCH_1):PAGE50_I292@PURE_QUANTA.SW_PUSHBUTTON4P_12_G34_H2(CHIPS)':
 '4': CDS_PINID='\4\';
NODE_NAME     SW8 1
 '@SCM_LIB.SCM(SCH_1):PAGE50_I293@PURE_QUANTA.SW_PUSHBUTTON4P_12_G34_H2(CHIPS)':
 '1': CDS_PINID='\1\';
NODE_NAME     SW8 3
 '@SCM_LIB.SCM(SCH_1):PAGE50_I293@PURE_QUANTA.SW_PUSHBUTTON4P_12_G34_H2(CHIPS)':
 '3': CDS_PINID='\3\';
NODE_NAME     SW8 4
 '@SCM_LIB.SCM(SCH_1):PAGE50_I293@PURE_QUANTA.SW_PUSHBUTTON4P_12_G34_H2(CHIPS)':
 '4': CDS_PINID='\4\';
NODE_NAME     D21 C
 '@SCM_LIB.SCM(SCH_1):PAGE50_I294@PURE_QUANTA.Q_LED(CHIPS)':
 'C': CDS_PINID='C';
NODE_NAME     U58 3
 '@SCM_LIB.SCM(SCH_1):PAGE22_I94@PURE_QUANTA.MC74VHC1G32DTT1G(CHIPS)':
 'GND': CDS_PINID='GND';
NODE_NAME     C337 2
 '@SCM_LIB.SCM(SCH_1):PAGE22_I97@PURE_QUANTA.Q_CAP(CHIPS)':
 'B': CDS_PINID='B';
NODE_NAME     C227 2
 '@SCM_LIB.SCM(SCH_1):PAGE51_I68@PURE_QUANTA.Q_CAP(CHIPS)':
 'B': CDS_PINID='B';
NODE_NAME     C208 2
 '@SCM_LIB.SCM(SCH_1):PAGE23_I169@PURE_QUANTA.Q_CAP(CHIPS)':
 'B': CDS_PINID='B';
NODE_NAME     C210 2
 '@SCM_LIB.SCM(SCH_1):PAGE23_I170@PURE_QUANTA.Q_CAP(CHIPS)':
 'B': CDS_PINID='B';
NODE_NAME     C173 2
 '@SCM_LIB.SCM(SCH_1):PAGE22_I107@PURE_QUANTA.Q_CAP(CHIPS)':
 'B': CDS_PINID='B';
NET_NAME
'GND_P1'
 '@SCM_LIB.SCM(SCH_1):GND_P1':
 C_SIGNAL='@scm_lib.scm(sch_1):gnd_p1',
 CDS_GLOBAL_NET='TRUE';
NODE_NAME     X1 2
 '@SCM_LIB.SCM(SCH_1):PAGE60_I13@PURE_QUANTA.TP_TDR_4P_FTS(CHIPS)':
 'P1': CDS_PINID='P1';
NODE_NAME     X1 3
 '@SCM_LIB.SCM(SCH_1):PAGE60_I13@PURE_QUANTA.TP_TDR_4P_FTS(CHIPS)':
 'P2': CDS_PINID='P2';
NODE_NAME     X7 2
 '@SCM_LIB.SCM(SCH_1):PAGE60_I14@PURE_QUANTA.TP_TDR_4P_FTS(CHIPS)':
 'P1': CDS_PINID='P1';
NODE_NAME     X7 3
 '@SCM_LIB.SCM(SCH_1):PAGE60_I14@PURE_QUANTA.TP_TDR_4P_FTS(CHIPS)':
 'P2': CDS_PINID='P2';
NODE_NAME     X12 2
 '@SCM_LIB.SCM(SCH_1):PAGE60_I18@PURE_QUANTA.TP_TDR_4P_FTS(CHIPS)':
 'P1': CDS_PINID='P1';
NODE_NAME     X12 3
 '@SCM_LIB.SCM(SCH_1):PAGE60_I18@PURE_QUANTA.TP_TDR_4P_FTS(CHIPS)':
 'P2': CDS_PINID='P2';
NODE_NAME     X6 2
 '@SCM_LIB.SCM(SCH_1):PAGE60_I19@PURE_QUANTA.TP_TDR_4P_FTS(CHIPS)':
 'P1': CDS_PINID='P1';
NODE_NAME     X6 3
 '@SCM_LIB.SCM(SCH_1):PAGE60_I19@PURE_QUANTA.TP_TDR_4P_FTS(CHIPS)':
 'P2': CDS_PINID='P2';
NODE_NAME     X11 2
 '@SCM_LIB.SCM(SCH_1):PAGE60_I22@PURE_QUANTA.TP_TDR_4P_FTS(CHIPS)':
 'P1': CDS_PINID='P1';
NODE_NAME     X11 3
 '@SCM_LIB.SCM(SCH_1):PAGE60_I22@PURE_QUANTA.TP_TDR_4P_FTS(CHIPS)':
 'P2': CDS_PINID='P2';
NODE_NAME     X5 2
 '@SCM_LIB.SCM(SCH_1):PAGE60_I23@PURE_QUANTA.TP_TDR_4P_FTS(CHIPS)':
 'P1': CDS_PINID='P1';
NODE_NAME     X5 3
 '@SCM_LIB.SCM(SCH_1):PAGE60_I23@PURE_QUANTA.TP_TDR_4P_FTS(CHIPS)':
 'P2': CDS_PINID='P2';
NODE_NAME     X8 2
 '@SCM_LIB.SCM(SCH_1):PAGE60_I34@PURE_QUANTA.TP_TDR_4P_FTS(CHIPS)':
 'P1': CDS_PINID='P1';
NODE_NAME     X8 3
 '@SCM_LIB.SCM(SCH_1):PAGE60_I34@PURE_QUANTA.TP_TDR_4P_FTS(CHIPS)':
 'P2': CDS_PINID='P2';
NODE_NAME     X2 2
 '@SCM_LIB.SCM(SCH_1):PAGE60_I35@PURE_QUANTA.TP_TDR_4P_FTS(CHIPS)':
 'P1': CDS_PINID='P1';
NODE_NAME     X2 3
 '@SCM_LIB.SCM(SCH_1):PAGE60_I35@PURE_QUANTA.TP_TDR_4P_FTS(CHIPS)':
 'P2': CDS_PINID='P2';
NODE_NAME     X19 2
 '@SCM_LIB.SCM(SCH_1):PAGE60_I38@PURE_QUANTA.TP_TDR_4P_FTS(CHIPS)':
 'P1': CDS_PINID='P1';
NODE_NAME     X19 3
 '@SCM_LIB.SCM(SCH_1):PAGE60_I38@PURE_QUANTA.TP_TDR_4P_FTS(CHIPS)':
 'P2': CDS_PINID='P2';
NODE_NAME     X13 2
 '@SCM_LIB.SCM(SCH_1):PAGE60_I39@PURE_QUANTA.TP_TDR_4P_FTS(CHIPS)':
 'P1': CDS_PINID='P1';
NODE_NAME     X13 3
 '@SCM_LIB.SCM(SCH_1):PAGE60_I39@PURE_QUANTA.TP_TDR_4P_FTS(CHIPS)':
 'P2': CDS_PINID='P2';
NODE_NAME     X18 2
 '@SCM_LIB.SCM(SCH_1):PAGE60_I42@PURE_QUANTA.TP_TDR_4P_FTS(CHIPS)':
 'P1': CDS_PINID='P1';
NODE_NAME     X18 3
 '@SCM_LIB.SCM(SCH_1):PAGE60_I42@PURE_QUANTA.TP_TDR_4P_FTS(CHIPS)':
 'P2': CDS_PINID='P2';
NODE_NAME     X24 2
 '@SCM_LIB.SCM(SCH_1):PAGE60_I43@PURE_QUANTA.TP_TDR_4P_FTS(CHIPS)':
 'P1': CDS_PINID='P1';
NODE_NAME     X24 3
 '@SCM_LIB.SCM(SCH_1):PAGE60_I43@PURE_QUANTA.TP_TDR_4P_FTS(CHIPS)':
 'P2': CDS_PINID='P2';
NODE_NAME     X17 2
 '@SCM_LIB.SCM(SCH_1):PAGE60_I46@PURE_QUANTA.TP_TDR_4P_FTS(CHIPS)':
 'P1': CDS_PINID='P1';
NODE_NAME     X17 3
 '@SCM_LIB.SCM(SCH_1):PAGE60_I46@PURE_QUANTA.TP_TDR_4P_FTS(CHIPS)':
 'P2': CDS_PINID='P2';
NODE_NAME     X23 2
 '@SCM_LIB.SCM(SCH_1):PAGE60_I47@PURE_QUANTA.TP_TDR_4P_FTS(CHIPS)':
 'P1': CDS_PINID='P1';
NODE_NAME     X23 3
 '@SCM_LIB.SCM(SCH_1):PAGE60_I47@PURE_QUANTA.TP_TDR_4P_FTS(CHIPS)':
 'P2': CDS_PINID='P2';
NODE_NAME     X14 2
 '@SCM_LIB.SCM(SCH_1):PAGE60_I58@PURE_QUANTA.TP_TDR_4P_FTS(CHIPS)':
 'P1': CDS_PINID='P1';
NODE_NAME     X14 3
 '@SCM_LIB.SCM(SCH_1):PAGE60_I58@PURE_QUANTA.TP_TDR_4P_FTS(CHIPS)':
 'P2': CDS_PINID='P2';
NODE_NAME     X20 2
 '@SCM_LIB.SCM(SCH_1):PAGE60_I59@PURE_QUANTA.TP_TDR_4P_FTS(CHIPS)':
 'P1': CDS_PINID='P1';
NODE_NAME     X20 3
 '@SCM_LIB.SCM(SCH_1):PAGE60_I59@PURE_QUANTA.TP_TDR_4P_FTS(CHIPS)':
 'P2': CDS_PINID='P2';
NODE_NAME     J9 3
 '@SCM_LIB.SCM(SCH_1):PAGE58_I55@PURE_QUANTA.PICOPROBE_BXA(CHIPS)':
 '3_G': CDS_PINID='\3_g\';
NODE_NAME     J11 3
 '@SCM_LIB.SCM(SCH_1):PAGE58_I57@PURE_QUANTA.PICOPROBE_BXA(CHIPS)':
 '3_G': CDS_PINID='\3_g\';
NODE_NAME     J16 3
 '@SCM_LIB.SCM(SCH_1):PAGE58_I58@PURE_QUANTA.PICOPROBE_BXA(CHIPS)':
 '3_G': CDS_PINID='\3_g\';
NODE_NAME     J17 3
 '@SCM_LIB.SCM(SCH_1):PAGE58_I59@PURE_QUANTA.PICOPROBE_BXA(CHIPS)':
 '3_G': CDS_PINID='\3_g\';
NODE_NAME     J25 3
 '@SCM_LIB.SCM(SCH_1):PAGE58_I60@PURE_QUANTA.PICOPROBE_BXA(CHIPS)':
 '3_G': CDS_PINID='\3_g\';
NODE_NAME     J28 3
 '@SCM_LIB.SCM(SCH_1):PAGE58_I61@PURE_QUANTA.PICOPROBE_BXA(CHIPS)':
 '3_G': CDS_PINID='\3_g\';
NODE_NAME     J26 3
 '@SCM_LIB.SCM(SCH_1):PAGE58_I62@PURE_QUANTA.PICOPROBE_BXA(CHIPS)':
 '3_G': CDS_PINID='\3_g\';
NODE_NAME     J27 3
 '@SCM_LIB.SCM(SCH_1):PAGE58_I63@PURE_QUANTA.PICOPROBE_BXA(CHIPS)':
 '3_G': CDS_PINID='\3_g\';
NODE_NAME     J12 3
 '@SCM_LIB.SCM(SCH_1):PAGE58_I64@PURE_QUANTA.PICOPROBE_BXA(CHIPS)':
 '3_G': CDS_PINID='\3_g\';
NODE_NAME     J29 3
 '@SCM_LIB.SCM(SCH_1):PAGE58_I65@PURE_QUANTA.PICOPROBE_BXA(CHIPS)':
 '3_G': CDS_PINID='\3_g\';
NODE_NAME     J22 3
 '@SCM_LIB.SCM(SCH_1):PAGE58_I66@PURE_QUANTA.PICOPROBE_BXA(CHIPS)':
 '3_G': CDS_PINID='\3_g\';
NODE_NAME     J30 3
 '@SCM_LIB.SCM(SCH_1):PAGE58_I67@PURE_QUANTA.PICOPROBE_BXA(CHIPS)':
 '3_G': CDS_PINID='\3_g\';
NODE_NAME     J24 3
 '@SCM_LIB.SCM(SCH_1):PAGE58_I68@PURE_QUANTA.PICOPROBE_BXA(CHIPS)':
 '3_G': CDS_PINID='\3_g\';
NODE_NAME     J23 3
 '@SCM_LIB.SCM(SCH_1):PAGE58_I69@PURE_QUANTA.PICOPROBE_BXA(CHIPS)':
 '3_G': CDS_PINID='\3_g\';
NODE_NAME     J20 3
 '@SCM_LIB.SCM(SCH_1):PAGE58_I70@PURE_QUANTA.PICOPROBE_BXA(CHIPS)':
 '3_G': CDS_PINID='\3_g\';
NODE_NAME     J19 3
 '@SCM_LIB.SCM(SCH_1):PAGE58_I71@PURE_QUANTA.PICOPROBE_BXA(CHIPS)':
 '3_G': CDS_PINID='\3_g\';
NET_NAME
'GPU_FPGA_RST_N'
 '@SCM_LIB.SCM(SCH_1):GPU_FPGA_RST_N':
 C_SIGNAL='@scm_lib.scm(sch_1):gpu_fpga_rst_n';
NODE_NAME     U5 F23
 '@SCM_LIB.SCM(SCH_1):PAGE13_I363@PURE_QUANTA.AST2600A3GP(CHIPS)':
 'RGMII3RXD0||RMII3RXD0||GPIOD0': CDS_PINID='\rgmii3rxd0||rmii3rxd0||gpiod0\';
NODE_NAME     U25 P8
 '@SCM_LIB.SCM(SCH_1):PAGE36_I1@PURE_QUANTA.LCMXO3LF2100C5BG256C(CHIPS)':
 'PB12A': CDS_PINID='PB12A';
NET_NAME
'GPU_NVS_PWR_BRAKE_R_N'
 '@SCM_LIB.SCM(SCH_1):GPU_NVS_PWR_BRAKE_R_N':
 C_SIGNAL='@scm_lib.scm(sch_1):gpu_nvs_pwr_brake_r_n';
NODE_NAME     U5 Y24
 '@SCM_LIB.SCM(SCH_1):PAGE15_I350@PURE_QUANTA.AST2600A3GP(CHIPS)':
 'GPIOQ2||TACH2': CDS_PINID='\gpioq2||tach2\';
NODE_NAME     U25 R7
 '@SCM_LIB.SCM(SCH_1):PAGE36_I1@PURE_QUANTA.LCMXO3LF2100C5BG256C(CHIPS)':
 'PB9A': CDS_PINID='PB9A';
NET_NAME
'GPU_WP_HW_CTRL_R_N'
 '@SCM_LIB.SCM(SCH_1):GPU_WP_HW_CTRL_R_N':
 C_SIGNAL='@scm_lib.scm(sch_1):gpu_wp_hw_ctrl_r_n';
NODE_NAME     U5 AB26
 '@SCM_LIB.SCM(SCH_1):PAGE15_I350@PURE_QUANTA.AST2600A3GP(CHIPS)':
 'GPIOQ3||TACH3': CDS_PINID='\gpioq3||tach3\';
NODE_NAME     U25 P7
 '@SCM_LIB.SCM(SCH_1):PAGE36_I1@PURE_QUANTA.LCMXO3LF2100C5BG256C(CHIPS)':
 'PB9B': CDS_PINID='PB9B';
NET_NAME
'HDD_LED_BUF'
 '@SCM_LIB.SCM(SCH_1):HDD_LED_BUF':
 C_SIGNAL='@scm_lib.scm(sch_1):hdd_led_buf';
NODE_NAME     Q12 3
 '@SCM_LIB.SCM(SCH_1):PAGE49_I24@PURE_QUANTA.MOSFET_DUAL_6P(CHIPS)':
 'D2': CDS_PINID='D2';
NODE_NAME     R813 1
 '@SCM_LIB.SCM(SCH_1):PAGE49_I35@PURE_QUANTA.Q_RES(CHIPS)':
 'A': CDS_PINID='A';
NET_NAME
'HDD_LED_BUF_R'
 '@SCM_LIB.SCM(SCH_1):HDD_LED_BUF_R':
 C_SIGNAL='@scm_lib.scm(sch_1):hdd_led_buf_r';
NODE_NAME     R813 2
 '@SCM_LIB.SCM(SCH_1):PAGE49_I35@PURE_QUANTA.Q_RES(CHIPS)':
 'B': CDS_PINID='B';
NODE_NAME     C324 1
 '@SCM_LIB.SCM(SCH_1):PAGE49_I37@PURE_QUANTA.Q_CAP(CHIPS)':
 'A': CDS_PINID='A';
NODE_NAME     R815 2
 '@SCM_LIB.SCM(SCH_1):PAGE49_I40@PURE_QUANTA.Q_RES(CHIPS)':
 'B': CDS_PINID='B';
NODE_NAME     D15 C
 '@SCM_LIB.SCM(SCH_1):PAGE49_I95@PURE_QUANTA.Q_LED(CHIPS)':
 'C': CDS_PINID='C';
NET_NAME
'HDD_LED_N'
 '@SCM_LIB.SCM(SCH_1):HDD_LED_N':
 C_SIGNAL='@scm_lib.scm(sch_1):hdd_led_n';
NODE_NAME     Q12 5
 '@SCM_LIB.SCM(SCH_1):PAGE49_I24@PURE_QUANTA.MOSFET_DUAL_6P(CHIPS)':
 'G2': CDS_PINID='G2';
NODE_NAME     R619 1
 '@SCM_LIB.SCM(SCH_1):PAGE49_I26@PURE_QUANTA.Q_RES(CHIPS)':
 'A': CDS_PINID='A';
NODE_NAME     R564 1
 '@SCM_LIB.SCM(SCH_1):PAGE10_I562@PURE_QUANTA.Q_RES(CHIPS)':
 'A': CDS_PINID='A';
NODE_NAME     R838 1
 '@SCM_LIB.SCM(SCH_1):PAGE10_I568@PURE_QUANTA.Q_RES(CHIPS)':
 'A': CDS_PINID='A';
NET_NAME
'HDD_LED_P5V_AUX'
 '@SCM_LIB.SCM(SCH_1):HDD_LED_P5V_AUX':
 C_SIGNAL='@scm_lib.scm(sch_1):hdd_led_p5v_aux';
NODE_NAME     C197 1
 '@SCM_LIB.SCM(SCH_1):PAGE49_I45@PURE_QUANTA.Q_CAP(CHIPS)':
 'A': CDS_PINID='A';
NODE_NAME     R569 1
 '@SCM_LIB.SCM(SCH_1):PAGE49_I60@PURE_QUANTA.Q_RES(CHIPS)':
 'A': CDS_PINID='A';
NODE_NAME     D15 A
 '@SCM_LIB.SCM(SCH_1):PAGE49_I95@PURE_QUANTA.Q_LED(CHIPS)':
 'A': CDS_PINID='A';
NET_NAME
'HDD_LED_R_N'
 '@SCM_LIB.SCM(SCH_1):HDD_LED_R_N':
 C_SIGNAL='@scm_lib.scm(sch_1):hdd_led_r_n';
NODE_NAME     GF1 B68
 '@SCM_LIB.SCM(SCH_1):PAGE10_I553@PURE_QUANTA.FCONN168_ME1016810202011_SCM(CHIPS)':
 'PCIE_HPM_TXP_3': CDS_PINID='PCIE_HPM_TXP_3';
NODE_NAME     R564 2
 '@SCM_LIB.SCM(SCH_1):PAGE10_I562@PURE_QUANTA.Q_RES(CHIPS)':
 'B': CDS_PINID='B';
NET_NAME
'H_CPU0_MEMTRIP_LVC1_N'
 '@SCM_LIB.SCM(SCH_1):H_CPU0_MEMTRIP_LVC1_N':
 C_SIGNAL='@scm_lib.scm(sch_1):h_cpu0_memtrip_lvc1_n';
NODE_NAME     U5 AB23
 '@SCM_LIB.SCM(SCH_1):PAGE15_I350@PURE_QUANTA.AST2600A3GP(CHIPS)':
 'GPIOP5||PWM13||THRUOUT2': CDS_PINID='\gpiop5||pwm13||thruout2\';
NODE_NAME     U25 D14
 '@SCM_LIB.SCM(SCH_1):PAGE35_I1@PURE_QUANTA.LCMXO3LF2100C5BG256C(CHIPS)':
 'PR1A': CDS_PINID='PR1A';
NET_NAME
'H_CPU0_PROCHOT_LVC1_N'
 '@SCM_LIB.SCM(SCH_1):H_CPU0_PROCHOT_LVC1_N':
 C_SIGNAL='@scm_lib.scm(sch_1):h_cpu0_prochot_lvc1_n';
NODE_NAME     U5 D14
 '@SCM_LIB.SCM(SCH_1):PAGE13_I363@PURE_QUANTA.AST2600A3GP(CHIPS)':
 'GPIOM0||NCTS1': CDS_PINID='\gpiom0||ncts1\';
NODE_NAME     R51 1
 '@SCM_LIB.SCM(SCH_1):PAGE35_I80@PURE_QUANTA.Q_RES(CHIPS)':
 'A': CDS_PINID='A';
NET_NAME
'H_CPU0_PROCHOT_LVC1_R_N'
 '@SCM_LIB.SCM(SCH_1):H_CPU0_PROCHOT_LVC1_R_N':
 C_SIGNAL='@scm_lib.scm(sch_1):h_cpu0_prochot_lvc1_r_n';
NODE_NAME     U25 J14
 '@SCM_LIB.SCM(SCH_1):PAGE35_I1@PURE_QUANTA.LCMXO3LF2100C5BG256C(CHIPS)':
 'PR7D': CDS_PINID='PR7D';
NODE_NAME     R51 2
 '@SCM_LIB.SCM(SCH_1):PAGE35_I80@PURE_QUANTA.Q_RES(CHIPS)':
 'B': CDS_PINID='B';
NET_NAME
'H_CPU1_MEMTRIP_LVC1_N'
 '@SCM_LIB.SCM(SCH_1):H_CPU1_MEMTRIP_LVC1_N':
 C_SIGNAL='@scm_lib.scm(sch_1):h_cpu1_memtrip_lvc1_n';
NODE_NAME     U5 AB24
 '@SCM_LIB.SCM(SCH_1):PAGE15_I350@PURE_QUANTA.AST2600A3GP(CHIPS)':
 'GPIOP6||PWM14': CDS_PINID='\gpiop6||pwm14\';
NODE_NAME     U25 D16
 '@SCM_LIB.SCM(SCH_1):PAGE35_I1@PURE_QUANTA.LCMXO3LF2100C5BG256C(CHIPS)':
 'PR2A': CDS_PINID='PR2A';
NET_NAME
'H_CPU1_PROCHOT_LVC1_N'
 '@SCM_LIB.SCM(SCH_1):H_CPU1_PROCHOT_LVC1_N':
 C_SIGNAL='@scm_lib.scm(sch_1):h_cpu1_prochot_lvc1_n';
NODE_NAME     R177 1
 '@SCM_LIB.SCM(SCH_1):PAGE13_I87@PURE_QUANTA.Q_RES(CHIPS)':
 'A': CDS_PINID='A';
NODE_NAME     U5 P24
 '@SCM_LIB.SCM(SCH_1):PAGE13_I363@PURE_QUANTA.AST2600A3GP(CHIPS)':
 'GPIOS5||RXD10': CDS_PINID='\gpios5||rxd10\';
NET_NAME
'H_CPU1_PROCHOT_LVC1_R_N'
 '@SCM_LIB.SCM(SCH_1):H_CPU1_PROCHOT_LVC1_R_N':
 C_SIGNAL='@scm_lib.scm(sch_1):h_cpu1_prochot_lvc1_r_n';
NODE_NAME     R177 2
 '@SCM_LIB.SCM(SCH_1):PAGE13_I87@PURE_QUANTA.Q_RES(CHIPS)':
 'B': CDS_PINID='B';
NODE_NAME     U25 E9
 '@SCM_LIB.SCM(SCH_1):PAGE34_I1@PURE_QUANTA.LCMXO3LF2100C5BG256C(CHIPS)':
 'PT17D': CDS_PINID='PT17D';
NET_NAME
'H_CPU_CATERR_LVC2_R2_N'
 '@SCM_LIB.SCM(SCH_1):H_CPU_CATERR_LVC2_R2_N':
 C_SIGNAL='@scm_lib.scm(sch_1):h_cpu_caterr_lvc2_r2_n';
NODE_NAME     GF1 OB13
 '@SCM_LIB.SCM(SCH_1):PAGE10_I553@PURE_QUANTA.FCONN168_ME1016810202011_SCM(CHIPS)':
 'SPI0_MOSI': CDS_PINID='SPI0_MOSI';
NODE_NAME     U5 F22
 '@SCM_LIB.SCM(SCH_1):PAGE13_I363@PURE_QUANTA.AST2600A3GP(CHIPS)':
 'RGMII3TXD3||GPIOC5': CDS_PINID='\rgmii3txd3||gpioc5\';
NET_NAME
'I3C1_SCL_R'
 '@SCM_LIB.SCM(SCH_1):I3C1_SCL_R':
 C_SIGNAL='@scm_lib.scm(sch_1):i3c1_scl_r';
NODE_NAME     U5 AF23
 '@SCM_LIB.SCM(SCH_1):PAGE14_I149@PURE_QUANTA.AST2600A3GP(CHIPS)':
 'I3C1SCL': CDS_PINID='I3C1SCL';
NODE_NAME     R184 2
 '@SCM_LIB.SCM(SCH_1):PAGE14_I232@PURE_QUANTA.Q_RES(CHIPS)':
 'B': CDS_PINID='B';
NET_NAME
'I3C1_SDA_R'
 '@SCM_LIB.SCM(SCH_1):I3C1_SDA_R':
 C_SIGNAL='@scm_lib.scm(sch_1):i3c1_sda_r';
NODE_NAME     U5 AE24
 '@SCM_LIB.SCM(SCH_1):PAGE14_I149@PURE_QUANTA.AST2600A3GP(CHIPS)':
 'I3C1SDA': CDS_PINID='I3C1SDA';
NODE_NAME     R185 2
 '@SCM_LIB.SCM(SCH_1):PAGE14_I236@PURE_QUANTA.Q_RES(CHIPS)':
 'B': CDS_PINID='B';
NET_NAME
'I3C1_SPD_SCL'
 '@SCM_LIB.SCM(SCH_1):I3C1_SPD_SCL':
 C_SIGNAL='@scm_lib.scm(sch_1):i3c1_spd_scl';
NODE_NAME     GF1 OA5
 '@SCM_LIB.SCM(SCH_1):PAGE10_I553@PURE_QUANTA.FCONN168_ME1016810202011_SCM(CHIPS)':
 'I3C_0_SCL': CDS_PINID='I3C_0_SCL';
NODE_NAME     R194 2
 '@SCM_LIB.SCM(SCH_1):PAGE14_I171@PURE_QUANTA.Q_RES(CHIPS)':
 'B': CDS_PINID='B';
NODE_NAME     R184 1
 '@SCM_LIB.SCM(SCH_1):PAGE14_I232@PURE_QUANTA.Q_RES(CHIPS)':
 'A': CDS_PINID='A';
NET_NAME
'I3C1_SPD_SDA'
 '@SCM_LIB.SCM(SCH_1):I3C1_SPD_SDA':
 C_SIGNAL='@scm_lib.scm(sch_1):i3c1_spd_sda';
NODE_NAME     GF1 OA6
 '@SCM_LIB.SCM(SCH_1):PAGE10_I553@PURE_QUANTA.FCONN168_ME1016810202011_SCM(CHIPS)':
 'I3C_0_SDA': CDS_PINID='I3C_0_SDA';
NODE_NAME     R195 2
 '@SCM_LIB.SCM(SCH_1):PAGE14_I172@PURE_QUANTA.Q_RES(CHIPS)':
 'B': CDS_PINID='B';
NODE_NAME     R185 1
 '@SCM_LIB.SCM(SCH_1):PAGE14_I236@PURE_QUANTA.Q_RES(CHIPS)':
 'A': CDS_PINID='A';
NET_NAME
'I3C2_SCL_R'
 '@SCM_LIB.SCM(SCH_1):I3C2_SCL_R':
 C_SIGNAL='@scm_lib.scm(sch_1):i3c2_scl_r';
NODE_NAME     U5 AF22
 '@SCM_LIB.SCM(SCH_1):PAGE14_I149@PURE_QUANTA.AST2600A3GP(CHIPS)':
 'I3C2SCL': CDS_PINID='I3C2SCL';
NODE_NAME     R186 2
 '@SCM_LIB.SCM(SCH_1):PAGE14_I233@PURE_QUANTA.Q_RES(CHIPS)':
 'B': CDS_PINID='B';
NET_NAME
'I3C2_SDA_R'
 '@SCM_LIB.SCM(SCH_1):I3C2_SDA_R':
 C_SIGNAL='@scm_lib.scm(sch_1):i3c2_sda_r';
NODE_NAME     U5 AE22
 '@SCM_LIB.SCM(SCH_1):PAGE14_I149@PURE_QUANTA.AST2600A3GP(CHIPS)':
 'I3C2SDA': CDS_PINID='I3C2SDA';
NODE_NAME     R187 2
 '@SCM_LIB.SCM(SCH_1):PAGE14_I237@PURE_QUANTA.Q_RES(CHIPS)':
 'B': CDS_PINID='B';
NET_NAME
'I3C2_SPD_SCL'
 '@SCM_LIB.SCM(SCH_1):I3C2_SPD_SCL':
 C_SIGNAL='@scm_lib.scm(sch_1):i3c2_spd_scl';
NODE_NAME     GF1 OA7
 '@SCM_LIB.SCM(SCH_1):PAGE10_I553@PURE_QUANTA.FCONN168_ME1016810202011_SCM(CHIPS)':
 'I3C_1_SCL': CDS_PINID='I3C_1_SCL';
NODE_NAME     R190 2
 '@SCM_LIB.SCM(SCH_1):PAGE14_I173@PURE_QUANTA.Q_RES(CHIPS)':
 'B': CDS_PINID='B';
NODE_NAME     R186 1
 '@SCM_LIB.SCM(SCH_1):PAGE14_I233@PURE_QUANTA.Q_RES(CHIPS)':
 'A': CDS_PINID='A';
NET_NAME
'I3C2_SPD_SDA'
 '@SCM_LIB.SCM(SCH_1):I3C2_SPD_SDA':
 C_SIGNAL='@scm_lib.scm(sch_1):i3c2_spd_sda';
NODE_NAME     GF1 OA8
 '@SCM_LIB.SCM(SCH_1):PAGE10_I553@PURE_QUANTA.FCONN168_ME1016810202011_SCM(CHIPS)':
 'I3C_1_SDA': CDS_PINID='I3C_1_SDA';
NODE_NAME     R191 2
 '@SCM_LIB.SCM(SCH_1):PAGE14_I174@PURE_QUANTA.Q_RES(CHIPS)':
 'B': CDS_PINID='B';
NODE_NAME     R187 1
 '@SCM_LIB.SCM(SCH_1):PAGE14_I237@PURE_QUANTA.Q_RES(CHIPS)':
 'A': CDS_PINID='A';
NET_NAME
'I3C3_SCL_R'
 '@SCM_LIB.SCM(SCH_1):I3C3_SCL_R':
 C_SIGNAL='@scm_lib.scm(sch_1):i3c3_scl_r';
NODE_NAME     U5 AF25
 '@SCM_LIB.SCM(SCH_1):PAGE14_I149@PURE_QUANTA.AST2600A3GP(CHIPS)':
 'I3C3SCL||FSI1CLK': CDS_PINID='\i3c3scl||fsi1clk\';
NODE_NAME     R198 1
 '@SCM_LIB.SCM(SCH_1):PAGE14_I234@PURE_QUANTA.Q_RES(CHIPS)':
 'A': CDS_PINID='A';
NET_NAME
'I3C3_SDA_R'
 '@SCM_LIB.SCM(SCH_1):I3C3_SDA_R':
 C_SIGNAL='@scm_lib.scm(sch_1):i3c3_sda_r';
NODE_NAME     U5 AE26
 '@SCM_LIB.SCM(SCH_1):PAGE14_I149@PURE_QUANTA.AST2600A3GP(CHIPS)':
 'I3C3SDA||FSI1DATA': CDS_PINID='\i3c3sda||fsi1data\';
NODE_NAME     R199 1
 '@SCM_LIB.SCM(SCH_1):PAGE14_I238@PURE_QUANTA.Q_RES(CHIPS)':
 'A': CDS_PINID='A';
NET_NAME
'I3C3_SPD_SCL'
 '@SCM_LIB.SCM(SCH_1):I3C3_SPD_SCL':
 C_SIGNAL='@scm_lib.scm(sch_1):i3c3_spd_scl';
NODE_NAME     GF1 OA9
 '@SCM_LIB.SCM(SCH_1):PAGE10_I553@PURE_QUANTA.FCONN168_ME1016810202011_SCM(CHIPS)':
 'I3C_2_SCL': CDS_PINID='I3C_2_SCL';
NODE_NAME     R188 2
 '@SCM_LIB.SCM(SCH_1):PAGE14_I183@PURE_QUANTA.Q_RES(CHIPS)':
 'B': CDS_PINID='B';
NODE_NAME     R198 2
 '@SCM_LIB.SCM(SCH_1):PAGE14_I234@PURE_QUANTA.Q_RES(CHIPS)':
 'B': CDS_PINID='B';
NET_NAME
'I3C3_SPD_SDA'
 '@SCM_LIB.SCM(SCH_1):I3C3_SPD_SDA':
 C_SIGNAL='@scm_lib.scm(sch_1):i3c3_spd_sda';
NODE_NAME     GF1 OA10
 '@SCM_LIB.SCM(SCH_1):PAGE10_I553@PURE_QUANTA.FCONN168_ME1016810202011_SCM(CHIPS)':
 'I3C_2_SDA': CDS_PINID='I3C_2_SDA';
NODE_NAME     R189 2
 '@SCM_LIB.SCM(SCH_1):PAGE14_I188@PURE_QUANTA.Q_RES(CHIPS)':
 'B': CDS_PINID='B';
NODE_NAME     R199 2
 '@SCM_LIB.SCM(SCH_1):PAGE14_I238@PURE_QUANTA.Q_RES(CHIPS)':
 'B': CDS_PINID='B';
NET_NAME
'I3C4_SCL_R'
 '@SCM_LIB.SCM(SCH_1):I3C4_SCL_R':
 C_SIGNAL='@scm_lib.scm(sch_1):i3c4_scl_r';
NODE_NAME     U5 AE25
 '@SCM_LIB.SCM(SCH_1):PAGE14_I149@PURE_QUANTA.AST2600A3GP(CHIPS)':
 'I3C4SCL||FSI2CLK': CDS_PINID='\i3c4scl||fsi2clk\';
NODE_NAME     R200 1
 '@SCM_LIB.SCM(SCH_1):PAGE14_I235@PURE_QUANTA.Q_RES(CHIPS)':
 'A': CDS_PINID='A';
NET_NAME
'I3C4_SDA_R'
 '@SCM_LIB.SCM(SCH_1):I3C4_SDA_R':
 C_SIGNAL='@scm_lib.scm(sch_1):i3c4_sda_r';
NODE_NAME     U5 AF24
 '@SCM_LIB.SCM(SCH_1):PAGE14_I149@PURE_QUANTA.AST2600A3GP(CHIPS)':
 'I3C4SDA||FSI2DATA': CDS_PINID='\i3c4sda||fsi2data\';
NODE_NAME     R201 1
 '@SCM_LIB.SCM(SCH_1):PAGE14_I239@PURE_QUANTA.Q_RES(CHIPS)':
 'A': CDS_PINID='A';
NET_NAME
'I3C4_SPD_SCL'
 '@SCM_LIB.SCM(SCH_1):I3C4_SPD_SCL':
 C_SIGNAL='@scm_lib.scm(sch_1):i3c4_spd_scl';
NODE_NAME     GF1 OA11
 '@SCM_LIB.SCM(SCH_1):PAGE10_I553@PURE_QUANTA.FCONN168_ME1016810202011_SCM(CHIPS)':
 'I3C_3_SCL': CDS_PINID='I3C_3_SCL';
NODE_NAME     R196 2
 '@SCM_LIB.SCM(SCH_1):PAGE14_I189@PURE_QUANTA.Q_RES(CHIPS)':
 'B': CDS_PINID='B';
NODE_NAME     R200 2
 '@SCM_LIB.SCM(SCH_1):PAGE14_I235@PURE_QUANTA.Q_RES(CHIPS)':
 'B': CDS_PINID='B';
NET_NAME
'I3C4_SPD_SDA'
 '@SCM_LIB.SCM(SCH_1):I3C4_SPD_SDA':
 C_SIGNAL='@scm_lib.scm(sch_1):i3c4_spd_sda';
NODE_NAME     GF1 OA12
 '@SCM_LIB.SCM(SCH_1):PAGE10_I553@PURE_QUANTA.FCONN168_ME1016810202011_SCM(CHIPS)':
 'I3C_3_SDA': CDS_PINID='I3C_3_SDA';
NODE_NAME     R197 2
 '@SCM_LIB.SCM(SCH_1):PAGE14_I190@PURE_QUANTA.Q_RES(CHIPS)':
 'B': CDS_PINID='B';
NODE_NAME     R201 2
 '@SCM_LIB.SCM(SCH_1):PAGE14_I239@PURE_QUANTA.Q_RES(CHIPS)':
 'B': CDS_PINID='B';
NET_NAME
'IBMC_MIOZ'
 '@SCM_LIB.SCM(SCH_1):IBMC_MIOZ':
 C_SIGNAL='@scm_lib.scm(sch_1):ibmc_mioz';
NODE_NAME     R127 2
 '@SCM_LIB.SCM(SCH_1):PAGE12_I46@PURE_QUANTA.Q_RES(CHIPS)':
 'B': CDS_PINID='B';
NODE_NAME     U5 P5
 '@SCM_LIB.SCM(SCH_1):PAGE12_I436@PURE_QUANTA.AST2600A3GP(CHIPS)':
 'MIOZ': CDS_PINID='MIOZ';
NET_NAME
'ID_LED_BUF'
 '@SCM_LIB.SCM(SCH_1):ID_LED_BUF':
 C_SIGNAL='@scm_lib.scm(sch_1):id_led_buf';
NODE_NAME     U9 4
 '@SCM_LIB.SCM(SCH_1):PAGE49_I5@PURE_QUANTA.MC74VHC1G32DTT1G(CHIPS)':
 'OUT_Y': CDS_PINID='OUT_Y';
NODE_NAME     Q9 2
 '@SCM_LIB.SCM(SCH_1):PAGE49_I6@PURE_QUANTA.MOSFET_NCH_DUAL(CHIPS)':
 'G1': CDS_PINID='G1';
NET_NAME
'ID_LED_D_P3V3_AUX'
 '@SCM_LIB.SCM(SCH_1):ID_LED_D_P3V3_AUX':
 C_SIGNAL='@scm_lib.scm(sch_1):id_led_d_p3v3_aux';
NODE_NAME     Q9 6
 '@SCM_LIB.SCM(SCH_1):PAGE49_I6@PURE_QUANTA.MOSFET_NCH_DUAL(CHIPS)':
 'D1': CDS_PINID='D1';
NODE_NAME     D13 C
 '@SCM_LIB.SCM(SCH_1):PAGE49_I97@PURE_QUANTA.Q_LED(CHIPS)':
 'C': CDS_PINID='C';
NET_NAME
'ID_LED_P3V3_AUX'
 '@SCM_LIB.SCM(SCH_1):ID_LED_P3V3_AUX':
 C_SIGNAL='@scm_lib.scm(sch_1):id_led_p3v3_aux';
NODE_NAME     R43 1
 '@SCM_LIB.SCM(SCH_1):PAGE49_I79@PURE_QUANTA.Q_RES(CHIPS)':
 'A': CDS_PINID='A';
NODE_NAME     D13 A
 '@SCM_LIB.SCM(SCH_1):PAGE49_I97@PURE_QUANTA.Q_LED(CHIPS)':
 'A': CDS_PINID='A';
NET_NAME
'ID_RST_BTN_BMC_N'
 '@SCM_LIB.SCM(SCH_1):ID_RST_BTN_BMC_N':
 C_SIGNAL='@scm_lib.scm(sch_1):id_rst_btn_bmc_n';
NODE_NAME     U32 4
 '@SCM_LIB.SCM(SCH_1):PAGE50_I49@PURE_QUANTA.74LVC1G17GW(CHIPS)':
 'Y': CDS_PINID='Y';
NODE_NAME     R565 2
 '@SCM_LIB.SCM(SCH_1):PAGE15_I406@PURE_QUANTA.Q_RES(CHIPS)':
 'B': CDS_PINID='B';
NET_NAME
'ID_RST_BTN_BMC_R_N'
 '@SCM_LIB.SCM(SCH_1):ID_RST_BTN_BMC_R_N':
 C_SIGNAL='@scm_lib.scm(sch_1):id_rst_btn_bmc_r_n';
NODE_NAME     U5 AA23
 '@SCM_LIB.SCM(SCH_1):PAGE15_I350@PURE_QUANTA.AST2600A3GP(CHIPS)':
 'GPIOP2||PWM10||THRUIN1': CDS_PINID='\gpiop2||pwm10||thruin1\';
NODE_NAME     R565 1
 '@SCM_LIB.SCM(SCH_1):PAGE15_I406@PURE_QUANTA.Q_RES(CHIPS)':
 'A': CDS_PINID='A';
NET_NAME
'IRQ_BMC_CPU_NMI'
 '@SCM_LIB.SCM(SCH_1):IRQ_BMC_CPU_NMI':
 C_SIGNAL='@scm_lib.scm(sch_1):irq_bmc_cpu_nmi';
NODE_NAME     R166 2
 '@SCM_LIB.SCM(SCH_1):PAGE13_I50@PURE_QUANTA.Q_RES(CHIPS)':
 'B': CDS_PINID='B';
NODE_NAME     U5 J24
 '@SCM_LIB.SCM(SCH_1):PAGE13_I363@PURE_QUANTA.AST2600A3GP(CHIPS)':
 'GPIOB7||RXD4': CDS_PINID='\gpiob7||rxd4\';
NET_NAME
'IRQ_BMC_CPU_NMI_R'
 '@SCM_LIB.SCM(SCH_1):IRQ_BMC_CPU_NMI_R':
 C_SIGNAL='@scm_lib.scm(sch_1):irq_bmc_cpu_nmi_r';
NODE_NAME     R166 1
 '@SCM_LIB.SCM(SCH_1):PAGE13_I50@PURE_QUANTA.Q_RES(CHIPS)':
 'A': CDS_PINID='A';
NODE_NAME     U25 B3
 '@SCM_LIB.SCM(SCH_1):PAGE34_I1@PURE_QUANTA.LCMXO3LF2100C5BG256C(CHIPS)':
 'PT9C': CDS_PINID='PT9C';
NET_NAME
'IRQ_BMC_LPC_SERIRQ_ESPI_GF'
 '@SCM_LIB.SCM(SCH_1):IRQ_BMC_LPC_SERIRQ_ESPI_GF':
 C_SIGNAL='@scm_lib.scm(sch_1):irq_bmc_lpc_serirq_espi_gf';
NODE_NAME     GF1 B3
 '@SCM_LIB.SCM(SCH_1):PAGE10_I553@PURE_QUANTA.FCONN168_ME1016810202011_SCM(CHIPS)':
 'ESPI_ALERT_N': CDS_PINID='ESPI_ALERT_N';
NODE_NAME     R116 2
 '@SCM_LIB.SCM(SCH_1):PAGE12_I3@PURE_QUANTA.Q_RES(CHIPS)':
 'B': CDS_PINID='B';
NODE_NAME     R119 1
 '@SCM_LIB.SCM(SCH_1):PAGE12_I34@PURE_QUANTA.Q_RES(CHIPS)':
 'A': CDS_PINID='A';
NET_NAME
'IRQ_BMC_PCH_NMI_N'
 '@SCM_LIB.SCM(SCH_1):IRQ_BMC_PCH_NMI_N':
 C_SIGNAL='@scm_lib.scm(sch_1):irq_bmc_pch_nmi_n';
NODE_NAME     R61 2
 '@SCM_LIB.SCM(SCH_1):PAGE13_I204@PURE_QUANTA.Q_RES(CHIPS)':
 'B': CDS_PINID='B';
NODE_NAME     U5 R23
 '@SCM_LIB.SCM(SCH_1):PAGE13_I363@PURE_QUANTA.AST2600A3GP(CHIPS)':
 'GPIOS0||MDC1': CDS_PINID='\gpios0||mdc1\';
NODE_NAME     R571 1
 '@SCM_LIB.SCM(SCH_1):PAGE34_I35@PURE_QUANTA.Q_RES(CHIPS)':
 'A': CDS_PINID='A';
NET_NAME
'IRQ_BMC_PCH_NMI_R_N'
 '@SCM_LIB.SCM(SCH_1):IRQ_BMC_PCH_NMI_R_N':
 C_SIGNAL='@scm_lib.scm(sch_1):irq_bmc_pch_nmi_r_n';
NODE_NAME     U25 A8
 '@SCM_LIB.SCM(SCH_1):PAGE34_I1@PURE_QUANTA.LCMXO3LF2100C5BG256C(CHIPS)':
 'PT17B||PCLKC0_1': CDS_PINID='\pt17b||pclkc0_1\';
NODE_NAME     R571 2
 '@SCM_LIB.SCM(SCH_1):PAGE34_I35@PURE_QUANTA.Q_RES(CHIPS)':
 'B': CDS_PINID='B';
NET_NAME
'IRQ_BMC_TPM_SPI_R_N'
 '@SCM_LIB.SCM(SCH_1):IRQ_BMC_TPM_SPI_R_N':
 C_SIGNAL='@scm_lib.scm(sch_1):irq_bmc_tpm_spi_r_n';
NODE_NAME     R113 2
 '@SCM_LIB.SCM(SCH_1):PAGE46_I105@PURE_QUANTA.Q_RES(CHIPS)':
 'B': CDS_PINID='B';
NODE_NAME     J10 9
 '@SCM_LIB.SCM(SCH_1):PAGE46_I113@PURE_QUANTA.SCONN11_9192031111LF(CHIPS)':
 '9': CDS_PINID='\9\';
NET_NAME
'IRQ_CPU0_VRHOT_N'
 '@SCM_LIB.SCM(SCH_1):IRQ_CPU0_VRHOT_N':
 C_SIGNAL='@scm_lib.scm(sch_1):irq_cpu0_vrhot_n';
NODE_NAME     U5 V26
 '@SCM_LIB.SCM(SCH_1):PAGE15_I350@PURE_QUANTA.AST2600A3GP(CHIPS)':
 'GPIOR3||TACH11': CDS_PINID='\gpior3||tach11\';
NODE_NAME     U25 F10
 '@SCM_LIB.SCM(SCH_1):PAGE34_I1@PURE_QUANTA.LCMXO3LF2100C5BG256C(CHIPS)':
 'PT21C': CDS_PINID='PT21C';
NET_NAME
'IRQ_CPU1_VRHOT_N'
 '@SCM_LIB.SCM(SCH_1):IRQ_CPU1_VRHOT_N':
 C_SIGNAL='@scm_lib.scm(sch_1):irq_cpu1_vrhot_n';
NODE_NAME     U5 U25
 '@SCM_LIB.SCM(SCH_1):PAGE15_I350@PURE_QUANTA.AST2600A3GP(CHIPS)':
 'GPIOR4||TACH12': CDS_PINID='\gpior4||tach12\';
NODE_NAME     U25 D11
 '@SCM_LIB.SCM(SCH_1):PAGE34_I1@PURE_QUANTA.LCMXO3LF2100C5BG256C(CHIPS)':
 'PT21D': CDS_PINID='PT21D';
NET_NAME
'IRQ_ESPI_LPC_SERIRQ_ALERT0_N'
 '@SCM_LIB.SCM(SCH_1):IRQ_ESPI_LPC_SERIRQ_ALERT0_N':
 C_SIGNAL='@scm_lib.scm(sch_1):irq_espi_lpc_serirq_alert0_n';
NODE_NAME     R119 2
 '@SCM_LIB.SCM(SCH_1):PAGE12_I34@PURE_QUANTA.Q_RES(CHIPS)':
 'B': CDS_PINID='B';
NODE_NAME     U5 AD7
 '@SCM_LIB.SCM(SCH_1):PAGE12_I436@PURE_QUANTA.AST2600A3GP(CHIPS)':
 'GPIOW6||LSIRQ#||ESPIALT#': CDS_PINID='\gpiow6||lsirq#||espialt#\';
NET_NAME
'IRQ_OC_DETECT_EN_N'
 '@SCM_LIB.SCM(SCH_1):IRQ_OC_DETECT_EN_N':
 C_SIGNAL='@scm_lib.scm(sch_1):irq_oc_detect_en_n';
NODE_NAME     U5 V24
 '@SCM_LIB.SCM(SCH_1):PAGE15_I350@PURE_QUANTA.AST2600A3GP(CHIPS)':
 'GPIOR2||TACH10': CDS_PINID='\gpior2||tach10\';
NODE_NAME     U25 B13
 '@SCM_LIB.SCM(SCH_1):PAGE34_I1@PURE_QUANTA.LCMXO3LF2100C5BG256C(CHIPS)':
 'PT22C': CDS_PINID='PT22C';
NET_NAME
'IRQ_OC_DETECT_N'
 '@SCM_LIB.SCM(SCH_1):IRQ_OC_DETECT_N':
 C_SIGNAL='@scm_lib.scm(sch_1):irq_oc_detect_n';
NODE_NAME     U5 V25
 '@SCM_LIB.SCM(SCH_1):PAGE15_I350@PURE_QUANTA.AST2600A3GP(CHIPS)':
 'GPIOR0||TACH8': CDS_PINID='\gpior0||tach8\';
NODE_NAME     U25 B11
 '@SCM_LIB.SCM(SCH_1):PAGE34_I1@PURE_QUANTA.LCMXO3LF2100C5BG256C(CHIPS)':
 'PT22A': CDS_PINID='PT22A';
NET_NAME
'IRQ_PCH_SCI_WHEA_N'
 '@SCM_LIB.SCM(SCH_1):IRQ_PCH_SCI_WHEA_N':
 C_SIGNAL='@scm_lib.scm(sch_1):irq_pch_sci_whea_n';
NODE_NAME     R826 2
 '@SCM_LIB.SCM(SCH_1):PAGE13_I351@PURE_QUANTA.Q_RES(CHIPS)':
 'B': CDS_PINID='B';
NODE_NAME     R816 2
 '@SCM_LIB.SCM(SCH_1):PAGE13_I353@PURE_QUANTA.Q_RES(CHIPS)':
 'B': CDS_PINID='B';
NODE_NAME     U25 B9
 '@SCM_LIB.SCM(SCH_1):PAGE34_I1@PURE_QUANTA.LCMXO3LF2100C5BG256C(CHIPS)':
 'PT19A': CDS_PINID='PT19A';
NET_NAME
'IRQ_PCH_SCI_WHEA_R_N'
 '@SCM_LIB.SCM(SCH_1):IRQ_PCH_SCI_WHEA_R_N':
 C_SIGNAL='@scm_lib.scm(sch_1):irq_pch_sci_whea_r_n';
NODE_NAME     R826 1
 '@SCM_LIB.SCM(SCH_1):PAGE13_I351@PURE_QUANTA.Q_RES(CHIPS)':
 'A': CDS_PINID='A';
NODE_NAME     U5 A15
 '@SCM_LIB.SCM(SCH_1):PAGE13_I363@PURE_QUANTA.AST2600A3GP(CHIPS)':
 'GPIOI7||SIOSCI#': CDS_PINID='\gpioi7||siosci#\';
NET_NAME
'IRQ_PCH_TPM_SPI_N'
 '@SCM_LIB.SCM(SCH_1):IRQ_PCH_TPM_SPI_N':
 C_SIGNAL='@scm_lib.scm(sch_1):irq_pch_tpm_spi_n';
NODE_NAME     U5 AA25
 '@SCM_LIB.SCM(SCH_1):PAGE15_I350@PURE_QUANTA.AST2600A3GP(CHIPS)':
 'GPIOQ0||TACH0': CDS_PINID='\gpioq0||tach0\';
NODE_NAME     R746 1
 '@SCM_LIB.SCM(SCH_1):PAGE36_I10@PURE_QUANTA.Q_RES(CHIPS)':
 'A': CDS_PINID='A';
NODE_NAME     R505 1
 '@SCM_LIB.SCM(SCH_1):PAGE46_I74@PURE_QUANTA.Q_RES(CHIPS)':
 'A': CDS_PINID='A';
NODE_NAME     R497 2
 '@SCM_LIB.SCM(SCH_1):PAGE46_I78@PURE_QUANTA.Q_RES(CHIPS)':
 'B': CDS_PINID='B';
NET_NAME
'IRQ_PCH_TPM_SPI_R2_N'
 '@SCM_LIB.SCM(SCH_1):IRQ_PCH_TPM_SPI_R2_N':
 C_SIGNAL='@scm_lib.scm(sch_1):irq_pch_tpm_spi_r2_n';
NODE_NAME     U25 T5
 '@SCM_LIB.SCM(SCH_1):PAGE36_I1@PURE_QUANTA.LCMXO3LF2100C5BG256C(CHIPS)':
 'PB6A': CDS_PINID='PB6A';
NODE_NAME     R746 2
 '@SCM_LIB.SCM(SCH_1):PAGE36_I10@PURE_QUANTA.Q_RES(CHIPS)':
 'B': CDS_PINID='B';
NET_NAME
'IRQ_PCH_TPM_SPI_R_N'
 '@SCM_LIB.SCM(SCH_1):IRQ_PCH_TPM_SPI_R_N':
 C_SIGNAL='@scm_lib.scm(sch_1):irq_pch_tpm_spi_r_n';
NODE_NAME     J5 9
 '@SCM_LIB.SCM(SCH_1):PAGE46_I56@PURE_QUANTA.SCONN11_9192031111LF(CHIPS)':
 '9': CDS_PINID='\9\';
NODE_NAME     R505 2
 '@SCM_LIB.SCM(SCH_1):PAGE46_I74@PURE_QUANTA.Q_RES(CHIPS)':
 'B': CDS_PINID='B';
NET_NAME
'IRQ_SGPIO_BMC_N'
 '@SCM_LIB.SCM(SCH_1):IRQ_SGPIO_BMC_N':
 C_SIGNAL='@scm_lib.scm(sch_1):irq_sgpio_bmc_n';
NODE_NAME     U5 G24
 '@SCM_LIB.SCM(SCH_1):PAGE13_I363@PURE_QUANTA.AST2600A3GP(CHIPS)':
 'RGMII3RXCTL||GPIOC7': CDS_PINID='\rgmii3rxctl||gpioc7\';
NODE_NAME     R689 2
 '@SCM_LIB.SCM(SCH_1):PAGE13_I398@PURE_QUANTA.Q_RES(CHIPS)':
 'B': CDS_PINID='B';
NET_NAME
'IRQ_SGPIO_N'
 '@SCM_LIB.SCM(SCH_1):IRQ_SGPIO_N':
 C_SIGNAL='@scm_lib.scm(sch_1):irq_sgpio_n';
NODE_NAME     GF1 B40
 '@SCM_LIB.SCM(SCH_1):PAGE10_I553@PURE_QUANTA.FCONN168_ME1016810202011_SCM(CHIPS)':
 'SGPIO_INTR_N': CDS_PINID='SGPIO_INTR_N';
NODE_NAME     R68 2
 '@SCM_LIB.SCM(SCH_1):PAGE11_I179@PURE_QUANTA.Q_RES(CHIPS)':
 'B': CDS_PINID='B';
NODE_NAME     R689 1
 '@SCM_LIB.SCM(SCH_1):PAGE13_I398@PURE_QUANTA.Q_RES(CHIPS)':
 'A': CDS_PINID='A';
NODE_NAME     R690 2
 '@SCM_LIB.SCM(SCH_1):PAGE35_I149@PURE_QUANTA.Q_RES(CHIPS)':
 'B': CDS_PINID='B';
NET_NAME
'IRQ_SGPIO_R_N'
 '@SCM_LIB.SCM(SCH_1):IRQ_SGPIO_R_N':
 C_SIGNAL='@scm_lib.scm(sch_1):irq_sgpio_r_n';
NODE_NAME     U25 E14
 '@SCM_LIB.SCM(SCH_1):PAGE35_I1@PURE_QUANTA.LCMXO3LF2100C5BG256C(CHIPS)':
 'PR2B': CDS_PINID='PR2B';
NODE_NAME     R690 1
 '@SCM_LIB.SCM(SCH_1):PAGE35_I149@PURE_QUANTA.Q_RES(CHIPS)':
 'A': CDS_PINID='A';
NET_NAME
'IRQ_SMI_ACTIVE_BMC_N'
 '@SCM_LIB.SCM(SCH_1):IRQ_SMI_ACTIVE_BMC_N':
 C_SIGNAL='@scm_lib.scm(sch_1):irq_smi_active_bmc_n';
NODE_NAME     R37 2
 '@SCM_LIB.SCM(SCH_1):PAGE13_I133@PURE_QUANTA.Q_RES(CHIPS)':
 'B': CDS_PINID='B';
NODE_NAME     U5 AC9
 '@SCM_LIB.SCM(SCH_1):PAGE13_I363@PURE_QUANTA.AST2600A3GP(CHIPS)':
 'GPIOX2||SPI2CS2#': CDS_PINID='\gpiox2||spi2cs2#\';
NET_NAME
'IRQ_SMI_ACTIVE_GF_N'
 '@SCM_LIB.SCM(SCH_1):IRQ_SMI_ACTIVE_GF_N':
 C_SIGNAL='@scm_lib.scm(sch_1):irq_smi_active_gf_n';
NODE_NAME     GF1 A56
 '@SCM_LIB.SCM(SCH_1):PAGE10_I553@PURE_QUANTA.FCONN168_ME1016810202011_SCM(CHIPS)':
 'IRQ_N': CDS_PINID='IRQ_N';
NODE_NAME     R37 1
 '@SCM_LIB.SCM(SCH_1):PAGE13_I133@PURE_QUANTA.Q_RES(CHIPS)':
 'A': CDS_PINID='A';
NET_NAME
'IRQ_SML0_ALERT_R_N'
 '@SCM_LIB.SCM(SCH_1):IRQ_SML0_ALERT_R_N':
 C_SIGNAL='@scm_lib.scm(sch_1):irq_sml0_alert_r_n';
NODE_NAME     U5 F24
 '@SCM_LIB.SCM(SCH_1):PAGE13_I363@PURE_QUANTA.AST2600A3GP(CHIPS)':
 'RGMII4TXCK||RMII4RCLKO||NCTS3||GPIOD4': CDS_PINID='\rgmii4txck||rmii4rclko||ncts3||gpiod4\';
NODE_NAME     U25 N7
 '@SCM_LIB.SCM(SCH_1):PAGE36_I1@PURE_QUANTA.LCMXO3LF2100C5BG256C(CHIPS)':
 'PB9D': CDS_PINID='PB9D';
NET_NAME
'IRQ_TPM_SPI_N'
 '@SCM_LIB.SCM(SCH_1):IRQ_TPM_SPI_N':
 C_SIGNAL='@scm_lib.scm(sch_1):irq_tpm_spi_n';
NODE_NAME     U5 AF15
 '@SCM_LIB.SCM(SCH_1):PAGE13_I363@PURE_QUANTA.AST2600A3GP(CHIPS)':
 'GPIOV7||LPCSMI#': CDS_PINID='\gpiov7||lpcsmi#\';
NODE_NAME     R59 2
 '@SCM_LIB.SCM(SCH_1):PAGE46_I98@PURE_QUANTA.Q_RES(CHIPS)':
 'B': CDS_PINID='B';
NODE_NAME     R113 1
 '@SCM_LIB.SCM(SCH_1):PAGE46_I105@PURE_QUANTA.Q_RES(CHIPS)':
 'A': CDS_PINID='A';
NET_NAME
'IRQ_UV_DETECT_N'
 '@SCM_LIB.SCM(SCH_1):IRQ_UV_DETECT_N':
 C_SIGNAL='@scm_lib.scm(sch_1):irq_uv_detect_n';
NODE_NAME     U5 U24
 '@SCM_LIB.SCM(SCH_1):PAGE15_I350@PURE_QUANTA.AST2600A3GP(CHIPS)':
 'GPIOR1||TACH9': CDS_PINID='\gpior1||tach9\';
NODE_NAME     U25 B7
 '@SCM_LIB.SCM(SCH_1):PAGE34_I1@PURE_QUANTA.LCMXO3LF2100C5BG256C(CHIPS)':
 'PT13A': CDS_PINID='PT13A';
NET_NAME
'J7_P1'
 '@SCM_LIB.SCM(SCH_1):J7_P1':
 C_SIGNAL='@scm_lib.scm(sch_1):j7_p1';
NODE_NAME     C217 1
 '@SCM_LIB.SCM(SCH_1):PAGE32_I21@PURE_QUANTA.Q_CAP(CHIPS)':
 'A': CDS_PINID='A';
NODE_NAME     C215 1
 '@SCM_LIB.SCM(SCH_1):PAGE32_I22@PURE_QUANTA.Q_CAP(CHIPS)':
 'A': CDS_PINID='A';
NODE_NAME     J7 1
 '@SCM_LIB.SCM(SCH_1):PAGE32_I132@PURE_QUANTA.CONN8_210HP1080BR1(CHIPS)':
 '1': CDS_PINID='\1\';
NODE_NAME     D20 2
 '@SCM_LIB.SCM(SCH_1):PAGE32_I144@PURE_QUANTA.SCHOTTKY_12(CHIPS)':
 'C': CDS_PINID='C';
NET_NAME
'JTAG_1_BMC_TCK_R'
 '@SCM_LIB.SCM(SCH_1):JTAG_1_BMC_TCK_R':
 C_SIGNAL='@scm_lib.scm(sch_1):jtag_1_bmc_tck_r';
NODE_NAME     U5 E17
 '@SCM_LIB.SCM(SCH_1):PAGE15_I350@PURE_QUANTA.AST2600A3GP(CHIPS)':
 'GPIOI2||MTCK2||TXD13': CDS_PINID='\gpioi2||mtck2||txd13\';
NODE_NAME     R222 1
 '@SCM_LIB.SCM(SCH_1):PAGE32_I80@PURE_QUANTA.Q_RES(CHIPS)':
 'A': CDS_PINID='A';
NET_NAME
'JTAG_1_BMC_TDI_R'
 '@SCM_LIB.SCM(SCH_1):JTAG_1_BMC_TDI_R':
 C_SIGNAL='@scm_lib.scm(sch_1):jtag_1_bmc_tdi_r';
NODE_NAME     U5 A16
 '@SCM_LIB.SCM(SCH_1):PAGE15_I350@PURE_QUANTA.AST2600A3GP(CHIPS)':
 'GPIOI1||MTDI2||RXD12': CDS_PINID='\gpioi1||mtdi2||rxd12\';
NODE_NAME     R639 1
 '@SCM_LIB.SCM(SCH_1):PAGE32_I88@PURE_QUANTA.Q_RES(CHIPS)':
 'A': CDS_PINID='A';
NET_NAME
'JTAG_1_BMC_TDO'
 '@SCM_LIB.SCM(SCH_1):JTAG_1_BMC_TDO':
 C_SIGNAL='@scm_lib.scm(sch_1):jtag_1_bmc_tdo';
NODE_NAME     U5 C16
 '@SCM_LIB.SCM(SCH_1):PAGE15_I350@PURE_QUANTA.AST2600A3GP(CHIPS)':
 'GPIOI4||MTDO2': CDS_PINID='\gpioi4||mtdo2\';
NODE_NAME     R398 1
 '@SCM_LIB.SCM(SCH_1):PAGE15_I351@PURE_QUANTA.Q_RES(CHIPS)':
 'A': CDS_PINID='A';
NET_NAME
'JTAG_1_BMC_TDO_R'
 '@SCM_LIB.SCM(SCH_1):JTAG_1_BMC_TDO_R':
 C_SIGNAL='@scm_lib.scm(sch_1):jtag_1_bmc_tdo_r';
NODE_NAME     R398 2
 '@SCM_LIB.SCM(SCH_1):PAGE15_I351@PURE_QUANTA.Q_RES(CHIPS)':
 'B': CDS_PINID='B';
NODE_NAME     R224 1
 '@SCM_LIB.SCM(SCH_1):PAGE32_I87@PURE_QUANTA.Q_RES(CHIPS)':
 'A': CDS_PINID='A';
NET_NAME
'JTAG_1_BMC_TMS_R'
 '@SCM_LIB.SCM(SCH_1):JTAG_1_BMC_TMS_R':
 C_SIGNAL='@scm_lib.scm(sch_1):jtag_1_bmc_tms_r';
NODE_NAME     U5 D16
 '@SCM_LIB.SCM(SCH_1):PAGE15_I350@PURE_QUANTA.AST2600A3GP(CHIPS)':
 'GPIOI3||MTMS2||RXD13': CDS_PINID='\gpioi3||mtms2||rxd13\';
NODE_NAME     R223 1
 '@SCM_LIB.SCM(SCH_1):PAGE32_I78@PURE_QUANTA.Q_RES(CHIPS)':
 'A': CDS_PINID='A';
NET_NAME
'JTAG_1_BMC_TRST_R'
 '@SCM_LIB.SCM(SCH_1):JTAG_1_BMC_TRST_R':
 C_SIGNAL='@scm_lib.scm(sch_1):jtag_1_bmc_trst_r';
NODE_NAME     U5 D17
 '@SCM_LIB.SCM(SCH_1):PAGE15_I350@PURE_QUANTA.AST2600A3GP(CHIPS)':
 'GPIOI0||MNTRST2||TXD12': CDS_PINID='\gpioi0||mntrst2||txd12\';
NODE_NAME     R221 1
 '@SCM_LIB.SCM(SCH_1):PAGE32_I81@PURE_QUANTA.Q_RES(CHIPS)':
 'A': CDS_PINID='A';
NET_NAME
'JTAG_MB_TCK'
 '@SCM_LIB.SCM(SCH_1):JTAG_MB_TCK':
 C_SIGNAL='@scm_lib.scm(sch_1):jtag_mb_tck';
NODE_NAME     GF1 A34
 '@SCM_LIB.SCM(SCH_1):PAGE10_I553@PURE_QUANTA.FCONN168_ME1016810202011_SCM(CHIPS)':
 'JTAG_TCK': CDS_PINID='JTAG_TCK';
NODE_NAME     R222 2
 '@SCM_LIB.SCM(SCH_1):PAGE32_I80@PURE_QUANTA.Q_RES(CHIPS)':
 'B': CDS_PINID='B';
NODE_NAME     R228 2
 '@SCM_LIB.SCM(SCH_1):PAGE32_I107@PURE_QUANTA.Q_RES(CHIPS)':
 'B': CDS_PINID='B';
NET_NAME
'JTAG_MB_TDI'
 '@SCM_LIB.SCM(SCH_1):JTAG_MB_TDI':
 C_SIGNAL='@scm_lib.scm(sch_1):jtag_mb_tdi';
NODE_NAME     GF1 A36
 '@SCM_LIB.SCM(SCH_1):PAGE10_I553@PURE_QUANTA.FCONN168_ME1016810202011_SCM(CHIPS)':
 'JTAG_TDI': CDS_PINID='JTAG_TDI';
NODE_NAME     R639 2
 '@SCM_LIB.SCM(SCH_1):PAGE32_I88@PURE_QUANTA.Q_RES(CHIPS)':
 'B': CDS_PINID='B';
NODE_NAME     R226 2
 '@SCM_LIB.SCM(SCH_1):PAGE32_I103@PURE_QUANTA.Q_RES(CHIPS)':
 'B': CDS_PINID='B';
NET_NAME
'JTAG_MB_TDO'
 '@SCM_LIB.SCM(SCH_1):JTAG_MB_TDO':
 C_SIGNAL='@scm_lib.scm(sch_1):jtag_mb_tdo';
NODE_NAME     GF1 A37
 '@SCM_LIB.SCM(SCH_1):PAGE10_I553@PURE_QUANTA.FCONN168_ME1016810202011_SCM(CHIPS)':
 'JTAG_TDO': CDS_PINID='JTAG_TDO';
NODE_NAME     R224 2
 '@SCM_LIB.SCM(SCH_1):PAGE32_I87@PURE_QUANTA.Q_RES(CHIPS)':
 'B': CDS_PINID='B';
NODE_NAME     R230 2
 '@SCM_LIB.SCM(SCH_1):PAGE32_I105@PURE_QUANTA.Q_RES(CHIPS)':
 'B': CDS_PINID='B';
NET_NAME
'JTAG_MB_TMS'
 '@SCM_LIB.SCM(SCH_1):JTAG_MB_TMS':
 C_SIGNAL='@scm_lib.scm(sch_1):jtag_mb_tms';
NODE_NAME     GF1 A35
 '@SCM_LIB.SCM(SCH_1):PAGE10_I553@PURE_QUANTA.FCONN168_ME1016810202011_SCM(CHIPS)':
 'JTAG_TMS': CDS_PINID='JTAG_TMS';
NODE_NAME     R223 2
 '@SCM_LIB.SCM(SCH_1):PAGE32_I78@PURE_QUANTA.Q_RES(CHIPS)':
 'B': CDS_PINID='B';
NODE_NAME     R227 2
 '@SCM_LIB.SCM(SCH_1):PAGE32_I104@PURE_QUANTA.Q_RES(CHIPS)':
 'B': CDS_PINID='B';
NET_NAME
'JTAG_MB_TRST_N'
 '@SCM_LIB.SCM(SCH_1):JTAG_MB_TRST_N':
 C_SIGNAL='@scm_lib.scm(sch_1):jtag_mb_trst_n';
NODE_NAME     R221 2
 '@SCM_LIB.SCM(SCH_1):PAGE32_I81@PURE_QUANTA.Q_RES(CHIPS)':
 'B': CDS_PINID='B';
NODE_NAME     R229 2
 '@SCM_LIB.SCM(SCH_1):PAGE32_I106@PURE_QUANTA.Q_RES(CHIPS)':
 'B': CDS_PINID='B';
NET_NAME
'JTAG_SCM_CONN_TCK'
 '@SCM_LIB.SCM(SCH_1):JTAG_SCM_CONN_TCK':
 C_SIGNAL='@scm_lib.scm(sch_1):jtag_scm_conn_tck';
NODE_NAME     R514 2
 '@SCM_LIB.SCM(SCH_1):PAGE32_I94@PURE_QUANTA.Q_RES(CHIPS)':
 'B': CDS_PINID='B';
NODE_NAME     J7 8
 '@SCM_LIB.SCM(SCH_1):PAGE32_I132@PURE_QUANTA.CONN8_210HP1080BR1(CHIPS)':
 '8': CDS_PINID='\8\';
NET_NAME
'JTAG_SCM_CONN_TDI'
 '@SCM_LIB.SCM(SCH_1):JTAG_SCM_CONN_TDI':
 C_SIGNAL='@scm_lib.scm(sch_1):jtag_scm_conn_tdi';
NODE_NAME     R516 2
 '@SCM_LIB.SCM(SCH_1):PAGE32_I95@PURE_QUANTA.Q_RES(CHIPS)':
 'B': CDS_PINID='B';
NODE_NAME     J7 3
 '@SCM_LIB.SCM(SCH_1):PAGE32_I132@PURE_QUANTA.CONN8_210HP1080BR1(CHIPS)':
 '3': CDS_PINID='\3\';
NET_NAME
'JTAG_SCM_CONN_TDO'
 '@SCM_LIB.SCM(SCH_1):JTAG_SCM_CONN_TDO':
 C_SIGNAL='@scm_lib.scm(sch_1):jtag_scm_conn_tdo';
NODE_NAME     R517 2
 '@SCM_LIB.SCM(SCH_1):PAGE32_I97@PURE_QUANTA.Q_RES(CHIPS)':
 'B': CDS_PINID='B';
NODE_NAME     J7 2
 '@SCM_LIB.SCM(SCH_1):PAGE32_I132@PURE_QUANTA.CONN8_210HP1080BR1(CHIPS)':
 '2': CDS_PINID='\2\';
NET_NAME
'JTAG_SCM_CONN_TMS'
 '@SCM_LIB.SCM(SCH_1):JTAG_SCM_CONN_TMS':
 C_SIGNAL='@scm_lib.scm(sch_1):jtag_scm_conn_tms';
NODE_NAME     R515 2
 '@SCM_LIB.SCM(SCH_1):PAGE32_I96@PURE_QUANTA.Q_RES(CHIPS)':
 'B': CDS_PINID='B';
NODE_NAME     J7 6
 '@SCM_LIB.SCM(SCH_1):PAGE32_I132@PURE_QUANTA.CONN8_210HP1080BR1(CHIPS)':
 '6': CDS_PINID='\6\';
NET_NAME
'JTAG_SCM_NTRST'
 '@SCM_LIB.SCM(SCH_1):JTAG_SCM_NTRST':
 C_SIGNAL='@scm_lib.scm(sch_1):jtag_scm_ntrst';
NODE_NAME     U5 F11
 '@SCM_LIB.SCM(SCH_1):PAGE15_I350@PURE_QUANTA.AST2600A3GP(CHIPS)':
 'NTRST||MNTRST1': CDS_PINID='\ntrst||mntrst1\';
NODE_NAME     R206 2
 '@SCM_LIB.SCM(SCH_1):PAGE32_I143@PURE_QUANTA.Q_RES(CHIPS)':
 'B': CDS_PINID='B';
NET_NAME
'JTAG_SCM_PLD_JTAGEN'
 '@SCM_LIB.SCM(SCH_1):JTAG_SCM_PLD_JTAGEN':
 C_SIGNAL='@scm_lib.scm(sch_1):jtag_scm_pld_jtagen';
NODE_NAME     R518 2
 '@SCM_LIB.SCM(SCH_1):PAGE32_I23@PURE_QUANTA.Q_RES(CHIPS)':
 'B': CDS_PINID='B';
NODE_NAME     R509 2
 '@SCM_LIB.SCM(SCH_1):PAGE48_I50@PURE_QUANTA.Q_RES(CHIPS)':
 'B': CDS_PINID='B';
NODE_NAME     R397 2
 '@SCM_LIB.SCM(SCH_1):PAGE34_I167@PURE_QUANTA.Q_RES(CHIPS)':
 'B': CDS_PINID='B';
NET_NAME
'JTAG_SCM_PLD_R1_JTAGEN'
 '@SCM_LIB.SCM(SCH_1):JTAG_SCM_PLD_R1_JTAGEN':
 C_SIGNAL='@scm_lib.scm(sch_1):jtag_scm_pld_r1_jtagen';
NODE_NAME     R518 1
 '@SCM_LIB.SCM(SCH_1):PAGE32_I23@PURE_QUANTA.Q_RES(CHIPS)':
 'A': CDS_PINID='A';
NODE_NAME     J7 4
 '@SCM_LIB.SCM(SCH_1):PAGE32_I132@PURE_QUANTA.CONN8_210HP1080BR1(CHIPS)':
 '4': CDS_PINID='\4\';
NET_NAME
'JTAG_SCM_PLD_R_JTAGEN'
 '@SCM_LIB.SCM(SCH_1):JTAG_SCM_PLD_R_JTAGEN':
 C_SIGNAL='@scm_lib.scm(sch_1):jtag_scm_pld_r_jtagen';
NODE_NAME     U25 C10
 '@SCM_LIB.SCM(SCH_1):PAGE34_I1@PURE_QUANTA.LCMXO3LF2100C5BG256C(CHIPS)':
 'PT20C||JTAGENB': CDS_PINID='\pt20c||jtagenb\';
NODE_NAME     R397 1
 '@SCM_LIB.SCM(SCH_1):PAGE34_I167@PURE_QUANTA.Q_RES(CHIPS)':
 'A': CDS_PINID='A';
NET_NAME
'JTAG_SCM_PLD_TCK'
 '@SCM_LIB.SCM(SCH_1):JTAG_SCM_PLD_TCK':
 C_SIGNAL='@scm_lib.scm(sch_1):jtag_scm_pld_tck';
NODE_NAME     R514 1
 '@SCM_LIB.SCM(SCH_1):PAGE32_I94@PURE_QUANTA.Q_RES(CHIPS)':
 'A': CDS_PINID='A';
NODE_NAME     R510 2
 '@SCM_LIB.SCM(SCH_1):PAGE32_I126@PURE_QUANTA.Q_RES(CHIPS)':
 'B': CDS_PINID='B';
NODE_NAME     U25 A7
 '@SCM_LIB.SCM(SCH_1):PAGE34_I1@PURE_QUANTA.LCMXO3LF2100C5BG256C(CHIPS)':
 'PT16C||TCK': CDS_PINID='\pt16c||tck\';
NODE_NAME     R285 1
 '@SCM_LIB.SCM(SCH_1):PAGE32_I141@PURE_QUANTA.Q_RES(CHIPS)':
 'A': CDS_PINID='A';
NET_NAME
'JTAG_SCM_PLD_TDI'
 '@SCM_LIB.SCM(SCH_1):JTAG_SCM_PLD_TDI':
 C_SIGNAL='@scm_lib.scm(sch_1):jtag_scm_pld_tdi';
NODE_NAME     R516 1
 '@SCM_LIB.SCM(SCH_1):PAGE32_I95@PURE_QUANTA.Q_RES(CHIPS)':
 'A': CDS_PINID='A';
NODE_NAME     R512 2
 '@SCM_LIB.SCM(SCH_1):PAGE32_I129@PURE_QUANTA.Q_RES(CHIPS)':
 'B': CDS_PINID='B';
NODE_NAME     U25 A6
 '@SCM_LIB.SCM(SCH_1):PAGE34_I1@PURE_QUANTA.LCMXO3LF2100C5BG256C(CHIPS)':
 'PT12D||TDI': CDS_PINID='\pt12d||tdi\';
NET_NAME
'JTAG_SCM_PLD_TDO'
 '@SCM_LIB.SCM(SCH_1):JTAG_SCM_PLD_TDO':
 C_SIGNAL='@scm_lib.scm(sch_1):jtag_scm_pld_tdo';
NODE_NAME     R517 1
 '@SCM_LIB.SCM(SCH_1):PAGE32_I97@PURE_QUANTA.Q_RES(CHIPS)':
 'A': CDS_PINID='A';
NODE_NAME     R513 2
 '@SCM_LIB.SCM(SCH_1):PAGE32_I128@PURE_QUANTA.Q_RES(CHIPS)':
 'B': CDS_PINID='B';
NODE_NAME     U25 C6
 '@SCM_LIB.SCM(SCH_1):PAGE34_I1@PURE_QUANTA.LCMXO3LF2100C5BG256C(CHIPS)':
 'PT12C||TDO': CDS_PINID='\pt12c||tdo\';
NET_NAME
'JTAG_SCM_PLD_TMS'
 '@SCM_LIB.SCM(SCH_1):JTAG_SCM_PLD_TMS':
 C_SIGNAL='@scm_lib.scm(sch_1):jtag_scm_pld_tms';
NODE_NAME     R515 1
 '@SCM_LIB.SCM(SCH_1):PAGE32_I96@PURE_QUANTA.Q_RES(CHIPS)':
 'A': CDS_PINID='A';
NODE_NAME     R511 2
 '@SCM_LIB.SCM(SCH_1):PAGE32_I127@PURE_QUANTA.Q_RES(CHIPS)':
 'B': CDS_PINID='B';
NODE_NAME     U25 B8
 '@SCM_LIB.SCM(SCH_1):PAGE34_I1@PURE_QUANTA.LCMXO3LF2100C5BG256C(CHIPS)':
 'PT16D||TMS': CDS_PINID='\pt16d||tms\';
NET_NAME
'JTAG_SCM_TCK'
 '@SCM_LIB.SCM(SCH_1):JTAG_SCM_TCK':
 C_SIGNAL='@scm_lib.scm(sch_1):jtag_scm_tck';
NODE_NAME     U5 B9
 '@SCM_LIB.SCM(SCH_1):PAGE15_I350@PURE_QUANTA.AST2600A3GP(CHIPS)':
 'TCK||MTCK1': CDS_PINID='\tck||mtck1\';
NODE_NAME     R510 1
 '@SCM_LIB.SCM(SCH_1):PAGE32_I126@PURE_QUANTA.Q_RES(CHIPS)':
 'A': CDS_PINID='A';
NODE_NAME     R834 2
 '@SCM_LIB.SCM(SCH_1):PAGE32_I131@PURE_QUANTA.Q_RES(CHIPS)':
 'B': CDS_PINID='B';
NODE_NAME     R202 2
 '@SCM_LIB.SCM(SCH_1):PAGE32_I140@PURE_QUANTA.Q_RES(CHIPS)':
 'B': CDS_PINID='B';
NET_NAME
'JTAG_SCM_TDI'
 '@SCM_LIB.SCM(SCH_1):JTAG_SCM_TDI':
 C_SIGNAL='@scm_lib.scm(sch_1):jtag_scm_tdi';
NODE_NAME     U5 D9
 '@SCM_LIB.SCM(SCH_1):PAGE15_I350@PURE_QUANTA.AST2600A3GP(CHIPS)':
 'TDI||MTDI1': CDS_PINID='\tdi||mtdi1\';
NODE_NAME     R204 2
 '@SCM_LIB.SCM(SCH_1):PAGE32_I120@PURE_QUANTA.Q_RES(CHIPS)':
 'B': CDS_PINID='B';
NODE_NAME     R512 1
 '@SCM_LIB.SCM(SCH_1):PAGE32_I129@PURE_QUANTA.Q_RES(CHIPS)':
 'A': CDS_PINID='A';
NET_NAME
'JTAG_SCM_TDO'
 '@SCM_LIB.SCM(SCH_1):JTAG_SCM_TDO':
 C_SIGNAL='@scm_lib.scm(sch_1):jtag_scm_tdo';
NODE_NAME     U5 C9
 '@SCM_LIB.SCM(SCH_1):PAGE15_I350@PURE_QUANTA.AST2600A3GP(CHIPS)':
 'TDO||MTDO1': CDS_PINID='\tdo||mtdo1\';
NODE_NAME     R523 2
 '@SCM_LIB.SCM(SCH_1):PAGE32_I119@PURE_QUANTA.Q_RES(CHIPS)':
 'B': CDS_PINID='B';
NODE_NAME     R513 1
 '@SCM_LIB.SCM(SCH_1):PAGE32_I128@PURE_QUANTA.Q_RES(CHIPS)':
 'A': CDS_PINID='A';
NET_NAME
'JTAG_SCM_TMS'
 '@SCM_LIB.SCM(SCH_1):JTAG_SCM_TMS':
 C_SIGNAL='@scm_lib.scm(sch_1):jtag_scm_tms';
NODE_NAME     U5 A9
 '@SCM_LIB.SCM(SCH_1):PAGE15_I350@PURE_QUANTA.AST2600A3GP(CHIPS)':
 'TMS||MTMS1': CDS_PINID='\tms||mtms1\';
NODE_NAME     R203 2
 '@SCM_LIB.SCM(SCH_1):PAGE32_I117@PURE_QUANTA.Q_RES(CHIPS)':
 'B': CDS_PINID='B';
NODE_NAME     R511 1
 '@SCM_LIB.SCM(SCH_1):PAGE32_I127@PURE_QUANTA.Q_RES(CHIPS)':
 'A': CDS_PINID='A';
NET_NAME
'LED_D21_R1'
 '@SCM_LIB.SCM(SCH_1):LED_D21_R1':
 C_SIGNAL='@scm_lib.scm(sch_1):led_d21_r1';
NODE_NAME     R286 2
 '@SCM_LIB.SCM(SCH_1):PAGE50_I224@PURE_QUANTA.Q_RES(CHIPS)':
 'B': CDS_PINID='B';
NODE_NAME     R389 1
 '@SCM_LIB.SCM(SCH_1):PAGE50_I225@PURE_QUANTA.Q_RES(CHIPS)':
 'A': CDS_PINID='A';
NET_NAME
'LED_D21_R2'
 '@SCM_LIB.SCM(SCH_1):LED_D21_R2':
 C_SIGNAL='@scm_lib.scm(sch_1):led_d21_r2';
NODE_NAME     R107 2
 '@SCM_LIB.SCM(SCH_1):PAGE50_I222@PURE_QUANTA.Q_RES(CHIPS)':
 'B': CDS_PINID='B';
NODE_NAME     R286 1
 '@SCM_LIB.SCM(SCH_1):PAGE50_I224@PURE_QUANTA.Q_RES(CHIPS)':
 'A': CDS_PINID='A';
NET_NAME
'LED_D21_R3'
 '@SCM_LIB.SCM(SCH_1):LED_D21_R3':
 C_SIGNAL='@scm_lib.scm(sch_1):led_d21_r3';
NODE_NAME     R107 1
 '@SCM_LIB.SCM(SCH_1):PAGE50_I222@PURE_QUANTA.Q_RES(CHIPS)':
 'A': CDS_PINID='A';
NODE_NAME     D21 A
 '@SCM_LIB.SCM(SCH_1):PAGE50_I294@PURE_QUANTA.Q_LED(CHIPS)':
 'A': CDS_PINID='A';
NET_NAME
'LED_D22_R'
 '@SCM_LIB.SCM(SCH_1):LED_D22_R':
 C_SIGNAL='@scm_lib.scm(sch_1):led_d22_r';
NODE_NAME     R80 1
 '@SCM_LIB.SCM(SCH_1):PAGE50_I210@PURE_QUANTA.Q_RES(CHIPS)':
 'A': CDS_PINID='A';
NODE_NAME     C27 1
 '@SCM_LIB.SCM(SCH_1):PAGE50_I212@PURE_QUANTA.Q_CAP(CHIPS)':
 'A': CDS_PINID='A';
NODE_NAME     D22 A
 '@SCM_LIB.SCM(SCH_1):PAGE50_I295@PURE_QUANTA.Q_LED(CHIPS)':
 'A': CDS_PINID='A';
NET_NAME
'LED_D22_R1'
 '@SCM_LIB.SCM(SCH_1):LED_D22_R1':
 C_SIGNAL='@scm_lib.scm(sch_1):led_d22_r1';
NODE_NAME     Q13 6
 '@SCM_LIB.SCM(SCH_1):PAGE50_I218@PURE_QUANTA.MOSFET_NCH_DUAL(CHIPS)':
 'D1': CDS_PINID='D1';
NODE_NAME     D22 C
 '@SCM_LIB.SCM(SCH_1):PAGE50_I295@PURE_QUANTA.Q_LED(CHIPS)':
 'C': CDS_PINID='C';
NET_NAME
'LED_POSTCODE_0'
 '@SCM_LIB.SCM(SCH_1):LED_POSTCODE_0':
 C_SIGNAL='@scm_lib.scm(sch_1):led_postcode_0';
NODE_NAME     U5 P25
 '@SCM_LIB.SCM(SCH_1):PAGE13_I363@PURE_QUANTA.AST2600A3GP(CHIPS)':
 'GPION0||NCTS2': CDS_PINID='\gpion0||ncts2\';
NODE_NAME     R604 1
 '@SCM_LIB.SCM(SCH_1):PAGE47_I37@PURE_QUANTA.Q_RES(CHIPS)':
 'A': CDS_PINID='A';
NODE_NAME     R700 1
 '@SCM_LIB.SCM(SCH_1):PAGE47_I62@PURE_QUANTA.Q_RES(CHIPS)':
 'A': CDS_PINID='A';
NET_NAME
'LED_POSTCODE_0_R'
 '@SCM_LIB.SCM(SCH_1):LED_POSTCODE_0_R':
 C_SIGNAL='@scm_lib.scm(sch_1):led_postcode_0_r';
NODE_NAME     D0 A
 '@SCM_LIB.SCM(SCH_1):PAGE47_I7@PURE_QUANTA.Q_LED(CHIPS)':
 'A': CDS_PINID='A';
NODE_NAME     R604 2
 '@SCM_LIB.SCM(SCH_1):PAGE47_I37@PURE_QUANTA.Q_RES(CHIPS)':
 'B': CDS_PINID='B';
NET_NAME
'LED_POSTCODE_0_R1'
 '@SCM_LIB.SCM(SCH_1):LED_POSTCODE_0_R1':
 C_SIGNAL='@scm_lib.scm(sch_1):led_postcode_0_r1';
NODE_NAME     U40 4
 '@SCM_LIB.SCM(SCH_1):PAGE28_I141@PURE_QUANTA.PCA9555PW(CHIPS)':
 'P00': CDS_PINID='P00';
NODE_NAME     R700 2
 '@SCM_LIB.SCM(SCH_1):PAGE47_I62@PURE_QUANTA.Q_RES(CHIPS)':
 'B': CDS_PINID='B';
NET_NAME
'LED_POSTCODE_1'
 '@SCM_LIB.SCM(SCH_1):LED_POSTCODE_1':
 C_SIGNAL='@scm_lib.scm(sch_1):led_postcode_1';
NODE_NAME     U5 N23
 '@SCM_LIB.SCM(SCH_1):PAGE13_I363@PURE_QUANTA.AST2600A3GP(CHIPS)':
 'GPION1||NDCD2': CDS_PINID='\gpion1||ndcd2\';
NODE_NAME     R603 1
 '@SCM_LIB.SCM(SCH_1):PAGE47_I35@PURE_QUANTA.Q_RES(CHIPS)':
 'A': CDS_PINID='A';
NODE_NAME     R698 1
 '@SCM_LIB.SCM(SCH_1):PAGE47_I60@PURE_QUANTA.Q_RES(CHIPS)':
 'A': CDS_PINID='A';
NET_NAME
'LED_POSTCODE_1_R'
 '@SCM_LIB.SCM(SCH_1):LED_POSTCODE_1_R':
 C_SIGNAL='@scm_lib.scm(sch_1):led_postcode_1_r';
NODE_NAME     D1 A
 '@SCM_LIB.SCM(SCH_1):PAGE47_I9@PURE_QUANTA.Q_LED(CHIPS)':
 'A': CDS_PINID='A';
NODE_NAME     R603 2
 '@SCM_LIB.SCM(SCH_1):PAGE47_I35@PURE_QUANTA.Q_RES(CHIPS)':
 'B': CDS_PINID='B';
NET_NAME
'LED_POSTCODE_1_R1'
 '@SCM_LIB.SCM(SCH_1):LED_POSTCODE_1_R1':
 C_SIGNAL='@scm_lib.scm(sch_1):led_postcode_1_r1';
NODE_NAME     U40 5
 '@SCM_LIB.SCM(SCH_1):PAGE28_I141@PURE_QUANTA.PCA9555PW(CHIPS)':
 'P01': CDS_PINID='P01';
NODE_NAME     R698 2
 '@SCM_LIB.SCM(SCH_1):PAGE47_I60@PURE_QUANTA.Q_RES(CHIPS)':
 'B': CDS_PINID='B';
NET_NAME
'LED_POSTCODE_2'
 '@SCM_LIB.SCM(SCH_1):LED_POSTCODE_2':
 C_SIGNAL='@scm_lib.scm(sch_1):led_postcode_2';
NODE_NAME     U5 N25
 '@SCM_LIB.SCM(SCH_1):PAGE13_I363@PURE_QUANTA.AST2600A3GP(CHIPS)':
 'GPION2||NDSR2': CDS_PINID='\gpion2||ndsr2\';
NODE_NAME     R602 1
 '@SCM_LIB.SCM(SCH_1):PAGE47_I33@PURE_QUANTA.Q_RES(CHIPS)':
 'A': CDS_PINID='A';
NODE_NAME     R697 1
 '@SCM_LIB.SCM(SCH_1):PAGE47_I58@PURE_QUANTA.Q_RES(CHIPS)':
 'A': CDS_PINID='A';
NET_NAME
'LED_POSTCODE_2_R'
 '@SCM_LIB.SCM(SCH_1):LED_POSTCODE_2_R':
 C_SIGNAL='@scm_lib.scm(sch_1):led_postcode_2_r';
NODE_NAME     D2 A
 '@SCM_LIB.SCM(SCH_1):PAGE47_I11@PURE_QUANTA.Q_LED(CHIPS)':
 'A': CDS_PINID='A';
NODE_NAME     R602 2
 '@SCM_LIB.SCM(SCH_1):PAGE47_I33@PURE_QUANTA.Q_RES(CHIPS)':
 'B': CDS_PINID='B';
NET_NAME
'LED_POSTCODE_2_R1'
 '@SCM_LIB.SCM(SCH_1):LED_POSTCODE_2_R1':
 C_SIGNAL='@scm_lib.scm(sch_1):led_postcode_2_r1';
NODE_NAME     U40 6
 '@SCM_LIB.SCM(SCH_1):PAGE28_I141@PURE_QUANTA.PCA9555PW(CHIPS)':
 'P02': CDS_PINID='P02';
NODE_NAME     R697 2
 '@SCM_LIB.SCM(SCH_1):PAGE47_I58@PURE_QUANTA.Q_RES(CHIPS)':
 'B': CDS_PINID='B';
NET_NAME
'LED_POSTCODE_3'
 '@SCM_LIB.SCM(SCH_1):LED_POSTCODE_3':
 C_SIGNAL='@scm_lib.scm(sch_1):led_postcode_3';
NODE_NAME     U5 N24
 '@SCM_LIB.SCM(SCH_1):PAGE13_I363@PURE_QUANTA.AST2600A3GP(CHIPS)':
 'GPION3||NRI2': CDS_PINID='\gpion3||nri2\';
NODE_NAME     R601 1
 '@SCM_LIB.SCM(SCH_1):PAGE47_I31@PURE_QUANTA.Q_RES(CHIPS)':
 'A': CDS_PINID='A';
NODE_NAME     R696 1
 '@SCM_LIB.SCM(SCH_1):PAGE47_I56@PURE_QUANTA.Q_RES(CHIPS)':
 'A': CDS_PINID='A';
NET_NAME
'LED_POSTCODE_3_R'
 '@SCM_LIB.SCM(SCH_1):LED_POSTCODE_3_R':
 C_SIGNAL='@scm_lib.scm(sch_1):led_postcode_3_r';
NODE_NAME     D3 A
 '@SCM_LIB.SCM(SCH_1):PAGE47_I13@PURE_QUANTA.Q_LED(CHIPS)':
 'A': CDS_PINID='A';
NODE_NAME     R601 2
 '@SCM_LIB.SCM(SCH_1):PAGE47_I31@PURE_QUANTA.Q_RES(CHIPS)':
 'B': CDS_PINID='B';
NET_NAME
'LED_POSTCODE_3_R1'
 '@SCM_LIB.SCM(SCH_1):LED_POSTCODE_3_R1':
 C_SIGNAL='@scm_lib.scm(sch_1):led_postcode_3_r1';
NODE_NAME     U40 7
 '@SCM_LIB.SCM(SCH_1):PAGE28_I141@PURE_QUANTA.PCA9555PW(CHIPS)':
 'P03': CDS_PINID='P03';
NODE_NAME     R696 2
 '@SCM_LIB.SCM(SCH_1):PAGE47_I56@PURE_QUANTA.Q_RES(CHIPS)':
 'B': CDS_PINID='B';
NET_NAME
'LED_POSTCODE_4'
 '@SCM_LIB.SCM(SCH_1):LED_POSTCODE_4':
 C_SIGNAL='@scm_lib.scm(sch_1):led_postcode_4';
NODE_NAME     U5 P26
 '@SCM_LIB.SCM(SCH_1):PAGE13_I363@PURE_QUANTA.AST2600A3GP(CHIPS)':
 'GPION4||NDTR2': CDS_PINID='\gpion4||ndtr2\';
NODE_NAME     R600 1
 '@SCM_LIB.SCM(SCH_1):PAGE47_I25@PURE_QUANTA.Q_RES(CHIPS)':
 'A': CDS_PINID='A';
NODE_NAME     R695 1
 '@SCM_LIB.SCM(SCH_1):PAGE47_I54@PURE_QUANTA.Q_RES(CHIPS)':
 'A': CDS_PINID='A';
NET_NAME
'LED_POSTCODE_4_R'
 '@SCM_LIB.SCM(SCH_1):LED_POSTCODE_4_R':
 C_SIGNAL='@scm_lib.scm(sch_1):led_postcode_4_r';
NODE_NAME     D4 A
 '@SCM_LIB.SCM(SCH_1):PAGE47_I10@PURE_QUANTA.Q_LED(CHIPS)':
 'A': CDS_PINID='A';
NODE_NAME     R600 2
 '@SCM_LIB.SCM(SCH_1):PAGE47_I25@PURE_QUANTA.Q_RES(CHIPS)':
 'B': CDS_PINID='B';
NET_NAME
'LED_POSTCODE_4_R1'
 '@SCM_LIB.SCM(SCH_1):LED_POSTCODE_4_R1':
 C_SIGNAL='@scm_lib.scm(sch_1):led_postcode_4_r1';
NODE_NAME     U40 8
 '@SCM_LIB.SCM(SCH_1):PAGE28_I141@PURE_QUANTA.PCA9555PW(CHIPS)':
 'P04': CDS_PINID='P04';
NODE_NAME     R695 2
 '@SCM_LIB.SCM(SCH_1):PAGE47_I54@PURE_QUANTA.Q_RES(CHIPS)':
 'B': CDS_PINID='B';
NET_NAME
'LED_POSTCODE_5'
 '@SCM_LIB.SCM(SCH_1):LED_POSTCODE_5':
 C_SIGNAL='@scm_lib.scm(sch_1):led_postcode_5';
NODE_NAME     U5 M23
 '@SCM_LIB.SCM(SCH_1):PAGE13_I363@PURE_QUANTA.AST2600A3GP(CHIPS)':
 'GPION5||NRTS2': CDS_PINID='\gpion5||nrts2\';
NODE_NAME     R599 1
 '@SCM_LIB.SCM(SCH_1):PAGE47_I23@PURE_QUANTA.Q_RES(CHIPS)':
 'A': CDS_PINID='A';
NODE_NAME     R676 1
 '@SCM_LIB.SCM(SCH_1):PAGE47_I52@PURE_QUANTA.Q_RES(CHIPS)':
 'A': CDS_PINID='A';
NET_NAME
'LED_POSTCODE_5_R'
 '@SCM_LIB.SCM(SCH_1):LED_POSTCODE_5_R':
 C_SIGNAL='@scm_lib.scm(sch_1):led_postcode_5_r';
NODE_NAME     D5 A
 '@SCM_LIB.SCM(SCH_1):PAGE47_I12@PURE_QUANTA.Q_LED(CHIPS)':
 'A': CDS_PINID='A';
NODE_NAME     R599 2
 '@SCM_LIB.SCM(SCH_1):PAGE47_I23@PURE_QUANTA.Q_RES(CHIPS)':
 'B': CDS_PINID='B';
NET_NAME
'LED_POSTCODE_5_R1'
 '@SCM_LIB.SCM(SCH_1):LED_POSTCODE_5_R1':
 C_SIGNAL='@scm_lib.scm(sch_1):led_postcode_5_r1';
NODE_NAME     U40 9
 '@SCM_LIB.SCM(SCH_1):PAGE28_I141@PURE_QUANTA.PCA9555PW(CHIPS)':
 'P05': CDS_PINID='P05';
NODE_NAME     R676 2
 '@SCM_LIB.SCM(SCH_1):PAGE47_I52@PURE_QUANTA.Q_RES(CHIPS)':
 'B': CDS_PINID='B';
NET_NAME
'LED_POSTCODE_6'
 '@SCM_LIB.SCM(SCH_1):LED_POSTCODE_6':
 C_SIGNAL='@scm_lib.scm(sch_1):led_postcode_6';
NODE_NAME     U5 N26
 '@SCM_LIB.SCM(SCH_1):PAGE13_I363@PURE_QUANTA.AST2600A3GP(CHIPS)':
 'GPION6||TXD2': CDS_PINID='\gpion6||txd2\';
NODE_NAME     R598 1
 '@SCM_LIB.SCM(SCH_1):PAGE47_I20@PURE_QUANTA.Q_RES(CHIPS)':
 'A': CDS_PINID='A';
NODE_NAME     R674 1
 '@SCM_LIB.SCM(SCH_1):PAGE47_I50@PURE_QUANTA.Q_RES(CHIPS)':
 'A': CDS_PINID='A';
NET_NAME
'LED_POSTCODE_6_R'
 '@SCM_LIB.SCM(SCH_1):LED_POSTCODE_6_R':
 C_SIGNAL='@scm_lib.scm(sch_1):led_postcode_6_r';
NODE_NAME     D6 A
 '@SCM_LIB.SCM(SCH_1):PAGE47_I14@PURE_QUANTA.Q_LED(CHIPS)':
 'A': CDS_PINID='A';
NODE_NAME     R598 2
 '@SCM_LIB.SCM(SCH_1):PAGE47_I20@PURE_QUANTA.Q_RES(CHIPS)':
 'B': CDS_PINID='B';
NET_NAME
'LED_POSTCODE_6_R1'
 '@SCM_LIB.SCM(SCH_1):LED_POSTCODE_6_R1':
 C_SIGNAL='@scm_lib.scm(sch_1):led_postcode_6_r1';
NODE_NAME     U40 10
 '@SCM_LIB.SCM(SCH_1):PAGE28_I141@PURE_QUANTA.PCA9555PW(CHIPS)':
 'P06': CDS_PINID='P06';
NODE_NAME     R674 2
 '@SCM_LIB.SCM(SCH_1):PAGE47_I50@PURE_QUANTA.Q_RES(CHIPS)':
 'B': CDS_PINID='B';
NET_NAME
'LED_POSTCODE_7'
 '@SCM_LIB.SCM(SCH_1):LED_POSTCODE_7':
 C_SIGNAL='@scm_lib.scm(sch_1):led_postcode_7';
NODE_NAME     U5 M26
 '@SCM_LIB.SCM(SCH_1):PAGE13_I363@PURE_QUANTA.AST2600A3GP(CHIPS)':
 'GPION7||RXD2': CDS_PINID='\gpion7||rxd2\';
NODE_NAME     R597 1
 '@SCM_LIB.SCM(SCH_1):PAGE47_I18@PURE_QUANTA.Q_RES(CHIPS)':
 'A': CDS_PINID='A';
NODE_NAME     R669 1
 '@SCM_LIB.SCM(SCH_1):PAGE47_I48@PURE_QUANTA.Q_RES(CHIPS)':
 'A': CDS_PINID='A';
NET_NAME
'LED_POSTCODE_7_R'
 '@SCM_LIB.SCM(SCH_1):LED_POSTCODE_7_R':
 C_SIGNAL='@scm_lib.scm(sch_1):led_postcode_7_r';
NODE_NAME     D7 A
 '@SCM_LIB.SCM(SCH_1):PAGE47_I5@PURE_QUANTA.Q_LED(CHIPS)':
 'A': CDS_PINID='A';
NODE_NAME     R597 2
 '@SCM_LIB.SCM(SCH_1):PAGE47_I18@PURE_QUANTA.Q_RES(CHIPS)':
 'B': CDS_PINID='B';
NET_NAME
'LED_POSTCODE_7_R1'
 '@SCM_LIB.SCM(SCH_1):LED_POSTCODE_7_R1':
 C_SIGNAL='@scm_lib.scm(sch_1):led_postcode_7_r1';
NODE_NAME     U40 11
 '@SCM_LIB.SCM(SCH_1):PAGE28_I141@PURE_QUANTA.PCA9555PW(CHIPS)':
 'P07': CDS_PINID='P07';
NODE_NAME     R669 2
 '@SCM_LIB.SCM(SCH_1):PAGE47_I48@PURE_QUANTA.Q_RES(CHIPS)':
 'B': CDS_PINID='B';
NET_NAME
'LED_POSTCODE_A0'
 '@SCM_LIB.SCM(SCH_1):LED_POSTCODE_A0':
 C_SIGNAL='@scm_lib.scm(sch_1):led_postcode_a0';
NODE_NAME     U40 21
 '@SCM_LIB.SCM(SCH_1):PAGE28_I141@PURE_QUANTA.PCA9555PW(CHIPS)':
 'A0': CDS_PINID='A0';
NODE_NAME     R738 2
 '@SCM_LIB.SCM(SCH_1):PAGE28_I171@PURE_QUANTA.Q_RES(CHIPS)':
 'B': CDS_PINID='B';
NODE_NAME     R743 1
 '@SCM_LIB.SCM(SCH_1):PAGE28_I175@PURE_QUANTA.Q_RES(CHIPS)':
 'A': CDS_PINID='A';
NET_NAME
'LED_POSTCODE_A1'
 '@SCM_LIB.SCM(SCH_1):LED_POSTCODE_A1':
 C_SIGNAL='@scm_lib.scm(sch_1):led_postcode_a1';
NODE_NAME     U40 2
 '@SCM_LIB.SCM(SCH_1):PAGE28_I141@PURE_QUANTA.PCA9555PW(CHIPS)':
 'A1': CDS_PINID='A1';
NODE_NAME     R739 2
 '@SCM_LIB.SCM(SCH_1):PAGE28_I169@PURE_QUANTA.Q_RES(CHIPS)':
 'B': CDS_PINID='B';
NODE_NAME     R744 1
 '@SCM_LIB.SCM(SCH_1):PAGE28_I173@PURE_QUANTA.Q_RES(CHIPS)':
 'A': CDS_PINID='A';
NET_NAME
'LED_POSTCODE_A2'
 '@SCM_LIB.SCM(SCH_1):LED_POSTCODE_A2':
 C_SIGNAL='@scm_lib.scm(sch_1):led_postcode_a2';
NODE_NAME     U40 3
 '@SCM_LIB.SCM(SCH_1):PAGE28_I141@PURE_QUANTA.PCA9555PW(CHIPS)':
 'A2': CDS_PINID='A2';
NODE_NAME     R740 2
 '@SCM_LIB.SCM(SCH_1):PAGE28_I168@PURE_QUANTA.Q_RES(CHIPS)':
 'B': CDS_PINID='B';
NODE_NAME     R745 1
 '@SCM_LIB.SCM(SCH_1):PAGE28_I172@PURE_QUANTA.Q_RES(CHIPS)':
 'A': CDS_PINID='A';
NET_NAME
'LED_POSTCODE_INT'
 '@SCM_LIB.SCM(SCH_1):LED_POSTCODE_INT':
 C_SIGNAL='@scm_lib.scm(sch_1):led_postcode_int';
NODE_NAME     U40 1
 '@SCM_LIB.SCM(SCH_1):PAGE28_I141@PURE_QUANTA.PCA9555PW(CHIPS)':
 'INT*': CDS_PINID='\int*\';
NODE_NAME     R667 2
 '@SCM_LIB.SCM(SCH_1):PAGE28_I147@PURE_QUANTA.Q_RES(CHIPS)':
 'B': CDS_PINID='B';
NET_NAME
'LPC_ESPI_SEL'
 '@SCM_LIB.SCM(SCH_1):LPC_ESPI_SEL':
 C_SIGNAL='@scm_lib.scm(sch_1):lpc_espi_sel';
NODE_NAME     GF1 B9
 '@SCM_LIB.SCM(SCH_1):PAGE10_I553@PURE_QUANTA.FCONN168_ME1016810202011_SCM(CHIPS)':
 'RSVD3': CDS_PINID='RSVD3';
NODE_NAME     R41 2
 '@SCM_LIB.SCM(SCH_1):PAGE11_I225@PURE_QUANTA.Q_RES(CHIPS)':
 'B': CDS_PINID='B';
NODE_NAME     R713 2
 '@SCM_LIB.SCM(SCH_1):PAGE17_I228@PURE_QUANTA.Q_RES(CHIPS)':
 'B': CDS_PINID='B';
NODE_NAME     R714 1
 '@SCM_LIB.SCM(SCH_1):PAGE27_I165@PURE_QUANTA.Q_RES(CHIPS)':
 'A': CDS_PINID='A';
NET_NAME
'LPC_ESPI_SEL_N'
 '@SCM_LIB.SCM(SCH_1):LPC_ESPI_SEL_N':
 C_SIGNAL='@scm_lib.scm(sch_1):lpc_espi_sel_n';
NODE_NAME     Q10 D
 '@SCM_LIB.SCM(SCH_1):PAGE17_I227@PURE_QUANTA.MOSFET_N_GSD(CHIPS)':
 'DRAIN': CDS_PINID='DRAIN';
NODE_NAME     R716 2
 '@SCM_LIB.SCM(SCH_1):PAGE17_I230@PURE_QUANTA.Q_RES(CHIPS)':
 'B': CDS_PINID='B';
NODE_NAME     C270 1
 '@SCM_LIB.SCM(SCH_1):PAGE17_I239@PURE_QUANTA.Q_CAP(CHIPS)':
 'A': CDS_PINID='A';
NODE_NAME     Q5 3
 '@SCM_LIB.SCM(SCH_1):PAGE17_I274@PURE_QUANTA.MOSFET_NCH_4D1S(CHIPS)':
 '3': CDS_PINID='\3\';
NODE_NAME     R493 1
 '@SCM_LIB.SCM(SCH_1):PAGE17_I284@PURE_QUANTA.Q_RES(CHIPS)':
 'A': CDS_PINID='A';
NODE_NAME     Q4 G
 '@SCM_LIB.SCM(SCH_1):PAGE17_I289@PURE_QUANTA.MOSFET_PCH_GDS(CHIPS)':
 'G': CDS_PINID='G';
NET_NAME
'LPC_ESPI_SEL_R'
 '@SCM_LIB.SCM(SCH_1):LPC_ESPI_SEL_R':
 C_SIGNAL='@scm_lib.scm(sch_1):lpc_espi_sel_r';
NODE_NAME     Q10 G
 '@SCM_LIB.SCM(SCH_1):PAGE17_I227@PURE_QUANTA.MOSFET_N_GSD(CHIPS)':
 'GATE': CDS_PINID='GATE';
NODE_NAME     R713 1
 '@SCM_LIB.SCM(SCH_1):PAGE17_I228@PURE_QUANTA.Q_RES(CHIPS)':
 'A': CDS_PINID='A';
NODE_NAME     C273 1
 '@SCM_LIB.SCM(SCH_1):PAGE17_I234@PURE_QUANTA.Q_CAP(CHIPS)':
 'A': CDS_PINID='A';
NET_NAME
'LPC_ESPI_SEL_R1'
 '@SCM_LIB.SCM(SCH_1):LPC_ESPI_SEL_R1':
 C_SIGNAL='@scm_lib.scm(sch_1):lpc_espi_sel_r1';
NODE_NAME     R714 2
 '@SCM_LIB.SCM(SCH_1):PAGE27_I165@PURE_QUANTA.Q_RES(CHIPS)':
 'B': CDS_PINID='B';
NODE_NAME     C267 1
 '@SCM_LIB.SCM(SCH_1):PAGE27_I166@PURE_QUANTA.Q_CAP(CHIPS)':
 'A': CDS_PINID='A';
NODE_NAME     Q7 G
 '@SCM_LIB.SCM(SCH_1):PAGE27_I243@PURE_QUANTA.2N7002A7(CHIPS)':
 'G': CDS_PINID='G';
NET_NAME
'MB_JTAG_PLD_R_JTAGEN'
 '@SCM_LIB.SCM(SCH_1):MB_JTAG_PLD_R_JTAGEN':
 C_SIGNAL='@scm_lib.scm(sch_1):mb_jtag_pld_r_jtagen';
NODE_NAME     R509 1
 '@SCM_LIB.SCM(SCH_1):PAGE48_I50@PURE_QUANTA.Q_RES(CHIPS)':
 'A': CDS_PINID='A';
NODE_NAME     R508 2
 '@SCM_LIB.SCM(SCH_1):PAGE48_I51@PURE_QUANTA.Q_RES(CHIPS)':
 'B': CDS_PINID='B';
NODE_NAME     R507 1
 '@SCM_LIB.SCM(SCH_1):PAGE48_I52@PURE_QUANTA.Q_RES(CHIPS)':
 'A': CDS_PINID='A';
NET_NAME
'M_BMC_DDR4_ALERT_N'
 '@SCM_LIB.SCM(SCH_1):M_BMC_DDR4_ALERT_N':
 C_SIGNAL='@scm_lib.scm(sch_1):m_bmc_ddr4_alert_n';
NODE_NAME     U5 N4
 '@SCM_LIB.SCM(SCH_1):PAGE12_I436@PURE_QUANTA.AST2600A3GP(CHIPS)':
 'MALERT#': CDS_PINID='\malert#\';
NODE_NAME     R9 1
 '@SCM_LIB.SCM(SCH_1):PAGE20_I111@PURE_QUANTA.Q_RES(CHIPS)':
 'A': CDS_PINID='A';
NODE_NAME     U1 P9
 '@SCM_LIB.SCM(SCH_1):PAGE20_I196@PURE_QUANTA.K4A8G165WCBCTD(CHIPS)':
 'ALERT_N': CDS_PINID='ALERT_N';
NET_NAME
'M_BMC_DDR4_BG1'
 '@SCM_LIB.SCM(SCH_1):M_BMC_DDR4_BG1':
 C_SIGNAL='@scm_lib.scm(sch_1):m_bmc_ddr4_bg1';
NODE_NAME     R2 1
 '@SCM_LIB.SCM(SCH_1):PAGE20_I13@PURE_QUANTA.Q_RES(CHIPS)':
 'A': CDS_PINID='A';
NODE_NAME     R1 1
 '@SCM_LIB.SCM(SCH_1):PAGE20_I14@PURE_QUANTA.Q_RES(CHIPS)':
 'A': CDS_PINID='A';
NODE_NAME     U1 M9
 '@SCM_LIB.SCM(SCH_1):PAGE20_I196@PURE_QUANTA.K4A8G165WCBCTD(CHIPS)':
 'VSS6': CDS_PINID='VSS6';
NET_NAME
'M_BMC_DDR4_DQ<0>'
 '@SCM_LIB.SCM(SCH_1):M_BMC_DDR4_DQ'<0>:
 C_SIGNAL='@scm_lib.scm(sch_1):m_bmc_ddr4_dq(0)';
NODE_NAME     U5 T3
 '@SCM_LIB.SCM(SCH_1):PAGE12_I436@PURE_QUANTA.AST2600A3GP(CHIPS)':
 'MDQ0': CDS_PINID='MDQ0';
NODE_NAME     U1 G2
 '@SCM_LIB.SCM(SCH_1):PAGE20_I196@PURE_QUANTA.K4A8G165WCBCTD(CHIPS)':
 'DQL0': CDS_PINID='DQL0';
NET_NAME
'M_BMC_DDR4_DQ<10>'
 '@SCM_LIB.SCM(SCH_1):M_BMC_DDR4_DQ'<10>:
 C_SIGNAL='@scm_lib.scm(sch_1):m_bmc_ddr4_dq(10)';
NODE_NAME     U5 W1
 '@SCM_LIB.SCM(SCH_1):PAGE12_I436@PURE_QUANTA.AST2600A3GP(CHIPS)':
 'MDQ10': CDS_PINID='MDQ10';
NODE_NAME     U1 C3
 '@SCM_LIB.SCM(SCH_1):PAGE20_I196@PURE_QUANTA.K4A8G165WCBCTD(CHIPS)':
 'DQU2': CDS_PINID='DQU2';
NET_NAME
'M_BMC_DDR4_DQ<11>'
 '@SCM_LIB.SCM(SCH_1):M_BMC_DDR4_DQ'<11>:
 C_SIGNAL='@scm_lib.scm(sch_1):m_bmc_ddr4_dq(11)';
NODE_NAME     U5 W3
 '@SCM_LIB.SCM(SCH_1):PAGE12_I436@PURE_QUANTA.AST2600A3GP(CHIPS)':
 'MDQ11': CDS_PINID='MDQ11';
NODE_NAME     U1 C7
 '@SCM_LIB.SCM(SCH_1):PAGE20_I196@PURE_QUANTA.K4A8G165WCBCTD(CHIPS)':
 'DQU3': CDS_PINID='DQU3';
NET_NAME
'M_BMC_DDR4_DQ<12>'
 '@SCM_LIB.SCM(SCH_1):M_BMC_DDR4_DQ'<12>:
 C_SIGNAL='@scm_lib.scm(sch_1):m_bmc_ddr4_dq(12)';
NODE_NAME     U5 W4
 '@SCM_LIB.SCM(SCH_1):PAGE12_I436@PURE_QUANTA.AST2600A3GP(CHIPS)':
 'MDQ12': CDS_PINID='MDQ12';
NODE_NAME     U1 C2
 '@SCM_LIB.SCM(SCH_1):PAGE20_I196@PURE_QUANTA.K4A8G165WCBCTD(CHIPS)':
 'DQU4': CDS_PINID='DQU4';
NET_NAME
'M_BMC_DDR4_DQ<13>'
 '@SCM_LIB.SCM(SCH_1):M_BMC_DDR4_DQ'<13>:
 C_SIGNAL='@scm_lib.scm(sch_1):m_bmc_ddr4_dq(13)';
NODE_NAME     U5 U4
 '@SCM_LIB.SCM(SCH_1):PAGE12_I436@PURE_QUANTA.AST2600A3GP(CHIPS)':
 'MDQ13': CDS_PINID='MDQ13';
NODE_NAME     U1 C8
 '@SCM_LIB.SCM(SCH_1):PAGE20_I196@PURE_QUANTA.K4A8G165WCBCTD(CHIPS)':
 'DQU5': CDS_PINID='DQU5';
NET_NAME
'M_BMC_DDR4_DQ<14>'
 '@SCM_LIB.SCM(SCH_1):M_BMC_DDR4_DQ'<14>:
 C_SIGNAL='@scm_lib.scm(sch_1):m_bmc_ddr4_dq(14)';
NODE_NAME     U5 V4
 '@SCM_LIB.SCM(SCH_1):PAGE12_I436@PURE_QUANTA.AST2600A3GP(CHIPS)':
 'MDQ14': CDS_PINID='MDQ14';
NODE_NAME     U1 D3
 '@SCM_LIB.SCM(SCH_1):PAGE20_I196@PURE_QUANTA.K4A8G165WCBCTD(CHIPS)':
 'DQU6': CDS_PINID='DQU6';
NET_NAME
'M_BMC_DDR4_DQ<15>'
 '@SCM_LIB.SCM(SCH_1):M_BMC_DDR4_DQ'<15>:
 C_SIGNAL='@scm_lib.scm(sch_1):m_bmc_ddr4_dq(15)';
NODE_NAME     U5 U3
 '@SCM_LIB.SCM(SCH_1):PAGE12_I436@PURE_QUANTA.AST2600A3GP(CHIPS)':
 'MDQ15': CDS_PINID='MDQ15';
NODE_NAME     U1 D7
 '@SCM_LIB.SCM(SCH_1):PAGE20_I196@PURE_QUANTA.K4A8G165WCBCTD(CHIPS)':
 'DQU7': CDS_PINID='DQU7';
NET_NAME
'M_BMC_DDR4_DQ<1>'
 '@SCM_LIB.SCM(SCH_1):M_BMC_DDR4_DQ'<1>:
 C_SIGNAL='@scm_lib.scm(sch_1):m_bmc_ddr4_dq(1)';
NODE_NAME     U5 R4
 '@SCM_LIB.SCM(SCH_1):PAGE12_I436@PURE_QUANTA.AST2600A3GP(CHIPS)':
 'MDQ1': CDS_PINID='MDQ1';
NODE_NAME     U1 F7
 '@SCM_LIB.SCM(SCH_1):PAGE20_I196@PURE_QUANTA.K4A8G165WCBCTD(CHIPS)':
 'DQL1': CDS_PINID='DQL1';
NET_NAME
'M_BMC_DDR4_DQ<2>'
 '@SCM_LIB.SCM(SCH_1):M_BMC_DDR4_DQ'<2>:
 C_SIGNAL='@scm_lib.scm(sch_1):m_bmc_ddr4_dq(2)';
NODE_NAME     U5 U1
 '@SCM_LIB.SCM(SCH_1):PAGE12_I436@PURE_QUANTA.AST2600A3GP(CHIPS)':
 'MDQ2': CDS_PINID='MDQ2';
NODE_NAME     U1 H3
 '@SCM_LIB.SCM(SCH_1):PAGE20_I196@PURE_QUANTA.K4A8G165WCBCTD(CHIPS)':
 'DQL2': CDS_PINID='DQL2';
NET_NAME
'M_BMC_DDR4_DQ<3>'
 '@SCM_LIB.SCM(SCH_1):M_BMC_DDR4_DQ'<3>:
 C_SIGNAL='@scm_lib.scm(sch_1):m_bmc_ddr4_dq(3)';
NODE_NAME     U5 R3
 '@SCM_LIB.SCM(SCH_1):PAGE12_I436@PURE_QUANTA.AST2600A3GP(CHIPS)':
 'MDQ3': CDS_PINID='MDQ3';
NODE_NAME     U1 H7
 '@SCM_LIB.SCM(SCH_1):PAGE20_I196@PURE_QUANTA.K4A8G165WCBCTD(CHIPS)':
 'DQL3': CDS_PINID='DQL3';
NET_NAME
'M_BMC_DDR4_DQ<4>'
 '@SCM_LIB.SCM(SCH_1):M_BMC_DDR4_DQ'<4>:
 C_SIGNAL='@scm_lib.scm(sch_1):m_bmc_ddr4_dq(4)';
NODE_NAME     U5 R1
 '@SCM_LIB.SCM(SCH_1):PAGE12_I436@PURE_QUANTA.AST2600A3GP(CHIPS)':
 'MDQ4': CDS_PINID='MDQ4';
NODE_NAME     U1 H2
 '@SCM_LIB.SCM(SCH_1):PAGE20_I196@PURE_QUANTA.K4A8G165WCBCTD(CHIPS)':
 'DQL4': CDS_PINID='DQL4';
NET_NAME
'M_BMC_DDR4_DQ<5>'
 '@SCM_LIB.SCM(SCH_1):M_BMC_DDR4_DQ'<5>:
 C_SIGNAL='@scm_lib.scm(sch_1):m_bmc_ddr4_dq(5)';
NODE_NAME     U5 P1
 '@SCM_LIB.SCM(SCH_1):PAGE12_I436@PURE_QUANTA.AST2600A3GP(CHIPS)':
 'MDQ5': CDS_PINID='MDQ5';
NODE_NAME     U1 H8
 '@SCM_LIB.SCM(SCH_1):PAGE20_I196@PURE_QUANTA.K4A8G165WCBCTD(CHIPS)':
 'DQL5': CDS_PINID='DQL5';
NET_NAME
'M_BMC_DDR4_DQ<6>'
 '@SCM_LIB.SCM(SCH_1):M_BMC_DDR4_DQ'<6>:
 C_SIGNAL='@scm_lib.scm(sch_1):m_bmc_ddr4_dq(6)';
NODE_NAME     U5 P2
 '@SCM_LIB.SCM(SCH_1):PAGE12_I436@PURE_QUANTA.AST2600A3GP(CHIPS)':
 'MDQ6': CDS_PINID='MDQ6';
NODE_NAME     U1 J3
 '@SCM_LIB.SCM(SCH_1):PAGE20_I196@PURE_QUANTA.K4A8G165WCBCTD(CHIPS)':
 'DQL6': CDS_PINID='DQL6';
NET_NAME
'M_BMC_DDR4_DQ<7>'
 '@SCM_LIB.SCM(SCH_1):M_BMC_DDR4_DQ'<7>:
 C_SIGNAL='@scm_lib.scm(sch_1):m_bmc_ddr4_dq(7)';
NODE_NAME     U5 P3
 '@SCM_LIB.SCM(SCH_1):PAGE12_I436@PURE_QUANTA.AST2600A3GP(CHIPS)':
 'MDQ7': CDS_PINID='MDQ7';
NODE_NAME     U1 J7
 '@SCM_LIB.SCM(SCH_1):PAGE20_I196@PURE_QUANTA.K4A8G165WCBCTD(CHIPS)':
 'DQL7': CDS_PINID='DQL7';
NET_NAME
'M_BMC_DDR4_DQ<8>'
 '@SCM_LIB.SCM(SCH_1):M_BMC_DDR4_DQ'<8>:
 C_SIGNAL='@scm_lib.scm(sch_1):m_bmc_ddr4_dq(8)';
NODE_NAME     U5 W2
 '@SCM_LIB.SCM(SCH_1):PAGE12_I436@PURE_QUANTA.AST2600A3GP(CHIPS)':
 'MDQ8': CDS_PINID='MDQ8';
NODE_NAME     U1 A3
 '@SCM_LIB.SCM(SCH_1):PAGE20_I196@PURE_QUANTA.K4A8G165WCBCTD(CHIPS)':
 'DQU0': CDS_PINID='DQU0';
NET_NAME
'M_BMC_DDR4_DQ<9>'
 '@SCM_LIB.SCM(SCH_1):M_BMC_DDR4_DQ'<9>:
 C_SIGNAL='@scm_lib.scm(sch_1):m_bmc_ddr4_dq(9)';
NODE_NAME     U5 V3
 '@SCM_LIB.SCM(SCH_1):PAGE12_I436@PURE_QUANTA.AST2600A3GP(CHIPS)':
 'MDQ9': CDS_PINID='MDQ9';
NODE_NAME     U1 B8
 '@SCM_LIB.SCM(SCH_1):PAGE20_I196@PURE_QUANTA.K4A8G165WCBCTD(CHIPS)':
 'DQU1': CDS_PINID='DQU1';
NET_NAME
'M_BMC_DDR4_DQS0_N'
 '@SCM_LIB.SCM(SCH_1):M_BMC_DDR4_DQS0_N':
 C_SIGNAL='@scm_lib.scm(sch_1):m_bmc_ddr4_dqs0_n';
NODE_NAME     U5 T1
 '@SCM_LIB.SCM(SCH_1):PAGE12_I436@PURE_QUANTA.AST2600A3GP(CHIPS)':
 'MDQS0#': CDS_PINID='\mdqs0#\';
NODE_NAME     U1 F3
 '@SCM_LIB.SCM(SCH_1):PAGE20_I196@PURE_QUANTA.K4A8G165WCBCTD(CHIPS)':
 'DQSL_C': CDS_PINID='DQSL_C';
NET_NAME
'M_BMC_DDR4_DQS0_P'
 '@SCM_LIB.SCM(SCH_1):M_BMC_DDR4_DQS0_P':
 C_SIGNAL='@scm_lib.scm(sch_1):m_bmc_ddr4_dqs0_p';
NODE_NAME     U5 T2
 '@SCM_LIB.SCM(SCH_1):PAGE12_I436@PURE_QUANTA.AST2600A3GP(CHIPS)':
 'MDQS0': CDS_PINID='MDQS0';
NODE_NAME     U1 G3
 '@SCM_LIB.SCM(SCH_1):PAGE20_I196@PURE_QUANTA.K4A8G165WCBCTD(CHIPS)':
 'DQSL_T': CDS_PINID='DQSL_T';
NET_NAME
'M_BMC_DDR4_DQS1_N'
 '@SCM_LIB.SCM(SCH_1):M_BMC_DDR4_DQS1_N':
 C_SIGNAL='@scm_lib.scm(sch_1):m_bmc_ddr4_dqs1_n';
NODE_NAME     U5 V1
 '@SCM_LIB.SCM(SCH_1):PAGE12_I436@PURE_QUANTA.AST2600A3GP(CHIPS)':
 'MDQS1#': CDS_PINID='\mdqs1#\';
NODE_NAME     U1 A7
 '@SCM_LIB.SCM(SCH_1):PAGE20_I196@PURE_QUANTA.K4A8G165WCBCTD(CHIPS)':
 'DQSU_C': CDS_PINID='DQSU_C';
NET_NAME
'M_BMC_DDR4_DQS1_P'
 '@SCM_LIB.SCM(SCH_1):M_BMC_DDR4_DQS1_P':
 C_SIGNAL='@scm_lib.scm(sch_1):m_bmc_ddr4_dqs1_p';
NODE_NAME     U5 V2
 '@SCM_LIB.SCM(SCH_1):PAGE12_I436@PURE_QUANTA.AST2600A3GP(CHIPS)':
 'MDQS1': CDS_PINID='MDQS1';
NODE_NAME     U1 B7
 '@SCM_LIB.SCM(SCH_1):PAGE20_I196@PURE_QUANTA.K4A8G165WCBCTD(CHIPS)':
 'DQSU_T': CDS_PINID='DQSU_T';
NET_NAME
'M_BMC_DDR4_MA<0>'
 '@SCM_LIB.SCM(SCH_1):M_BMC_DDR4_MA'<0>:
 C_SIGNAL='@scm_lib.scm(sch_1):m_bmc_ddr4_ma(0)';
NODE_NAME     U5 F3
 '@SCM_LIB.SCM(SCH_1):PAGE12_I436@PURE_QUANTA.AST2600A3GP(CHIPS)':
 'MA0': CDS_PINID='MA0';
NODE_NAME     R326 2
 '@SCM_LIB.SCM(SCH_1):PAGE20_I193@PURE_QUANTA.Q_RES(CHIPS)':
 'B': CDS_PINID='B';
NODE_NAME     R351 1
 '@SCM_LIB.SCM(SCH_1):PAGE20_I194@PURE_QUANTA.Q_RES(CHIPS)':
 'A': CDS_PINID='A';
NODE_NAME     U1 P3
 '@SCM_LIB.SCM(SCH_1):PAGE20_I196@PURE_QUANTA.K4A8G165WCBCTD(CHIPS)':
 'A0': CDS_PINID='A0';
NET_NAME
'M_BMC_DDR4_MA<10>'
 '@SCM_LIB.SCM(SCH_1):M_BMC_DDR4_MA'<10>:
 C_SIGNAL='@scm_lib.scm(sch_1):m_bmc_ddr4_ma(10)';
NODE_NAME     U5 F2
 '@SCM_LIB.SCM(SCH_1):PAGE12_I436@PURE_QUANTA.AST2600A3GP(CHIPS)':
 'MA10': CDS_PINID='MA10';
NODE_NAME     R336 2
 '@SCM_LIB.SCM(SCH_1):PAGE20_I162@PURE_QUANTA.Q_RES(CHIPS)':
 'B': CDS_PINID='B';
NODE_NAME     R361 1
 '@SCM_LIB.SCM(SCH_1):PAGE20_I167@PURE_QUANTA.Q_RES(CHIPS)':
 'A': CDS_PINID='A';
NODE_NAME     U1 M3
 '@SCM_LIB.SCM(SCH_1):PAGE20_I196@PURE_QUANTA.K4A8G165WCBCTD(CHIPS)':
 'A10||AP': CDS_PINID='\a10||ap\';
NET_NAME
'M_BMC_DDR4_MA<11>'
 '@SCM_LIB.SCM(SCH_1):M_BMC_DDR4_MA'<11>:
 C_SIGNAL='@scm_lib.scm(sch_1):m_bmc_ddr4_ma(11)';
NODE_NAME     U5 G1
 '@SCM_LIB.SCM(SCH_1):PAGE12_I436@PURE_QUANTA.AST2600A3GP(CHIPS)':
 'MA11': CDS_PINID='MA11';
NODE_NAME     R337 2
 '@SCM_LIB.SCM(SCH_1):PAGE20_I161@PURE_QUANTA.Q_RES(CHIPS)':
 'B': CDS_PINID='B';
NODE_NAME     R362 1
 '@SCM_LIB.SCM(SCH_1):PAGE20_I168@PURE_QUANTA.Q_RES(CHIPS)':
 'A': CDS_PINID='A';
NODE_NAME     U1 T2
 '@SCM_LIB.SCM(SCH_1):PAGE20_I196@PURE_QUANTA.K4A8G165WCBCTD(CHIPS)':
 'A11': CDS_PINID='A11';
NET_NAME
'M_BMC_DDR4_MA<12>'
 '@SCM_LIB.SCM(SCH_1):M_BMC_DDR4_MA'<12>:
 C_SIGNAL='@scm_lib.scm(sch_1):m_bmc_ddr4_ma(12)';
NODE_NAME     U5 L4
 '@SCM_LIB.SCM(SCH_1):PAGE12_I436@PURE_QUANTA.AST2600A3GP(CHIPS)':
 'MA12': CDS_PINID='MA12';
NODE_NAME     R338 2
 '@SCM_LIB.SCM(SCH_1):PAGE20_I160@PURE_QUANTA.Q_RES(CHIPS)':
 'B': CDS_PINID='B';
NODE_NAME     R363 1
 '@SCM_LIB.SCM(SCH_1):PAGE20_I166@PURE_QUANTA.Q_RES(CHIPS)':
 'A': CDS_PINID='A';
NODE_NAME     U1 M7
 '@SCM_LIB.SCM(SCH_1):PAGE20_I196@PURE_QUANTA.K4A8G165WCBCTD(CHIPS)':
 'A12||BC_N': CDS_PINID='\a12||bc_n\';
NET_NAME
'M_BMC_DDR4_MA<13>'
 '@SCM_LIB.SCM(SCH_1):M_BMC_DDR4_MA'<13>:
 C_SIGNAL='@scm_lib.scm(sch_1):m_bmc_ddr4_ma(13)';
NODE_NAME     U5 K3
 '@SCM_LIB.SCM(SCH_1):PAGE12_I436@PURE_QUANTA.AST2600A3GP(CHIPS)':
 'MA13': CDS_PINID='MA13';
NODE_NAME     R339 2
 '@SCM_LIB.SCM(SCH_1):PAGE20_I159@PURE_QUANTA.Q_RES(CHIPS)':
 'B': CDS_PINID='B';
NODE_NAME     R364 1
 '@SCM_LIB.SCM(SCH_1):PAGE20_I165@PURE_QUANTA.Q_RES(CHIPS)':
 'A': CDS_PINID='A';
NODE_NAME     U1 T8
 '@SCM_LIB.SCM(SCH_1):PAGE20_I196@PURE_QUANTA.K4A8G165WCBCTD(CHIPS)':
 'A13': CDS_PINID='A13';
NET_NAME
'M_BMC_DDR4_MA<1>'
 '@SCM_LIB.SCM(SCH_1):M_BMC_DDR4_MA'<1>:
 C_SIGNAL='@scm_lib.scm(sch_1):m_bmc_ddr4_ma(1)';
NODE_NAME     U5 K5
 '@SCM_LIB.SCM(SCH_1):PAGE12_I436@PURE_QUANTA.AST2600A3GP(CHIPS)':
 'MA1': CDS_PINID='MA1';
NODE_NAME     R327 2
 '@SCM_LIB.SCM(SCH_1):PAGE20_I177@PURE_QUANTA.Q_RES(CHIPS)':
 'B': CDS_PINID='B';
NODE_NAME     R352 1
 '@SCM_LIB.SCM(SCH_1):PAGE20_I184@PURE_QUANTA.Q_RES(CHIPS)':
 'A': CDS_PINID='A';
NODE_NAME     U1 P7
 '@SCM_LIB.SCM(SCH_1):PAGE20_I196@PURE_QUANTA.K4A8G165WCBCTD(CHIPS)':
 'A1': CDS_PINID='A1';
NET_NAME
'M_BMC_DDR4_MA<2>'
 '@SCM_LIB.SCM(SCH_1):M_BMC_DDR4_MA'<2>:
 C_SIGNAL='@scm_lib.scm(sch_1):m_bmc_ddr4_ma(2)';
NODE_NAME     U5 F1
 '@SCM_LIB.SCM(SCH_1):PAGE12_I436@PURE_QUANTA.AST2600A3GP(CHIPS)':
 'MA2': CDS_PINID='MA2';
NODE_NAME     R328 2
 '@SCM_LIB.SCM(SCH_1):PAGE20_I176@PURE_QUANTA.Q_RES(CHIPS)':
 'B': CDS_PINID='B';
NODE_NAME     R353 1
 '@SCM_LIB.SCM(SCH_1):PAGE20_I183@PURE_QUANTA.Q_RES(CHIPS)':
 'A': CDS_PINID='A';
NODE_NAME     U1 R3
 '@SCM_LIB.SCM(SCH_1):PAGE20_I196@PURE_QUANTA.K4A8G165WCBCTD(CHIPS)':
 'A2': CDS_PINID='A2';
NET_NAME
'M_BMC_DDR4_MA<3>'
 '@SCM_LIB.SCM(SCH_1):M_BMC_DDR4_MA'<3>:
 C_SIGNAL='@scm_lib.scm(sch_1):m_bmc_ddr4_ma(3)';
NODE_NAME     U5 H3
 '@SCM_LIB.SCM(SCH_1):PAGE12_I436@PURE_QUANTA.AST2600A3GP(CHIPS)':
 'MA3': CDS_PINID='MA3';
NODE_NAME     R329 2
 '@SCM_LIB.SCM(SCH_1):PAGE20_I175@PURE_QUANTA.Q_RES(CHIPS)':
 'B': CDS_PINID='B';
NODE_NAME     R354 1
 '@SCM_LIB.SCM(SCH_1):PAGE20_I181@PURE_QUANTA.Q_RES(CHIPS)':
 'A': CDS_PINID='A';
NODE_NAME     U1 N7
 '@SCM_LIB.SCM(SCH_1):PAGE20_I196@PURE_QUANTA.K4A8G165WCBCTD(CHIPS)':
 'A3': CDS_PINID='A3';
NET_NAME
'M_BMC_DDR4_MA<4>'
 '@SCM_LIB.SCM(SCH_1):M_BMC_DDR4_MA'<4>:
 C_SIGNAL='@scm_lib.scm(sch_1):m_bmc_ddr4_ma(4)';
NODE_NAME     U5 J3
 '@SCM_LIB.SCM(SCH_1):PAGE12_I436@PURE_QUANTA.AST2600A3GP(CHIPS)':
 'MA4': CDS_PINID='MA4';
NODE_NAME     R330 2
 '@SCM_LIB.SCM(SCH_1):PAGE20_I174@PURE_QUANTA.Q_RES(CHIPS)':
 'B': CDS_PINID='B';
NODE_NAME     R355 1
 '@SCM_LIB.SCM(SCH_1):PAGE20_I182@PURE_QUANTA.Q_RES(CHIPS)':
 'A': CDS_PINID='A';
NODE_NAME     U1 N3
 '@SCM_LIB.SCM(SCH_1):PAGE20_I196@PURE_QUANTA.K4A8G165WCBCTD(CHIPS)':
 'A4': CDS_PINID='A4';
NET_NAME
'M_BMC_DDR4_MA<5>'
 '@SCM_LIB.SCM(SCH_1):M_BMC_DDR4_MA'<5>:
 C_SIGNAL='@scm_lib.scm(sch_1):m_bmc_ddr4_ma(5)';
NODE_NAME     U5 L1
 '@SCM_LIB.SCM(SCH_1):PAGE12_I436@PURE_QUANTA.AST2600A3GP(CHIPS)':
 'MA5': CDS_PINID='MA5';
NODE_NAME     R331 2
 '@SCM_LIB.SCM(SCH_1):PAGE20_I173@PURE_QUANTA.Q_RES(CHIPS)':
 'B': CDS_PINID='B';
NODE_NAME     R356 1
 '@SCM_LIB.SCM(SCH_1):PAGE20_I180@PURE_QUANTA.Q_RES(CHIPS)':
 'A': CDS_PINID='A';
NODE_NAME     U1 P8
 '@SCM_LIB.SCM(SCH_1):PAGE20_I196@PURE_QUANTA.K4A8G165WCBCTD(CHIPS)':
 'A5': CDS_PINID='A5';
NET_NAME
'M_BMC_DDR4_MA<6>'
 '@SCM_LIB.SCM(SCH_1):M_BMC_DDR4_MA'<6>:
 C_SIGNAL='@scm_lib.scm(sch_1):m_bmc_ddr4_ma(6)';
NODE_NAME     U5 M5
 '@SCM_LIB.SCM(SCH_1):PAGE12_I436@PURE_QUANTA.AST2600A3GP(CHIPS)':
 'MA6': CDS_PINID='MA6';
NODE_NAME     R332 2
 '@SCM_LIB.SCM(SCH_1):PAGE20_I171@PURE_QUANTA.Q_RES(CHIPS)':
 'B': CDS_PINID='B';
NODE_NAME     R357 1
 '@SCM_LIB.SCM(SCH_1):PAGE20_I179@PURE_QUANTA.Q_RES(CHIPS)':
 'A': CDS_PINID='A';
NODE_NAME     U1 P2
 '@SCM_LIB.SCM(SCH_1):PAGE20_I196@PURE_QUANTA.K4A8G165WCBCTD(CHIPS)':
 'A6': CDS_PINID='A6';
NET_NAME
'M_BMC_DDR4_MA<7>'
 '@SCM_LIB.SCM(SCH_1):M_BMC_DDR4_MA'<7>:
 C_SIGNAL='@scm_lib.scm(sch_1):m_bmc_ddr4_ma(7)';
NODE_NAME     U5 M2
 '@SCM_LIB.SCM(SCH_1):PAGE12_I436@PURE_QUANTA.AST2600A3GP(CHIPS)':
 'MA7': CDS_PINID='MA7';
NODE_NAME     R333 2
 '@SCM_LIB.SCM(SCH_1):PAGE20_I172@PURE_QUANTA.Q_RES(CHIPS)':
 'B': CDS_PINID='B';
NODE_NAME     R358 1
 '@SCM_LIB.SCM(SCH_1):PAGE20_I178@PURE_QUANTA.Q_RES(CHIPS)':
 'A': CDS_PINID='A';
NODE_NAME     U1 R8
 '@SCM_LIB.SCM(SCH_1):PAGE20_I196@PURE_QUANTA.K4A8G165WCBCTD(CHIPS)':
 'A7': CDS_PINID='A7';
NET_NAME
'M_BMC_DDR4_MA<8>'
 '@SCM_LIB.SCM(SCH_1):M_BMC_DDR4_MA'<8>:
 C_SIGNAL='@scm_lib.scm(sch_1):m_bmc_ddr4_ma(8)';
NODE_NAME     U5 M1
 '@SCM_LIB.SCM(SCH_1):PAGE12_I436@PURE_QUANTA.AST2600A3GP(CHIPS)':
 'MA8': CDS_PINID='MA8';
NODE_NAME     R334 2
 '@SCM_LIB.SCM(SCH_1):PAGE20_I164@PURE_QUANTA.Q_RES(CHIPS)':
 'B': CDS_PINID='B';
NODE_NAME     R359 1
 '@SCM_LIB.SCM(SCH_1):PAGE20_I170@PURE_QUANTA.Q_RES(CHIPS)':
 'A': CDS_PINID='A';
NODE_NAME     U1 R2
 '@SCM_LIB.SCM(SCH_1):PAGE20_I196@PURE_QUANTA.K4A8G165WCBCTD(CHIPS)':
 'A8': CDS_PINID='A8';
NET_NAME
'M_BMC_DDR4_MA<9>'
 '@SCM_LIB.SCM(SCH_1):M_BMC_DDR4_MA'<9>:
 C_SIGNAL='@scm_lib.scm(sch_1):m_bmc_ddr4_ma(9)';
NODE_NAME     U5 N1
 '@SCM_LIB.SCM(SCH_1):PAGE12_I436@PURE_QUANTA.AST2600A3GP(CHIPS)':
 'MA9': CDS_PINID='MA9';
NODE_NAME     R335 2
 '@SCM_LIB.SCM(SCH_1):PAGE20_I163@PURE_QUANTA.Q_RES(CHIPS)':
 'B': CDS_PINID='B';
NODE_NAME     R360 1
 '@SCM_LIB.SCM(SCH_1):PAGE20_I169@PURE_QUANTA.Q_RES(CHIPS)':
 'A': CDS_PINID='A';
NODE_NAME     U1 R7
 '@SCM_LIB.SCM(SCH_1):PAGE20_I196@PURE_QUANTA.K4A8G165WCBCTD(CHIPS)':
 'A9': CDS_PINID='A9';
NET_NAME
'M_BMC_DDR4_MACT_N'
 '@SCM_LIB.SCM(SCH_1):M_BMC_DDR4_MACT_N':
 C_SIGNAL='@scm_lib.scm(sch_1):m_bmc_ddr4_mact_n';
NODE_NAME     U5 H1
 '@SCM_LIB.SCM(SCH_1):PAGE12_I436@PURE_QUANTA.AST2600A3GP(CHIPS)':
 'MA14||MACT#': CDS_PINID='\ma14||mact#\';
NODE_NAME     R344 2
 '@SCM_LIB.SCM(SCH_1):PAGE20_I121@PURE_QUANTA.Q_RES(CHIPS)':
 'B': CDS_PINID='B';
NODE_NAME     R369 1
 '@SCM_LIB.SCM(SCH_1):PAGE20_I132@PURE_QUANTA.Q_RES(CHIPS)':
 'A': CDS_PINID='A';
NODE_NAME     U1 L3
 '@SCM_LIB.SCM(SCH_1):PAGE20_I196@PURE_QUANTA.K4A8G165WCBCTD(CHIPS)':
 'ACT_N': CDS_PINID='ACT_N';
NET_NAME
'M_BMC_DDR4_MBA0'
 '@SCM_LIB.SCM(SCH_1):M_BMC_DDR4_MBA0':
 C_SIGNAL='@scm_lib.scm(sch_1):m_bmc_ddr4_mba0';
NODE_NAME     U5 G4
 '@SCM_LIB.SCM(SCH_1):PAGE12_I436@PURE_QUANTA.AST2600A3GP(CHIPS)':
 'MBA0': CDS_PINID='MBA0';
NODE_NAME     R346 2
 '@SCM_LIB.SCM(SCH_1):PAGE20_I120@PURE_QUANTA.Q_RES(CHIPS)':
 'B': CDS_PINID='B';
NODE_NAME     R371 1
 '@SCM_LIB.SCM(SCH_1):PAGE20_I130@PURE_QUANTA.Q_RES(CHIPS)':
 'A': CDS_PINID='A';
NODE_NAME     U1 N2
 '@SCM_LIB.SCM(SCH_1):PAGE20_I196@PURE_QUANTA.K4A8G165WCBCTD(CHIPS)':
 'BA0': CDS_PINID='BA0';
NET_NAME
'M_BMC_DDR4_MBA1'
 '@SCM_LIB.SCM(SCH_1):M_BMC_DDR4_MBA1':
 C_SIGNAL='@scm_lib.scm(sch_1):m_bmc_ddr4_mba1';
NODE_NAME     U5 H5
 '@SCM_LIB.SCM(SCH_1):PAGE12_I436@PURE_QUANTA.AST2600A3GP(CHIPS)':
 'MBA1': CDS_PINID='MBA1';
NODE_NAME     R347 2
 '@SCM_LIB.SCM(SCH_1):PAGE20_I117@PURE_QUANTA.Q_RES(CHIPS)':
 'B': CDS_PINID='B';
NODE_NAME     R372 1
 '@SCM_LIB.SCM(SCH_1):PAGE20_I129@PURE_QUANTA.Q_RES(CHIPS)':
 'A': CDS_PINID='A';
NODE_NAME     U1 N8
 '@SCM_LIB.SCM(SCH_1):PAGE20_I196@PURE_QUANTA.K4A8G165WCBCTD(CHIPS)':
 'BA1': CDS_PINID='BA1';
NET_NAME
'M_BMC_DDR4_MBG0'
 '@SCM_LIB.SCM(SCH_1):M_BMC_DDR4_MBG0':
 C_SIGNAL='@scm_lib.scm(sch_1):m_bmc_ddr4_mbg0';
NODE_NAME     U5 G3
 '@SCM_LIB.SCM(SCH_1):PAGE12_I436@PURE_QUANTA.AST2600A3GP(CHIPS)':
 'MBA2||MBG0': CDS_PINID='\mba2||mbg0\';
NODE_NAME     R345 2
 '@SCM_LIB.SCM(SCH_1):PAGE20_I119@PURE_QUANTA.Q_RES(CHIPS)':
 'B': CDS_PINID='B';
NODE_NAME     R370 1
 '@SCM_LIB.SCM(SCH_1):PAGE20_I131@PURE_QUANTA.Q_RES(CHIPS)':
 'A': CDS_PINID='A';
NODE_NAME     U1 M2
 '@SCM_LIB.SCM(SCH_1):PAGE20_I196@PURE_QUANTA.K4A8G165WCBCTD(CHIPS)':
 'BG0': CDS_PINID='BG0';
NET_NAME
'M_BMC_DDR4_MBG1'
 '@SCM_LIB.SCM(SCH_1):M_BMC_DDR4_MBG1':
 C_SIGNAL='@scm_lib.scm(sch_1):m_bmc_ddr4_mbg1';
NODE_NAME     U5 M3
 '@SCM_LIB.SCM(SCH_1):PAGE12_I436@PURE_QUANTA.AST2600A3GP(CHIPS)':
 'MA15||MBG1': CDS_PINID='\ma15||mbg1\';
NODE_NAME     R1 2
 '@SCM_LIB.SCM(SCH_1):PAGE20_I14@PURE_QUANTA.Q_RES(CHIPS)':
 'B': CDS_PINID='B';
NODE_NAME     R350 2
 '@SCM_LIB.SCM(SCH_1):PAGE20_I114@PURE_QUANTA.Q_RES(CHIPS)':
 'B': CDS_PINID='B';
NODE_NAME     R375 1
 '@SCM_LIB.SCM(SCH_1):PAGE20_I115@PURE_QUANTA.Q_RES(CHIPS)':
 'A': CDS_PINID='A';
NET_NAME
'M_BMC_DDR4_MCAS_N'
 '@SCM_LIB.SCM(SCH_1):M_BMC_DDR4_MCAS_N':
 C_SIGNAL='@scm_lib.scm(sch_1):m_bmc_ddr4_mcas_n';
NODE_NAME     U5 J4
 '@SCM_LIB.SCM(SCH_1):PAGE12_I436@PURE_QUANTA.AST2600A3GP(CHIPS)':
 'MCAS#': CDS_PINID='\mcas#\';
NODE_NAME     R341 2
 '@SCM_LIB.SCM(SCH_1):PAGE20_I125@PURE_QUANTA.Q_RES(CHIPS)':
 'B': CDS_PINID='B';
NODE_NAME     R366 1
 '@SCM_LIB.SCM(SCH_1):PAGE20_I137@PURE_QUANTA.Q_RES(CHIPS)':
 'A': CDS_PINID='A';
NODE_NAME     U1 M8
 '@SCM_LIB.SCM(SCH_1):PAGE20_I196@PURE_QUANTA.K4A8G165WCBCTD(CHIPS)':
 'CAS_N||A15': CDS_PINID='\cas_n||a15\';
NET_NAME
'M_BMC_DDR4_MCKE'
 '@SCM_LIB.SCM(SCH_1):M_BMC_DDR4_MCKE':
 C_SIGNAL='@scm_lib.scm(sch_1):m_bmc_ddr4_mcke';
NODE_NAME     U5 L5
 '@SCM_LIB.SCM(SCH_1):PAGE12_I436@PURE_QUANTA.AST2600A3GP(CHIPS)':
 'MCKE': CDS_PINID='MCKE';
NODE_NAME     R349 2
 '@SCM_LIB.SCM(SCH_1):PAGE20_I116@PURE_QUANTA.Q_RES(CHIPS)':
 'B': CDS_PINID='B';
NODE_NAME     R374 1
 '@SCM_LIB.SCM(SCH_1):PAGE20_I127@PURE_QUANTA.Q_RES(CHIPS)':
 'A': CDS_PINID='A';
NODE_NAME     U1 K2
 '@SCM_LIB.SCM(SCH_1):PAGE20_I196@PURE_QUANTA.K4A8G165WCBCTD(CHIPS)':
 'CKE': CDS_PINID='CKE';
NET_NAME
'M_BMC_DDR4_MCLK_C'
 '@SCM_LIB.SCM(SCH_1):M_BMC_DDR4_MCLK_C':
 C_SIGNAL='@scm_lib.scm(sch_1):m_bmc_ddr4_mclk_c';
NODE_NAME     R8 2
 '@SCM_LIB.SCM(SCH_1):PAGE20_I89@PURE_QUANTA.Q_RES(CHIPS)':
 'B': CDS_PINID='B';
NODE_NAME     R7 2
 '@SCM_LIB.SCM(SCH_1):PAGE20_I90@PURE_QUANTA.Q_RES(CHIPS)':
 'B': CDS_PINID='B';
NODE_NAME     C12 1
 '@SCM_LIB.SCM(SCH_1):PAGE20_I106@PURE_QUANTA.Q_CAP(CHIPS)':
 'A': CDS_PINID='A';
NODE_NAME     C229 1
 '@SCM_LIB.SCM(SCH_1):PAGE20_I107@PURE_QUANTA.Q_CAP(CHIPS)':
 'A': CDS_PINID='A';
NET_NAME
'M_BMC_DDR4_MCLK_DN'
 '@SCM_LIB.SCM(SCH_1):M_BMC_DDR4_MCLK_DN':
 C_SIGNAL='@scm_lib.scm(sch_1):m_bmc_ddr4_mclk_dn';
NODE_NAME     U5 K1
 '@SCM_LIB.SCM(SCH_1):PAGE12_I436@PURE_QUANTA.AST2600A3GP(CHIPS)':
 'MCK#': CDS_PINID='\mck#\';
NODE_NAME     R7 1
 '@SCM_LIB.SCM(SCH_1):PAGE20_I90@PURE_QUANTA.Q_RES(CHIPS)':
 'A': CDS_PINID='A';
NODE_NAME     U1 K8
 '@SCM_LIB.SCM(SCH_1):PAGE20_I196@PURE_QUANTA.K4A8G165WCBCTD(CHIPS)':
 'CK_C': CDS_PINID='CK_C';
NET_NAME
'M_BMC_DDR4_MCLK_DP'
 '@SCM_LIB.SCM(SCH_1):M_BMC_DDR4_MCLK_DP':
 C_SIGNAL='@scm_lib.scm(sch_1):m_bmc_ddr4_mclk_dp';
NODE_NAME     U5 K2
 '@SCM_LIB.SCM(SCH_1):PAGE12_I436@PURE_QUANTA.AST2600A3GP(CHIPS)':
 'MCK': CDS_PINID='MCK';
NODE_NAME     R8 1
 '@SCM_LIB.SCM(SCH_1):PAGE20_I89@PURE_QUANTA.Q_RES(CHIPS)':
 'A': CDS_PINID='A';
NODE_NAME     U1 K7
 '@SCM_LIB.SCM(SCH_1):PAGE20_I196@PURE_QUANTA.K4A8G165WCBCTD(CHIPS)':
 'CK_T': CDS_PINID='CK_T';
NET_NAME
'M_BMC_DDR4_MCS_N'
 '@SCM_LIB.SCM(SCH_1):M_BMC_DDR4_MCS_N':
 C_SIGNAL='@scm_lib.scm(sch_1):m_bmc_ddr4_mcs_n';
NODE_NAME     U5 H2
 '@SCM_LIB.SCM(SCH_1):PAGE12_I436@PURE_QUANTA.AST2600A3GP(CHIPS)':
 'MCS#': CDS_PINID='\mcs#\';
NODE_NAME     R343 2
 '@SCM_LIB.SCM(SCH_1):PAGE20_I123@PURE_QUANTA.Q_RES(CHIPS)':
 'B': CDS_PINID='B';
NODE_NAME     R368 1
 '@SCM_LIB.SCM(SCH_1):PAGE20_I135@PURE_QUANTA.Q_RES(CHIPS)':
 'A': CDS_PINID='A';
NODE_NAME     U1 L7
 '@SCM_LIB.SCM(SCH_1):PAGE20_I196@PURE_QUANTA.K4A8G165WCBCTD(CHIPS)':
 'CS_N': CDS_PINID='CS_N';
NET_NAME
'M_BMC_DDR4_MDM0'
 '@SCM_LIB.SCM(SCH_1):M_BMC_DDR4_MDM0':
 C_SIGNAL='@scm_lib.scm(sch_1):m_bmc_ddr4_mdm0';
NODE_NAME     U5 N3
 '@SCM_LIB.SCM(SCH_1):PAGE12_I436@PURE_QUANTA.AST2600A3GP(CHIPS)':
 'MDM0': CDS_PINID='MDM0';
NODE_NAME     U1 E7
 '@SCM_LIB.SCM(SCH_1):PAGE20_I196@PURE_QUANTA.K4A8G165WCBCTD(CHIPS)':
 'DML_N||DBIL_N': CDS_PINID='\dml_n||dbil_n\';
NET_NAME
'M_BMC_DDR4_MDM1'
 '@SCM_LIB.SCM(SCH_1):M_BMC_DDR4_MDM1':
 C_SIGNAL='@scm_lib.scm(sch_1):m_bmc_ddr4_mdm1';
NODE_NAME     U5 R5
 '@SCM_LIB.SCM(SCH_1):PAGE12_I436@PURE_QUANTA.AST2600A3GP(CHIPS)':
 'MDM1': CDS_PINID='MDM1';
NODE_NAME     U1 E2
 '@SCM_LIB.SCM(SCH_1):PAGE20_I196@PURE_QUANTA.K4A8G165WCBCTD(CHIPS)':
 'DMU_N||DBIU_N': CDS_PINID='\dmu_n||dbiu_n\';
NET_NAME
'M_BMC_DDR4_MODT'
 '@SCM_LIB.SCM(SCH_1):M_BMC_DDR4_MODT':
 C_SIGNAL='@scm_lib.scm(sch_1):m_bmc_ddr4_modt';
NODE_NAME     U5 J1
 '@SCM_LIB.SCM(SCH_1):PAGE12_I436@PURE_QUANTA.AST2600A3GP(CHIPS)':
 'MODT': CDS_PINID='MODT';
NODE_NAME     R348 2
 '@SCM_LIB.SCM(SCH_1):PAGE20_I118@PURE_QUANTA.Q_RES(CHIPS)':
 'B': CDS_PINID='B';
NODE_NAME     R373 1
 '@SCM_LIB.SCM(SCH_1):PAGE20_I128@PURE_QUANTA.Q_RES(CHIPS)':
 'A': CDS_PINID='A';
NODE_NAME     U1 K3
 '@SCM_LIB.SCM(SCH_1):PAGE20_I196@PURE_QUANTA.K4A8G165WCBCTD(CHIPS)':
 'ODT': CDS_PINID='ODT';
NET_NAME
'M_BMC_DDR4_MRAS_N'
 '@SCM_LIB.SCM(SCH_1):M_BMC_DDR4_MRAS_N':
 C_SIGNAL='@scm_lib.scm(sch_1):m_bmc_ddr4_mras_n';
NODE_NAME     U5 J5
 '@SCM_LIB.SCM(SCH_1):PAGE12_I436@PURE_QUANTA.AST2600A3GP(CHIPS)':
 'MRAS#': CDS_PINID='\mras#\';
NODE_NAME     R342 2
 '@SCM_LIB.SCM(SCH_1):PAGE20_I122@PURE_QUANTA.Q_RES(CHIPS)':
 'B': CDS_PINID='B';
NODE_NAME     R367 1
 '@SCM_LIB.SCM(SCH_1):PAGE20_I136@PURE_QUANTA.Q_RES(CHIPS)':
 'A': CDS_PINID='A';
NODE_NAME     U1 L8
 '@SCM_LIB.SCM(SCH_1):PAGE20_I196@PURE_QUANTA.K4A8G165WCBCTD(CHIPS)':
 'RAS_N': CDS_PINID='RAS_N';
NET_NAME
'M_BMC_DDR4_MWE_N'
 '@SCM_LIB.SCM(SCH_1):M_BMC_DDR4_MWE_N':
 C_SIGNAL='@scm_lib.scm(sch_1):m_bmc_ddr4_mwe_n';
NODE_NAME     U5 G5
 '@SCM_LIB.SCM(SCH_1):PAGE12_I436@PURE_QUANTA.AST2600A3GP(CHIPS)':
 'MWE#': CDS_PINID='\mwe#\';
NODE_NAME     R340 2
 '@SCM_LIB.SCM(SCH_1):PAGE20_I124@PURE_QUANTA.Q_RES(CHIPS)':
 'B': CDS_PINID='B';
NODE_NAME     R365 1
 '@SCM_LIB.SCM(SCH_1):PAGE20_I138@PURE_QUANTA.Q_RES(CHIPS)':
 'A': CDS_PINID='A';
NODE_NAME     U1 L2
 '@SCM_LIB.SCM(SCH_1):PAGE20_I196@PURE_QUANTA.K4A8G165WCBCTD(CHIPS)':
 'WE_N||A14': CDS_PINID='\we_n||a14\';
NET_NAME
'M_BMC_DDR4_RST_N'
 '@SCM_LIB.SCM(SCH_1):M_BMC_DDR4_RST_N':
 C_SIGNAL='@scm_lib.scm(sch_1):m_bmc_ddr4_rst_n';
NODE_NAME     U5 L3
 '@SCM_LIB.SCM(SCH_1):PAGE12_I436@PURE_QUANTA.AST2600A3GP(CHIPS)':
 'MRESET#': CDS_PINID='\mreset#\';
NODE_NAME     U1 P1
 '@SCM_LIB.SCM(SCH_1):PAGE20_I196@PURE_QUANTA.K4A8G165WCBCTD(CHIPS)':
 'RESET_N': CDS_PINID='RESET_N';
NET_NAME
'M_BMC_DDR4_ZQU'
 '@SCM_LIB.SCM(SCH_1):M_BMC_DDR4_ZQU':
 C_SIGNAL='@scm_lib.scm(sch_1):m_bmc_ddr4_zqu';
NODE_NAME     R3 1
 '@SCM_LIB.SCM(SCH_1):PAGE20_I17@PURE_QUANTA.Q_RES(CHIPS)':
 'A': CDS_PINID='A';
NODE_NAME     U1 E9
 '@SCM_LIB.SCM(SCH_1):PAGE20_I196@PURE_QUANTA.K4A8G165WCBCTD(CHIPS)':
 'VSS2': CDS_PINID='VSS2';
NET_NAME
'NC'
 'NC':
 C_SIGNAL='NC';
NODE_NAME     U5 AB4
 '@SCM_LIB.SCM(SCH_1):PAGE14_I149@PURE_QUANTA.AST2600A3GP(CHIPS)':
 'GPIO18D0||EMMCCLK': CDS_PINID='\gpio18d0||emmcclk\';
NODE_NAME     U5 AA4
 '@SCM_LIB.SCM(SCH_1):PAGE14_I149@PURE_QUANTA.AST2600A3GP(CHIPS)':
 'GPIO18D1||EMMCCMD': CDS_PINID='\gpio18d1||emmccmd\';
NODE_NAME     U5 AC4
 '@SCM_LIB.SCM(SCH_1):PAGE14_I149@PURE_QUANTA.AST2600A3GP(CHIPS)':
 'GPIO18D2||EMMCDAT0': CDS_PINID='\gpio18d2||emmcdat0\';
NODE_NAME     U5 AA5
 '@SCM_LIB.SCM(SCH_1):PAGE14_I149@PURE_QUANTA.AST2600A3GP(CHIPS)':
 'GPIO18D3||EMMCDAT1': CDS_PINID='\gpio18d3||emmcdat1\';
NODE_NAME     U5 Y5
 '@SCM_LIB.SCM(SCH_1):PAGE14_I149@PURE_QUANTA.AST2600A3GP(CHIPS)':
 'GPIO18D4||EMMCDAT2': CDS_PINID='\gpio18d4||emmcdat2\';
NODE_NAME     U5 AB5
 '@SCM_LIB.SCM(SCH_1):PAGE14_I149@PURE_QUANTA.AST2600A3GP(CHIPS)':
 'GPIO18D5||EMMCDAT3': CDS_PINID='\gpio18d5||emmcdat3\';
NODE_NAME     U5 AC5
 '@SCM_LIB.SCM(SCH_1):PAGE14_I149@PURE_QUANTA.AST2600A3GP(CHIPS)':
 'GPIO18D6||EMMCCD#': CDS_PINID='\gpio18d6||emmccd#\';
NODE_NAME     U5 AB6
 '@SCM_LIB.SCM(SCH_1):PAGE14_I149@PURE_QUANTA.AST2600A3GP(CHIPS)':
 'GPIO18D7||EMMCWP#': CDS_PINID='\gpio18d7||emmcwp#\';
NODE_NAME     U5 Y1
 '@SCM_LIB.SCM(SCH_1):PAGE14_I149@PURE_QUANTA.AST2600A3GP(CHIPS)':
 'GPIO18E0||EMMCDAT4||FWSPI18CS#||VBCS#': CDS_PINID='\gpio18e0||emmcdat4||fwspi18cs#||vbcs#\';
NODE_NAME     U5 Y2
 '@SCM_LIB.SCM(SCH_1):PAGE14_I149@PURE_QUANTA.AST2600A3GP(CHIPS)':
 'GPIO18E1||EMMCDAT5||FWSPI18CK||VBCK': CDS_PINID='\gpio18e1||emmcdat5||fwspi18ck||vbck\';
NODE_NAME     U5 Y3
 '@SCM_LIB.SCM(SCH_1):PAGE14_I149@PURE_QUANTA.AST2600A3GP(CHIPS)':
 'GPIO18E2||EMMCDAT6||FWSPI18MOSI||VBMOSI': CDS_PINID='\gpio18e2||emmcdat6||fwspi18mosi||vbmosi\';
NODE_NAME     U5 Y4
 '@SCM_LIB.SCM(SCH_1):PAGE14_I149@PURE_QUANTA.AST2600A3GP(CHIPS)':
 'GPIO18E3||EMMCDAT7||FWSPI18MISO||VBMISO': CDS_PINID='\gpio18e3||emmcdat7||fwspi18miso||vbmiso\';
NODE_NAME     U5 B3
 '@SCM_LIB.SCM(SCH_1):PAGE14_I149@PURE_QUANTA.AST2600A3GP(CHIPS)':
 'RGMII1RXCK||RMII1RCLKI||GPIO18A6': CDS_PINID='\rgmii1rxck||rmii1rclki||gpio18a6\';
NODE_NAME     U5 A2
 '@SCM_LIB.SCM(SCH_1):PAGE14_I149@PURE_QUANTA.AST2600A3GP(CHIPS)':
 'RGMII1RXCTL||GPIO18A7': CDS_PINID='\rgmii1rxctl||gpio18a7\';
NODE_NAME     U5 B2
 '@SCM_LIB.SCM(SCH_1):PAGE14_I149@PURE_QUANTA.AST2600A3GP(CHIPS)':
 'RGMII1RXD0||RMII1RXD0||GPIO18B0': CDS_PINID='\rgmii1rxd0||rmii1rxd0||gpio18b0\';
NODE_NAME     U5 B1
 '@SCM_LIB.SCM(SCH_1):PAGE14_I149@PURE_QUANTA.AST2600A3GP(CHIPS)':
 'RGMII1RXD1||RMII1RXD1||GPIO18B1': CDS_PINID='\rgmii1rxd1||rmii1rxd1||gpio18b1\';
NODE_NAME     U5 C4
 '@SCM_LIB.SCM(SCH_1):PAGE14_I149@PURE_QUANTA.AST2600A3GP(CHIPS)':
 'RGMII1RXD2||RMII1CRSDV||GPIO18B2': CDS_PINID='\rgmii1rxd2||rmii1crsdv||gpio18b2\';
NODE_NAME     U5 E5
 '@SCM_LIB.SCM(SCH_1):PAGE14_I149@PURE_QUANTA.AST2600A3GP(CHIPS)':
 'RGMII1RXD3||RMII1RXER||GPIO18B3': CDS_PINID='\rgmii1rxd3||rmii1rxer||gpio18b3\';
NODE_NAME     U5 D6
 '@SCM_LIB.SCM(SCH_1):PAGE14_I149@PURE_QUANTA.AST2600A3GP(CHIPS)':
 'RGMII1TXCTL||RMII1TXEN||GPIO18A1': CDS_PINID='\rgmii1txctl||rmii1txen||gpio18a1\';
NODE_NAME     U5 D5
 '@SCM_LIB.SCM(SCH_1):PAGE14_I149@PURE_QUANTA.AST2600A3GP(CHIPS)':
 'RGMII1TXD0||RMII1TXD0||GPIO18A2': CDS_PINID='\rgmii1txd0||rmii1txd0||gpio18a2\';
NODE_NAME     U5 A3
 '@SCM_LIB.SCM(SCH_1):PAGE14_I149@PURE_QUANTA.AST2600A3GP(CHIPS)':
 'RGMII1TXD1||RMII1TXD1||GPIO18A3': CDS_PINID='\rgmii1txd1||rmii1txd1||gpio18a3\';
NODE_NAME     U5 C5
 '@SCM_LIB.SCM(SCH_1):PAGE14_I149@PURE_QUANTA.AST2600A3GP(CHIPS)':
 'RGMII1TXD2||GPIO18A4': CDS_PINID='\rgmii1txd2||gpio18a4\';
NODE_NAME     U5 E6
 '@SCM_LIB.SCM(SCH_1):PAGE14_I149@PURE_QUANTA.AST2600A3GP(CHIPS)':
 'RGMII1TXD3||GPIO18A5': CDS_PINID='\rgmii1txd3||gpio18a5\';
NODE_NAME     U5 D2
 '@SCM_LIB.SCM(SCH_1):PAGE14_I149@PURE_QUANTA.AST2600A3GP(CHIPS)':
 'RGMII2RXCK||RMII2RCLKI||GPIO18C2': CDS_PINID='\rgmii2rxck||rmii2rclki||gpio18c2\';
NODE_NAME     U5 E3
 '@SCM_LIB.SCM(SCH_1):PAGE14_I149@PURE_QUANTA.AST2600A3GP(CHIPS)':
 'RGMII2RXCTL||GPIO18C3': CDS_PINID='\rgmii2rxctl||gpio18c3\';
NODE_NAME     U5 D1
 '@SCM_LIB.SCM(SCH_1):PAGE14_I149@PURE_QUANTA.AST2600A3GP(CHIPS)':
 'RGMII2RXD0||RMII2RXD0||GPIO18C4': CDS_PINID='\rgmii2rxd0||rmii2rxd0||gpio18c4\';
NODE_NAME     U5 F4
 '@SCM_LIB.SCM(SCH_1):PAGE14_I149@PURE_QUANTA.AST2600A3GP(CHIPS)':
 'RGMII2RXD1||RMII2RXD1||GPIO18C5': CDS_PINID='\rgmii2rxd1||rmii2rxd1||gpio18c5\';
NODE_NAME     U5 E2
 '@SCM_LIB.SCM(SCH_1):PAGE14_I149@PURE_QUANTA.AST2600A3GP(CHIPS)':
 'RGMII2RXD2||RMII2CRSDV||GPIO18C6': CDS_PINID='\rgmii2rxd2||rmii2crsdv||gpio18c6\';
NODE_NAME     U5 E1
 '@SCM_LIB.SCM(SCH_1):PAGE14_I149@PURE_QUANTA.AST2600A3GP(CHIPS)':
 'RGMII2RXD3||RMII2RXER||GPIO18C7': CDS_PINID='\rgmii2rxd3||rmii2rxer||gpio18c7\';
NODE_NAME     U5 D4
 '@SCM_LIB.SCM(SCH_1):PAGE14_I149@PURE_QUANTA.AST2600A3GP(CHIPS)':
 'RGMII2TXCK||RMII2RCLKO||GPIO18B4': CDS_PINID='\rgmii2txck||rmii2rclko||gpio18b4\';
NODE_NAME     U5 C2
 '@SCM_LIB.SCM(SCH_1):PAGE14_I149@PURE_QUANTA.AST2600A3GP(CHIPS)':
 'RGMII2TXCTL||RMII2TXEN||GPIO18B5': CDS_PINID='\rgmii2txctl||rmii2txen||gpio18b5\';
NODE_NAME     U5 C1
 '@SCM_LIB.SCM(SCH_1):PAGE14_I149@PURE_QUANTA.AST2600A3GP(CHIPS)':
 'RGMII2TXD0||RMII2TXD0||GPIO18B6': CDS_PINID='\rgmii2txd0||rmii2txd0||gpio18b6\';
NODE_NAME     U5 AD22
 '@SCM_LIB.SCM(SCH_1):PAGE15_I350@PURE_QUANTA.AST2600A3GP(CHIPS)':
 'GPIOO1||PWM1': CDS_PINID='\gpioo1||pwm1\';
NODE_NAME     U13 1
 '@SCM_LIB.SCM(SCH_1):PAGE22_I89@PURE_QUANTA.MC74VHC1G07DFT2G(CHIPS)':
 'NC1': CDS_PINID='NC1';
NODE_NAME     U44 1
 '@SCM_LIB.SCM(SCH_1):PAGE25_I61@PURE_QUANTA.SN74LVC1G07DCKR(CHIPS)':
 'NC1': CDS_PINID='NC1';
NODE_NAME     U23 1
 '@SCM_LIB.SCM(SCH_1):PAGE28_I180@PURE_QUANTA.74LVC1G07W57(CHIPS)':
 'NC1': CDS_PINID='NC1';
NODE_NAME     U22 TH
 '@SCM_LIB.SCM(SCH_1):PAGE29_I206@PURE_QUANTA.PI3PCIE3212ZBEX(CHIPS)':
 'TH': CDS_PINID='TH';
NODE_NAME     U25 D9
 '@SCM_LIB.SCM(SCH_1):PAGE34_I1@PURE_QUANTA.LCMXO3LF2100C5BG256C(CHIPS)':
 'PT18B': CDS_PINID='PT18B';
NODE_NAME     U25 A10
 '@SCM_LIB.SCM(SCH_1):PAGE34_I1@PURE_QUANTA.LCMXO3LF2100C5BG256C(CHIPS)':
 'PT19B': CDS_PINID='PT19B';
NODE_NAME     U25 F9
 '@SCM_LIB.SCM(SCH_1):PAGE34_I1@PURE_QUANTA.LCMXO3LF2100C5BG256C(CHIPS)':
 'PT19C': CDS_PINID='PT19C';
NODE_NAME     U25 D10
 '@SCM_LIB.SCM(SCH_1):PAGE34_I1@PURE_QUANTA.LCMXO3LF2100C5BG256C(CHIPS)':
 'PT20A': CDS_PINID='PT20A';
NODE_NAME     U25 F16
 '@SCM_LIB.SCM(SCH_1):PAGE35_I1@PURE_QUANTA.LCMXO3LF2100C5BG256C(CHIPS)':
 'PR4B': CDS_PINID='PR4B';
NODE_NAME     U25 G15
 '@SCM_LIB.SCM(SCH_1):PAGE35_I1@PURE_QUANTA.LCMXO3LF2100C5BG256C(CHIPS)':
 'PR5A': CDS_PINID='PR5A';
NODE_NAME     U25 G14
 '@SCM_LIB.SCM(SCH_1):PAGE35_I1@PURE_QUANTA.LCMXO3LF2100C5BG256C(CHIPS)':
 'PR5B': CDS_PINID='PR5B';
NODE_NAME     U25 H14
 '@SCM_LIB.SCM(SCH_1):PAGE35_I1@PURE_QUANTA.LCMXO3LF2100C5BG256C(CHIPS)':
 'PR7A||PCLKT1_0': CDS_PINID='\pr7a||pclkt1_0\';
NODE_NAME     U25 H16
 '@SCM_LIB.SCM(SCH_1):PAGE35_I1@PURE_QUANTA.LCMXO3LF2100C5BG256C(CHIPS)':
 'PR7B||PCLKC1_0': CDS_PINID='\pr7b||pclkc1_0\';
NODE_NAME     U25 K16
 '@SCM_LIB.SCM(SCH_1):PAGE35_I1@PURE_QUANTA.LCMXO3LF2100C5BG256C(CHIPS)':
 'PR9B': CDS_PINID='PR9B';
NODE_NAME     U25 J11
 '@SCM_LIB.SCM(SCH_1):PAGE35_I1@PURE_QUANTA.LCMXO3LF2100C5BG256C(CHIPS)':
 'PR10C': CDS_PINID='PR10C';
NODE_NAME     U25 L15
 '@SCM_LIB.SCM(SCH_1):PAGE35_I1@PURE_QUANTA.LCMXO3LF2100C5BG256C(CHIPS)':
 'PR12A': CDS_PINID='PR12A';
NODE_NAME     U25 M16
 '@SCM_LIB.SCM(SCH_1):PAGE35_I1@PURE_QUANTA.LCMXO3LF2100C5BG256C(CHIPS)':
 'PR12B': CDS_PINID='PR12B';
NODE_NAME     U25 P16
 '@SCM_LIB.SCM(SCH_1):PAGE35_I1@PURE_QUANTA.LCMXO3LF2100C5BG256C(CHIPS)':
 'PR13D': CDS_PINID='PR13D';
NODE_NAME     U25 P15
 '@SCM_LIB.SCM(SCH_1):PAGE35_I1@PURE_QUANTA.LCMXO3LF2100C5BG256C(CHIPS)':
 'PR14C': CDS_PINID='PR14C';
NODE_NAME     U25 T4
 '@SCM_LIB.SCM(SCH_1):PAGE36_I1@PURE_QUANTA.LCMXO3LF2100C5BG256C(CHIPS)':
 'PB3B': CDS_PINID='PB3B';
NODE_NAME     U25 R9
 '@SCM_LIB.SCM(SCH_1):PAGE36_I1@PURE_QUANTA.LCMXO3LF2100C5BG256C(CHIPS)':
 'PB18A': CDS_PINID='PB18A';
NODE_NAME     U25 T10
 '@SCM_LIB.SCM(SCH_1):PAGE36_I1@PURE_QUANTA.LCMXO3LF2100C5BG256C(CHIPS)':
 'PB18B': CDS_PINID='PB18B';
NODE_NAME     U25 P10
 '@SCM_LIB.SCM(SCH_1):PAGE36_I1@PURE_QUANTA.LCMXO3LF2100C5BG256C(CHIPS)':
 'PB19A': CDS_PINID='PB19A';
NODE_NAME     U25 R10
 '@SCM_LIB.SCM(SCH_1):PAGE36_I1@PURE_QUANTA.LCMXO3LF2100C5BG256C(CHIPS)':
 'PB19B': CDS_PINID='PB19B';
NODE_NAME     U25 N10
 '@SCM_LIB.SCM(SCH_1):PAGE36_I1@PURE_QUANTA.LCMXO3LF2100C5BG256C(CHIPS)':
 'PB19C': CDS_PINID='PB19C';
NODE_NAME     U25 M11
 '@SCM_LIB.SCM(SCH_1):PAGE36_I1@PURE_QUANTA.LCMXO3LF2100C5BG256C(CHIPS)':
 'PB19D': CDS_PINID='PB19D';
NODE_NAME     U25 T11
 '@SCM_LIB.SCM(SCH_1):PAGE36_I1@PURE_QUANTA.LCMXO3LF2100C5BG256C(CHIPS)':
 'PB21A': CDS_PINID='PB21A';
NODE_NAME     U25 P11
 '@SCM_LIB.SCM(SCH_1):PAGE36_I1@PURE_QUANTA.LCMXO3LF2100C5BG256C(CHIPS)':
 'PB21B': CDS_PINID='PB21B';
NODE_NAME     U25 N11
 '@SCM_LIB.SCM(SCH_1):PAGE36_I1@PURE_QUANTA.LCMXO3LF2100C5BG256C(CHIPS)':
 'PB21D': CDS_PINID='PB21D';
NODE_NAME     U25 R11
 '@SCM_LIB.SCM(SCH_1):PAGE36_I1@PURE_QUANTA.LCMXO3LF2100C5BG256C(CHIPS)':
 'PB22A': CDS_PINID='PB22A';
NODE_NAME     U25 T12
 '@SCM_LIB.SCM(SCH_1):PAGE36_I1@PURE_QUANTA.LCMXO3LF2100C5BG256C(CHIPS)':
 'PB22B': CDS_PINID='PB22B';
NODE_NAME     U25 R13
 '@SCM_LIB.SCM(SCH_1):PAGE36_I1@PURE_QUANTA.LCMXO3LF2100C5BG256C(CHIPS)':
 'PB22C': CDS_PINID='PB22C';
NODE_NAME     U25 T14
 '@SCM_LIB.SCM(SCH_1):PAGE36_I1@PURE_QUANTA.LCMXO3LF2100C5BG256C(CHIPS)':
 'PB22D': CDS_PINID='PB22D';
NODE_NAME     U25 P12
 '@SCM_LIB.SCM(SCH_1):PAGE36_I1@PURE_QUANTA.LCMXO3LF2100C5BG256C(CHIPS)':
 'PB24A': CDS_PINID='PB24A';
NODE_NAME     U25 T13
 '@SCM_LIB.SCM(SCH_1):PAGE36_I1@PURE_QUANTA.LCMXO3LF2100C5BG256C(CHIPS)':
 'PB24B': CDS_PINID='PB24B';
NODE_NAME     U25 P13
 '@SCM_LIB.SCM(SCH_1):PAGE36_I1@PURE_QUANTA.LCMXO3LF2100C5BG256C(CHIPS)':
 'PB25B||SI||SISPI': CDS_PINID='\pb25b||si||sispi\';
NODE_NAME     U25 L1
 '@SCM_LIB.SCM(SCH_1):PAGE37_I1@PURE_QUANTA.LCMXO3LF2100C5BG256C(CHIPS)':
 'PL11A': CDS_PINID='PL11A';
NODE_NAME     U25 L3
 '@SCM_LIB.SCM(SCH_1):PAGE37_I1@PURE_QUANTA.LCMXO3LF2100C5BG256C(CHIPS)':
 'PL11B': CDS_PINID='PL11B';
NODE_NAME     U25 K4
 '@SCM_LIB.SCM(SCH_1):PAGE37_I1@PURE_QUANTA.LCMXO3LF2100C5BG256C(CHIPS)':
 'PL11C': CDS_PINID='PL11C';
NODE_NAME     U25 L5
 '@SCM_LIB.SCM(SCH_1):PAGE37_I1@PURE_QUANTA.LCMXO3LF2100C5BG256C(CHIPS)':
 'PL11D': CDS_PINID='PL11D';
NODE_NAME     U25 L2
 '@SCM_LIB.SCM(SCH_1):PAGE37_I1@PURE_QUANTA.LCMXO3LF2100C5BG256C(CHIPS)':
 'PL12A||PCLKT3_0': CDS_PINID='\pl12a||pclkt3_0\';
NODE_NAME     U25 M1
 '@SCM_LIB.SCM(SCH_1):PAGE37_I1@PURE_QUANTA.LCMXO3LF2100C5BG256C(CHIPS)':
 'PL12B||PCLKC3_0': CDS_PINID='\pl12b||pclkc3_0\';
NODE_NAME     U25 K5
 '@SCM_LIB.SCM(SCH_1):PAGE37_I1@PURE_QUANTA.LCMXO3LF2100C5BG256C(CHIPS)':
 'PL12C': CDS_PINID='PL12C';
NODE_NAME     U25 L4
 '@SCM_LIB.SCM(SCH_1):PAGE37_I1@PURE_QUANTA.LCMXO3LF2100C5BG256C(CHIPS)':
 'PL12D': CDS_PINID='PL12D';
NODE_NAME     U25 M3
 '@SCM_LIB.SCM(SCH_1):PAGE37_I1@PURE_QUANTA.LCMXO3LF2100C5BG256C(CHIPS)':
 'PL13A': CDS_PINID='PL13A';
NODE_NAME     U25 N1
 '@SCM_LIB.SCM(SCH_1):PAGE37_I1@PURE_QUANTA.LCMXO3LF2100C5BG256C(CHIPS)':
 'PL13B': CDS_PINID='PL13B';
NODE_NAME     U25 N2
 '@SCM_LIB.SCM(SCH_1):PAGE37_I1@PURE_QUANTA.LCMXO3LF2100C5BG256C(CHIPS)':
 'PL13C': CDS_PINID='PL13C';
NODE_NAME     U25 P1
 '@SCM_LIB.SCM(SCH_1):PAGE37_I1@PURE_QUANTA.LCMXO3LF2100C5BG256C(CHIPS)':
 'PL13D': CDS_PINID='PL13D';
NODE_NAME     U25 M2
 '@SCM_LIB.SCM(SCH_1):PAGE37_I1@PURE_QUANTA.LCMXO3LF2100C5BG256C(CHIPS)':
 'PL14A': CDS_PINID='PL14A';
NODE_NAME     U25 N3
 '@SCM_LIB.SCM(SCH_1):PAGE37_I1@PURE_QUANTA.LCMXO3LF2100C5BG256C(CHIPS)':
 'PL14B': CDS_PINID='PL14B';
NODE_NAME     U25 R1
 '@SCM_LIB.SCM(SCH_1):PAGE37_I1@PURE_QUANTA.LCMXO3LF2100C5BG256C(CHIPS)':
 'PL14C': CDS_PINID='PL14C';
NODE_NAME     U25 P2
 '@SCM_LIB.SCM(SCH_1):PAGE37_I1@PURE_QUANTA.LCMXO3LF2100C5BG256C(CHIPS)':
 'PL14D': CDS_PINID='PL14D';
NODE_NAME     U25 G1
 '@SCM_LIB.SCM(SCH_1):PAGE38_I1@PURE_QUANTA.LCMXO3LF2100C5BG256C(CHIPS)':
 'PL6A': CDS_PINID='PL6A';
NODE_NAME     U25 H2
 '@SCM_LIB.SCM(SCH_1):PAGE38_I1@PURE_QUANTA.LCMXO3LF2100C5BG256C(CHIPS)':
 'PL6B': CDS_PINID='PL6B';
NODE_NAME     U25 H4
 '@SCM_LIB.SCM(SCH_1):PAGE38_I1@PURE_QUANTA.LCMXO3LF2100C5BG256C(CHIPS)':
 'PL6C': CDS_PINID='PL6C';
NODE_NAME     U25 J6
 '@SCM_LIB.SCM(SCH_1):PAGE38_I1@PURE_QUANTA.LCMXO3LF2100C5BG256C(CHIPS)':
 'PL6D': CDS_PINID='PL6D';
NODE_NAME     U25 H3
 '@SCM_LIB.SCM(SCH_1):PAGE38_I1@PURE_QUANTA.LCMXO3LF2100C5BG256C(CHIPS)':
 'PL7A': CDS_PINID='PL7A';
NODE_NAME     U25 H1
 '@SCM_LIB.SCM(SCH_1):PAGE38_I1@PURE_QUANTA.LCMXO3LF2100C5BG256C(CHIPS)':
 'PL7B': CDS_PINID='PL7B';
NODE_NAME     U25 J1
 '@SCM_LIB.SCM(SCH_1):PAGE38_I1@PURE_QUANTA.LCMXO3LF2100C5BG256C(CHIPS)':
 'PL7C||PCLKT4_0': CDS_PINID='\pl7c||pclkt4_0\';
NODE_NAME     U25 J3
 '@SCM_LIB.SCM(SCH_1):PAGE38_I1@PURE_QUANTA.LCMXO3LF2100C5BG256C(CHIPS)':
 'PL7D||PCLKC4_0': CDS_PINID='\pl7d||pclkc4_0\';
NODE_NAME     U25 J2
 '@SCM_LIB.SCM(SCH_1):PAGE38_I1@PURE_QUANTA.LCMXO3LF2100C5BG256C(CHIPS)':
 'PL9A': CDS_PINID='PL9A';
NODE_NAME     U25 K1
 '@SCM_LIB.SCM(SCH_1):PAGE38_I1@PURE_QUANTA.LCMXO3LF2100C5BG256C(CHIPS)':
 'PL9B': CDS_PINID='PL9B';
NODE_NAME     U25 H5
 '@SCM_LIB.SCM(SCH_1):PAGE38_I1@PURE_QUANTA.LCMXO3LF2100C5BG256C(CHIPS)':
 'PL9C': CDS_PINID='PL9C';
NODE_NAME     U25 J4
 '@SCM_LIB.SCM(SCH_1):PAGE38_I1@PURE_QUANTA.LCMXO3LF2100C5BG256C(CHIPS)':
 'PL9D': CDS_PINID='PL9D';
NODE_NAME     U25 K3
 '@SCM_LIB.SCM(SCH_1):PAGE38_I1@PURE_QUANTA.LCMXO3LF2100C5BG256C(CHIPS)':
 'PL10A': CDS_PINID='PL10A';
NODE_NAME     U25 K2
 '@SCM_LIB.SCM(SCH_1):PAGE38_I1@PURE_QUANTA.LCMXO3LF2100C5BG256C(CHIPS)':
 'PL10B': CDS_PINID='PL10B';
NODE_NAME     U25 J5
 '@SCM_LIB.SCM(SCH_1):PAGE38_I1@PURE_QUANTA.LCMXO3LF2100C5BG256C(CHIPS)':
 'PL10C': CDS_PINID='PL10C';
NODE_NAME     U25 K6
 '@SCM_LIB.SCM(SCH_1):PAGE38_I1@PURE_QUANTA.LCMXO3LF2100C5BG256C(CHIPS)':
 'PL10D': CDS_PINID='PL10D';
NODE_NAME     U25 D3
 '@SCM_LIB.SCM(SCH_1):PAGE39_I1@PURE_QUANTA.LCMXO3LF2100C5BG256C(CHIPS)':
 'PL1A||L_GPLLT_FB': CDS_PINID='\pl1a||l_gpllt_fb\';
NODE_NAME     U25 D1
 '@SCM_LIB.SCM(SCH_1):PAGE39_I1@PURE_QUANTA.LCMXO3LF2100C5BG256C(CHIPS)':
 'PL1B||L_GPLLC_FB': CDS_PINID='\pl1b||l_gpllc_fb\';
NODE_NAME     U25 B1
 '@SCM_LIB.SCM(SCH_1):PAGE39_I1@PURE_QUANTA.LCMXO3LF2100C5BG256C(CHIPS)':
 'PL1C': CDS_PINID='PL1C';
NODE_NAME     U25 C2
 '@SCM_LIB.SCM(SCH_1):PAGE39_I1@PURE_QUANTA.LCMXO3LF2100C5BG256C(CHIPS)':
 'PL1D': CDS_PINID='PL1D';
NODE_NAME     U25 E2
 '@SCM_LIB.SCM(SCH_1):PAGE39_I1@PURE_QUANTA.LCMXO3LF2100C5BG256C(CHIPS)':
 'PL2A||L_GPLLT_IN': CDS_PINID='\pl2a||l_gpllt_in\';
NODE_NAME     U25 E3
 '@SCM_LIB.SCM(SCH_1):PAGE39_I1@PURE_QUANTA.LCMXO3LF2100C5BG256C(CHIPS)':
 'PL2B||L_GPLLC_IN': CDS_PINID='\pl2b||l_gpllc_in\';
NODE_NAME     U25 C1
 '@SCM_LIB.SCM(SCH_1):PAGE39_I1@PURE_QUANTA.LCMXO3LF2100C5BG256C(CHIPS)':
 'PL2C': CDS_PINID='PL2C';
NODE_NAME     U25 D2
 '@SCM_LIB.SCM(SCH_1):PAGE39_I1@PURE_QUANTA.LCMXO3LF2100C5BG256C(CHIPS)':
 'PL2D': CDS_PINID='PL2D';
NODE_NAME     U25 E1
 '@SCM_LIB.SCM(SCH_1):PAGE39_I1@PURE_QUANTA.LCMXO3LF2100C5BG256C(CHIPS)':
 'PL3A||PCLKT5_0': CDS_PINID='\pl3a||pclkt5_0\';
NODE_NAME     U25 F2
 '@SCM_LIB.SCM(SCH_1):PAGE39_I1@PURE_QUANTA.LCMXO3LF2100C5BG256C(CHIPS)':
 'PL3B||PCLKC5_0': CDS_PINID='\pl3b||pclkc5_0\';
NODE_NAME     U25 F4
 '@SCM_LIB.SCM(SCH_1):PAGE39_I1@PURE_QUANTA.LCMXO3LF2100C5BG256C(CHIPS)':
 'PL3C': CDS_PINID='PL3C';
NODE_NAME     U25 G6
 '@SCM_LIB.SCM(SCH_1):PAGE39_I1@PURE_QUANTA.LCMXO3LF2100C5BG256C(CHIPS)':
 'PL3D': CDS_PINID='PL3D';
NODE_NAME     U25 F3
 '@SCM_LIB.SCM(SCH_1):PAGE39_I1@PURE_QUANTA.LCMXO3LF2100C5BG256C(CHIPS)':
 'PL4A': CDS_PINID='PL4A';
NODE_NAME     U25 F1
 '@SCM_LIB.SCM(SCH_1):PAGE39_I1@PURE_QUANTA.LCMXO3LF2100C5BG256C(CHIPS)':
 'PL4B': CDS_PINID='PL4B';
NODE_NAME     U25 G5
 '@SCM_LIB.SCM(SCH_1):PAGE39_I1@PURE_QUANTA.LCMXO3LF2100C5BG256C(CHIPS)':
 'PL4C': CDS_PINID='PL4C';
NODE_NAME     U25 G4
 '@SCM_LIB.SCM(SCH_1):PAGE39_I1@PURE_QUANTA.LCMXO3LF2100C5BG256C(CHIPS)':
 'PL4D': CDS_PINID='PL4D';
NODE_NAME     U25 G2
 '@SCM_LIB.SCM(SCH_1):PAGE39_I1@PURE_QUANTA.LCMXO3LF2100C5BG256C(CHIPS)':
 'PL5A': CDS_PINID='PL5A';
NODE_NAME     U25 G3
 '@SCM_LIB.SCM(SCH_1):PAGE39_I1@PURE_QUANTA.LCMXO3LF2100C5BG256C(CHIPS)':
 'PL5B': CDS_PINID='PL5B';
NODE_NAME     U25 F5
 '@SCM_LIB.SCM(SCH_1):PAGE39_I1@PURE_QUANTA.LCMXO3LF2100C5BG256C(CHIPS)':
 'PL5C': CDS_PINID='PL5C';
NODE_NAME     U25 H6
 '@SCM_LIB.SCM(SCH_1):PAGE39_I1@PURE_QUANTA.LCMXO3LF2100C5BG256C(CHIPS)':
 'PL5D': CDS_PINID='PL5D';
NODE_NAME     U25 A2
 '@SCM_LIB.SCM(SCH_1):PAGE40_I1@PURE_QUANTA.LCMXO3LF2100C5BG256C(CHIPS)':
 'NC1': CDS_PINID='NC1';
NODE_NAME     H2B1 1
 '@SCM_LIB.SCM(SCH_1):PAGE57_I14@PURE_QUANTA.HOLE(CHIPS)':
 '1': CDS_PINID='\1\';
NODE_NAME     H2B2 1
 '@SCM_LIB.SCM(SCH_1):PAGE57_I34@PURE_QUANTA.HOLE(CHIPS)':
 '1': CDS_PINID='\1\';
NODE_NAME     DM3 1
 '@SCM_LIB.SCM(SCH_1):PAGE59_I35@PURE_QUANTA.DUMMY_SYMBOL(CHIPS)':
 '1': CDS_PINID='\1\';
NODE_NAME     DM1 1
 '@SCM_LIB.SCM(SCH_1):PAGE59_I36@PURE_QUANTA.DUMMY_SYMBOL(CHIPS)':
 '1': CDS_PINID='\1\';
NODE_NAME     DM2 1
 '@SCM_LIB.SCM(SCH_1):PAGE59_I37@PURE_QUANTA.DUMMY_SYMBOL(CHIPS)':
 '1': CDS_PINID='\1\';
NODE_NAME     J4 6
 '@SCM_LIB.SCM(SCH_1):PAGE21_I84@PURE_QUANTA.SCONN67_NASA0S6730TS67(CHIPS)':
 '6': CDS_PINID='\6\';
NODE_NAME     J4 17
 '@SCM_LIB.SCM(SCH_1):PAGE21_I84@PURE_QUANTA.SCONN67_NASA0S6730TS67(CHIPS)':
 '17': CDS_PINID='\17\';
NODE_NAME     J4 20
 '@SCM_LIB.SCM(SCH_1):PAGE21_I84@PURE_QUANTA.SCONN67_NASA0S6730TS67(CHIPS)':
 '20': CDS_PINID='\20\';
NODE_NAME     J4 22
 '@SCM_LIB.SCM(SCH_1):PAGE21_I84@PURE_QUANTA.SCONN67_NASA0S6730TS67(CHIPS)':
 '22': CDS_PINID='\22\';
NODE_NAME     J4 32
 '@SCM_LIB.SCM(SCH_1):PAGE21_I84@PURE_QUANTA.SCONN67_NASA0S6730TS67(CHIPS)':
 '32': CDS_PINID='\32\';
NODE_NAME     J4 34
 '@SCM_LIB.SCM(SCH_1):PAGE21_I84@PURE_QUANTA.SCONN67_NASA0S6730TS67(CHIPS)':
 '34': CDS_PINID='\34\';
NODE_NAME     J4 38
 '@SCM_LIB.SCM(SCH_1):PAGE21_I84@PURE_QUANTA.SCONN67_NASA0S6730TS67(CHIPS)':
 '38': CDS_PINID='\38\';
NODE_NAME     J4 41
 '@SCM_LIB.SCM(SCH_1):PAGE21_I84@PURE_QUANTA.SCONN67_NASA0S6730TS67(CHIPS)':
 '41': CDS_PINID='\41\';
NODE_NAME     J4 43
 '@SCM_LIB.SCM(SCH_1):PAGE21_I84@PURE_QUANTA.SCONN67_NASA0S6730TS67(CHIPS)':
 '43': CDS_PINID='\43\';
NODE_NAME     J4 44
 '@SCM_LIB.SCM(SCH_1):PAGE21_I84@PURE_QUANTA.SCONN67_NASA0S6730TS67(CHIPS)':
 '44': CDS_PINID='\44\';
NODE_NAME     J4 47
 '@SCM_LIB.SCM(SCH_1):PAGE21_I84@PURE_QUANTA.SCONN67_NASA0S6730TS67(CHIPS)':
 '47': CDS_PINID='\47\';
NODE_NAME     J4 48
 '@SCM_LIB.SCM(SCH_1):PAGE21_I84@PURE_QUANTA.SCONN67_NASA0S6730TS67(CHIPS)':
 '48': CDS_PINID='\48\';
NODE_NAME     J4 49
 '@SCM_LIB.SCM(SCH_1):PAGE21_I84@PURE_QUANTA.SCONN67_NASA0S6730TS67(CHIPS)':
 '49': CDS_PINID='\49\';
NODE_NAME     J4 50
 '@SCM_LIB.SCM(SCH_1):PAGE21_I84@PURE_QUANTA.SCONN67_NASA0S6730TS67(CHIPS)':
 '50': CDS_PINID='\50\';
NODE_NAME     J4 53
 '@SCM_LIB.SCM(SCH_1):PAGE21_I84@PURE_QUANTA.SCONN67_NASA0S6730TS67(CHIPS)':
 '53': CDS_PINID='\53\';
NODE_NAME     J4 60
 '@SCM_LIB.SCM(SCH_1):PAGE21_I84@PURE_QUANTA.SCONN67_NASA0S6730TS67(CHIPS)':
 '60': CDS_PINID='\60\';
NODE_NAME     J4 62
 '@SCM_LIB.SCM(SCH_1):PAGE21_I84@PURE_QUANTA.SCONN67_NASA0S6730TS67(CHIPS)':
 '62': CDS_PINID='\62\';
NODE_NAME     J4 64
 '@SCM_LIB.SCM(SCH_1):PAGE21_I84@PURE_QUANTA.SCONN67_NASA0S6730TS67(CHIPS)':
 '64': CDS_PINID='\64\';
NODE_NAME     J4 68
 '@SCM_LIB.SCM(SCH_1):PAGE21_I84@PURE_QUANTA.SCONN67_NASA0S6730TS67(CHIPS)':
 '68': CDS_PINID='\68\';
NODE_NAME     J4 70
 '@SCM_LIB.SCM(SCH_1):PAGE21_I84@PURE_QUANTA.SCONN67_NASA0S6730TS67(CHIPS)':
 '70': CDS_PINID='\70\';
NODE_NAME     J4 73
 '@SCM_LIB.SCM(SCH_1):PAGE21_I84@PURE_QUANTA.SCONN67_NASA0S6730TS67(CHIPS)':
 '73': CDS_PINID='\73\';
NODE_NAME     H2 1
 '@SCM_LIB.SCM(SCH_1):PAGE57_I45@PURE_QUANTA.HOLE(CHIPS)':
 '1': CDS_PINID='\1\';
NET_NAME
'NC_DP_BMC_AUX_N'
 '@SCM_LIB.SCM(SCH_1):NC_DP_BMC_AUX_N':
 C_SIGNAL='@scm_lib.scm(sch_1):nc_dp_bmc_aux_n';
NODE_NAME     U5 AB3
 '@SCM_LIB.SCM(SCH_1):PAGE12_I436@PURE_QUANTA.AST2600A3GP(CHIPS)':
 'DPAUXN': CDS_PINID='DPAUXN';
NET_NAME
'NC_DP_BMC_AUX_P'
 '@SCM_LIB.SCM(SCH_1):NC_DP_BMC_AUX_P':
 C_SIGNAL='@scm_lib.scm(sch_1):nc_dp_bmc_aux_p';
NODE_NAME     U5 AC3
 '@SCM_LIB.SCM(SCH_1):PAGE12_I436@PURE_QUANTA.AST2600A3GP(CHIPS)':
 'DPAUXP': CDS_PINID='DPAUXP';
NET_NAME
'NC_DP_BMC_TX0_N'
 '@SCM_LIB.SCM(SCH_1):NC_DP_BMC_TX0_N':
 C_SIGNAL='@scm_lib.scm(sch_1):nc_dp_bmc_tx0_n';
NODE_NAME     U5 AB1
 '@SCM_LIB.SCM(SCH_1):PAGE12_I436@PURE_QUANTA.AST2600A3GP(CHIPS)':
 'DPTXN0': CDS_PINID='DPTXN0';
NET_NAME
'NC_DP_BMC_TX0_P'
 '@SCM_LIB.SCM(SCH_1):NC_DP_BMC_TX0_P':
 C_SIGNAL='@scm_lib.scm(sch_1):nc_dp_bmc_tx0_p';
NODE_NAME     U5 AC1
 '@SCM_LIB.SCM(SCH_1):PAGE12_I436@PURE_QUANTA.AST2600A3GP(CHIPS)':
 'DPTXP0': CDS_PINID='DPTXP0';
NET_NAME
'NC_DP_BMC_TX1_N'
 '@SCM_LIB.SCM(SCH_1):NC_DP_BMC_TX1_N':
 C_SIGNAL='@scm_lib.scm(sch_1):nc_dp_bmc_tx1_n';
NODE_NAME     U5 AA2
 '@SCM_LIB.SCM(SCH_1):PAGE12_I436@PURE_QUANTA.AST2600A3GP(CHIPS)':
 'DPTXN1': CDS_PINID='DPTXN1';
NET_NAME
'NC_DP_BMC_TX1_P'
 '@SCM_LIB.SCM(SCH_1):NC_DP_BMC_TX1_P':
 C_SIGNAL='@scm_lib.scm(sch_1):nc_dp_bmc_tx1_p';
NODE_NAME     U5 AB2
 '@SCM_LIB.SCM(SCH_1):PAGE12_I436@PURE_QUANTA.AST2600A3GP(CHIPS)':
 'DPTXP1': CDS_PINID='DPTXP1';
NET_NAME
'NC_FM_PFR_NO_SERVICE_ACT_N'
 '@SCM_LIB.SCM(SCH_1):NC_FM_PFR_NO_SERVICE_ACT_N':
 C_SIGNAL='@scm_lib.scm(sch_1):nc_fm_pfr_no_service_act_n';
NODE_NAME     U25 L7
 '@SCM_LIB.SCM(SCH_1):PAGE36_I1@PURE_QUANTA.LCMXO3LF2100C5BG256C(CHIPS)':
 'PB8D': CDS_PINID='PB8D';
NET_NAME
'NC_FM_PFR_UPDATE_N'
 '@SCM_LIB.SCM(SCH_1):NC_FM_PFR_UPDATE_N':
 C_SIGNAL='@scm_lib.scm(sch_1):nc_fm_pfr_update_n';
NODE_NAME     U25 R8
 '@SCM_LIB.SCM(SCH_1):PAGE36_I1@PURE_QUANTA.LCMXO3LF2100C5BG256C(CHIPS)':
 'PB11B||PCLKC2_0': CDS_PINID='\pb11b||pclkc2_0\';
NET_NAME
'NC_J1_P3'
 '@SCM_LIB.SCM(SCH_1):NC_J1_P3':
 C_SIGNAL='@scm_lib.scm(sch_1):nc_j1_p3';
NODE_NAME     J1 3
 '@SCM_LIB.SCM(SCH_1):PAGE25_I169@PURE_QUANTA.SCONN3_212H9103GBR1(CHIPS)':
 '3': CDS_PINID='\3\';
NET_NAME
'NC_U16_P1'
 '@SCM_LIB.SCM(SCH_1):NC_U16_P1':
 C_SIGNAL='@scm_lib.scm(sch_1):nc_u16_p1';
NODE_NAME     U16 1
 '@SCM_LIB.SCM(SCH_1):PAGE50_I227@PURE_QUANTA.74LVC1G07GW(CHIPS)':
 'NC': CDS_PINID='NC';
NET_NAME
'NC_U54_P1'
 '@SCM_LIB.SCM(SCH_1):NC_U54_P1':
 C_SIGNAL='@scm_lib.scm(sch_1):nc_u54_p1';
NODE_NAME     U54 5
 '@SCM_LIB.SCM(SCH_1):PAGE25_I138@PURE_QUANTA.74LVC1G74DP(CHIPS)':
 'Q': CDS_PINID='Q';
NET_NAME
'NC_U55_P1'
 '@SCM_LIB.SCM(SCH_1):NC_U55_P1':
 C_SIGNAL='@scm_lib.scm(sch_1):nc_u55_p1';
NODE_NAME     U55 1
 '@SCM_LIB.SCM(SCH_1):PAGE25_I150@PURE_QUANTA.SN74LVC1G14DCKR(CHIPS)':
 'NC': CDS_PINID='NC';
NET_NAME
'NC_U57_P1'
 '@SCM_LIB.SCM(SCH_1):NC_U57_P1':
 C_SIGNAL='@scm_lib.scm(sch_1):nc_u57_p1';
NODE_NAME     U57 1
 '@SCM_LIB.SCM(SCH_1):PAGE50_I278@PURE_QUANTA.74LVC1G07GW(CHIPS)':
 'NC': CDS_PINID='NC';
NET_NAME
'P0V6_DDR_VREF_AUX'
 '@SCM_LIB.SCM(SCH_1):P0V6_DDR_VREF_AUX':
 C_SIGNAL='@scm_lib.scm(sch_1):p0v6_ddr_vref_aux',
 CDS_GLOBAL_NET='TRUE';
NODE_NAME     C21 1
 '@SCM_LIB.SCM(SCH_1):PAGE12_I24@PURE_QUANTA.Q_CAP(CHIPS)':
 'A': CDS_PINID='A';
NODE_NAME     C23 1
 '@SCM_LIB.SCM(SCH_1):PAGE12_I28@PURE_QUANTA.Q_CAP(CHIPS)':
 'A': CDS_PINID='A';
NODE_NAME     U5 T5
 '@SCM_LIB.SCM(SCH_1):PAGE12_I436@PURE_QUANTA.AST2600A3GP(CHIPS)':
 'MVREF_T5': CDS_PINID='MVREF_T5';
NODE_NAME     U5 U5
 '@SCM_LIB.SCM(SCH_1):PAGE12_I436@PURE_QUANTA.AST2600A3GP(CHIPS)':
 'MVREF_U5': CDS_PINID='MVREF_U5';
NODE_NAME     R325 1
 '@SCM_LIB.SCM(SCH_1):PAGE20_I27@PURE_QUANTA.Q_RES(CHIPS)':
 'A': CDS_PINID='A';
NODE_NAME     R324 2
 '@SCM_LIB.SCM(SCH_1):PAGE20_I28@PURE_QUANTA.Q_RES(CHIPS)':
 'B': CDS_PINID='B';
NODE_NAME     C168 1
 '@SCM_LIB.SCM(SCH_1):PAGE20_I32@PURE_QUANTA.Q_CAP(CHIPS)':
 'A': CDS_PINID='A';
NODE_NAME     C170 1
 '@SCM_LIB.SCM(SCH_1):PAGE20_I33@PURE_QUANTA.Q_CAP(CHIPS)':
 'A': CDS_PINID='A';
NODE_NAME     C169 2
 '@SCM_LIB.SCM(SCH_1):PAGE20_I34@PURE_QUANTA.Q_CAP(CHIPS)':
 'B': CDS_PINID='B';
NODE_NAME     C10 1
 '@SCM_LIB.SCM(SCH_1):PAGE20_I85@PURE_QUANTA.Q_CAP(CHIPS)':
 'A': CDS_PINID='A';
NODE_NAME     U1 M1
 '@SCM_LIB.SCM(SCH_1):PAGE20_I196@PURE_QUANTA.K4A8G165WCBCTD(CHIPS)':
 'VREFCA': CDS_PINID='VREFCA';
NODE_NAME     C22 1
 '@SCM_LIB.SCM(SCH_1):PAGE12_I448@PURE_QUANTA.Q_CAP(CHIPS)':
 'A': CDS_PINID='A';
NET_NAME
'P12V_AUX'
 '@SCM_LIB.SCM(SCH_1):P12V_AUX':
 C_SIGNAL='@scm_lib.scm(sch_1):p12v_aux',
 CDS_GLOBAL_NET='TRUE';
NODE_NAME     GF1 OA1
 '@SCM_LIB.SCM(SCH_1):PAGE10_I553@PURE_QUANTA.FCONN168_ME1016810202011_SCM(CHIPS)':
 'P12V_AUX_OA1': CDS_PINID='P12V_AUX_OA1';
NODE_NAME     GF1 OA2
 '@SCM_LIB.SCM(SCH_1):PAGE10_I553@PURE_QUANTA.FCONN168_ME1016810202011_SCM(CHIPS)':
 'P12V_AUX_OA2': CDS_PINID='P12V_AUX_OA2';
NODE_NAME     GF1 OB1
 '@SCM_LIB.SCM(SCH_1):PAGE10_I553@PURE_QUANTA.FCONN168_ME1016810202011_SCM(CHIPS)':
 'P12V_AUX_OB1': CDS_PINID='P12V_AUX_OB1';
NODE_NAME     GF1 OB2
 '@SCM_LIB.SCM(SCH_1):PAGE10_I553@PURE_QUANTA.FCONN168_ME1016810202011_SCM(CHIPS)':
 'P12V_AUX_OB2': CDS_PINID='P12V_AUX_OB2';
NODE_NAME     R785 1
 '@SCM_LIB.SCM(SCH_1):PAGE15_I202@PURE_QUANTA.Q_RES(CHIPS)':
 'A': CDS_PINID='A';
NODE_NAME     PR521 1
 '@SCM_LIB.SCM(SCH_1):PAGE51_I4@PURE_QUANTA.Q_RES(CHIPS)':
 'A': CDS_PINID='A';
NODE_NAME     PL4 1
 '@SCM_LIB.SCM(SCH_1):PAGE51_I39@PURE_QUANTA.Q_INDUCTOR(CHIPS)':
 '1': CDS_PINID='\1\';
NODE_NAME     C241 1
 '@SCM_LIB.SCM(SCH_1):PAGE51_I52@PURE_QUANTA.Q_CAP(CHIPS)':
 'A': CDS_PINID='A';
NODE_NAME     PL19 1
 '@SCM_LIB.SCM(SCH_1):PAGE52_I32@PURE_QUANTA.Q_INDUCTOR(CHIPS)':
 '1': CDS_PINID='\1\';
NODE_NAME     C262 1
 '@SCM_LIB.SCM(SCH_1):PAGE52_I101@PURE_QUANTA.Q_CAP(CHIPS)':
 'A': CDS_PINID='A';
NODE_NAME     PL29 1
 '@SCM_LIB.SCM(SCH_1):PAGE55_I31@PURE_QUANTA.Q_INDUCTOR(CHIPS)':
 '1': CDS_PINID='\1\';
NODE_NAME     C278 1
 '@SCM_LIB.SCM(SCH_1):PAGE55_I54@PURE_QUANTA.Q_CAP(CHIPS)':
 'A': CDS_PINID='A';
NODE_NAME     PL32 1
 '@SCM_LIB.SCM(SCH_1):PAGE56_I34@PURE_QUANTA.Q_INDUCTOR(CHIPS)':
 '1': CDS_PINID='\1\';
NODE_NAME     C280 1
 '@SCM_LIB.SCM(SCH_1):PAGE56_I58@PURE_QUANTA.Q_CAP(CHIPS)':
 'A': CDS_PINID='A';
NODE_NAME     C329 1
 '@SCM_LIB.SCM(SCH_1):PAGE10_I573@PURE_QUANTA.Q_CAP(CHIPS)':
 'A': CDS_PINID='A';
NODE_NAME     C330 1
 '@SCM_LIB.SCM(SCH_1):PAGE10_I574@PURE_QUANTA.Q_CAP(CHIPS)':
 'A': CDS_PINID='A';
NODE_NAME     U56 3
 '@SCM_LIB.SCM(SCH_1):PAGE51_I56@PURE_QUANTA.AP2205W57(CHIPS)':
 'EN': CDS_PINID='EN';
NODE_NAME     U56 1
 '@SCM_LIB.SCM(SCH_1):PAGE51_I56@PURE_QUANTA.AP2205W57(CHIPS)':
 'VIN': CDS_PINID='VIN';
NODE_NAME     C226 1
 '@SCM_LIB.SCM(SCH_1):PAGE51_I60@PURE_QUANTA.Q_CAP(CHIPS)':
 'A': CDS_PINID='A';
NODE_NAME     R389 2
 '@SCM_LIB.SCM(SCH_1):PAGE50_I225@PURE_QUANTA.Q_RES(CHIPS)':
 'B': CDS_PINID='B';
NET_NAME
'P12V_SENSOR'
 '@SCM_LIB.SCM(SCH_1):P12V_SENSOR':
 C_SIGNAL='@scm_lib.scm(sch_1):p12v_sensor';
NODE_NAME     C290 1
 '@SCM_LIB.SCM(SCH_1):PAGE15_I201@PURE_QUANTA.Q_CAP(CHIPS)':
 'A': CDS_PINID='A';
NODE_NAME     R785 2
 '@SCM_LIB.SCM(SCH_1):PAGE15_I202@PURE_QUANTA.Q_RES(CHIPS)':
 'B': CDS_PINID='B';
NODE_NAME     R786 1
 '@SCM_LIB.SCM(SCH_1):PAGE15_I203@PURE_QUANTA.Q_RES(CHIPS)':
 'A': CDS_PINID='A';
NODE_NAME     U5 AD20
 '@SCM_LIB.SCM(SCH_1):PAGE15_I350@PURE_QUANTA.AST2600A3GP(CHIPS)':
 'ADC0||GPIT0': CDS_PINID='\adc0||gpit0\';
NET_NAME
'P1V0_AUX'
 '@SCM_LIB.SCM(SCH_1):P1V0_AUX':
 C_SIGNAL='@scm_lib.scm(sch_1):p1v0_aux',
 CDS_GLOBAL_NET='TRUE';
NODE_NAME     R796 1
 '@SCM_LIB.SCM(SCH_1):PAGE15_I255@PURE_QUANTA.Q_RES(CHIPS)':
 'A': CDS_PINID='A';
NODE_NAME     L8 1
 '@SCM_LIB.SCM(SCH_1):PAGE16_I29@PURE_QUANTA.Q_INDUCTOR(CHIPS)':
 '1': CDS_PINID='\1\';
NODE_NAME     C86 1
 '@SCM_LIB.SCM(SCH_1):PAGE16_I149@PURE_QUANTA.Q_CAP(CHIPS)':
 'A': CDS_PINID='A';
NODE_NAME     C92 1
 '@SCM_LIB.SCM(SCH_1):PAGE16_I150@PURE_QUANTA.Q_CAP(CHIPS)':
 'A': CDS_PINID='A';
NODE_NAME     C99 1
 '@SCM_LIB.SCM(SCH_1):PAGE16_I154@PURE_QUANTA.Q_CAP(CHIPS)':
 'A': CDS_PINID='A';
NODE_NAME     C104 1
 '@SCM_LIB.SCM(SCH_1):PAGE16_I155@PURE_QUANTA.Q_CAP(CHIPS)':
 'A': CDS_PINID='A';
NODE_NAME     C108 1
 '@SCM_LIB.SCM(SCH_1):PAGE16_I157@PURE_QUANTA.Q_CAP(CHIPS)':
 'A': CDS_PINID='A';
NODE_NAME     C118 1
 '@SCM_LIB.SCM(SCH_1):PAGE16_I162@PURE_QUANTA.Q_CAP(CHIPS)':
 'A': CDS_PINID='A';
NODE_NAME     C123 1
 '@SCM_LIB.SCM(SCH_1):PAGE16_I171@PURE_QUANTA.Q_CAP(CHIPS)':
 'A': CDS_PINID='A';
NODE_NAME     U5 L9
 '@SCM_LIB.SCM(SCH_1):PAGE16_I188@PURE_QUANTA.AST2600A3GP(CHIPS)':
 'IV10D_L9': CDS_PINID='IV10D_L9';
NODE_NAME     U5 L10
 '@SCM_LIB.SCM(SCH_1):PAGE16_I188@PURE_QUANTA.AST2600A3GP(CHIPS)':
 'IV10D_L10': CDS_PINID='IV10D_L10';
NODE_NAME     U5 M8
 '@SCM_LIB.SCM(SCH_1):PAGE16_I188@PURE_QUANTA.AST2600A3GP(CHIPS)':
 'IV10D_M8': CDS_PINID='IV10D_M8';
NODE_NAME     U5 M11
 '@SCM_LIB.SCM(SCH_1):PAGE16_I188@PURE_QUANTA.AST2600A3GP(CHIPS)':
 'IV10D_M11': CDS_PINID='IV10D_M11';
NODE_NAME     U5 N8
 '@SCM_LIB.SCM(SCH_1):PAGE16_I188@PURE_QUANTA.AST2600A3GP(CHIPS)':
 'IV10D_N8': CDS_PINID='IV10D_N8';
NODE_NAME     U5 N11
 '@SCM_LIB.SCM(SCH_1):PAGE16_I188@PURE_QUANTA.AST2600A3GP(CHIPS)':
 'IV10D_N11': CDS_PINID='IV10D_N11';
NODE_NAME     U5 P8
 '@SCM_LIB.SCM(SCH_1):PAGE16_I188@PURE_QUANTA.AST2600A3GP(CHIPS)':
 'IV10D_P8': CDS_PINID='IV10D_P8';
NODE_NAME     U5 P11
 '@SCM_LIB.SCM(SCH_1):PAGE16_I188@PURE_QUANTA.AST2600A3GP(CHIPS)':
 'IV10D_P11': CDS_PINID='IV10D_P11';
NODE_NAME     U5 R9
 '@SCM_LIB.SCM(SCH_1):PAGE16_I188@PURE_QUANTA.AST2600A3GP(CHIPS)':
 'IV10D_R9': CDS_PINID='IV10D_R9';
NODE_NAME     U5 R10
 '@SCM_LIB.SCM(SCH_1):PAGE16_I188@PURE_QUANTA.AST2600A3GP(CHIPS)':
 'IV10D_R10': CDS_PINID='IV10D_R10';
NODE_NAME     R281 1
 '@SCM_LIB.SCM(SCH_1):PAGE17_I92@PURE_QUANTA.Q_RES(CHIPS)':
 'A': CDS_PINID='A';
NODE_NAME     R279 1
 '@SCM_LIB.SCM(SCH_1):PAGE17_I95@PURE_QUANTA.Q_RES(CHIPS)':
 'A': CDS_PINID='A';
NODE_NAME     L6 1
 '@SCM_LIB.SCM(SCH_1):PAGE17_I124@PURE_QUANTA.Q_INDUCTOR(CHIPS)':
 '1': CDS_PINID='\1\';
NODE_NAME     L13 1
 '@SCM_LIB.SCM(SCH_1):PAGE17_I158@PURE_QUANTA.Q_INDUCTOR(CHIPS)':
 '1': CDS_PINID='\1\';
NODE_NAME     L15 1
 '@SCM_LIB.SCM(SCH_1):PAGE17_I170@PURE_QUANTA.Q_INDUCTOR(CHIPS)':
 '1': CDS_PINID='\1\';
NODE_NAME     PU42 12
 '@SCM_LIB.SCM(SCH_1):PAGE56_I15@PURE_QUANTA.NB695GDZ(CHIPS)':
 'VOUT': CDS_PINID='VOUT';
NODE_NAME     PC266 1
 '@SCM_LIB.SCM(SCH_1):PAGE56_I23@PURE_QUANTA.Q_CAP(CHIPS)':
 'A': CDS_PINID='A';
NODE_NAME     PC267 1
 '@SCM_LIB.SCM(SCH_1):PAGE56_I24@PURE_QUANTA.Q_CAP(CHIPS)':
 'A': CDS_PINID='A';
NODE_NAME     PC268 1
 '@SCM_LIB.SCM(SCH_1):PAGE56_I25@PURE_QUANTA.Q_CAP(CHIPS)':
 'A': CDS_PINID='A';
NODE_NAME     PC269 1
 '@SCM_LIB.SCM(SCH_1):PAGE56_I28@PURE_QUANTA.Q_CAP(CHIPS)':
 'A': CDS_PINID='A';
NODE_NAME     PC270 1
 '@SCM_LIB.SCM(SCH_1):PAGE56_I29@PURE_QUANTA.Q_CAP(CHIPS)':
 'A': CDS_PINID='A';
NODE_NAME     PL33 2
 '@SCM_LIB.SCM(SCH_1):PAGE56_I37@PURE_QUANTA.Q_INDUCTOR(CHIPS)':
 '2': CDS_PINID='\2\';
NODE_NAME     U43 5
 '@SCM_LIB.SCM(SCH_1):PAGE22_I90@PURE_QUANTA.TPS3808G18DBVR(CHIPS)':
 'SENSE': CDS_PINID='SENSE';
NODE_NAME     C113 1
 '@SCM_LIB.SCM(SCH_1):PAGE16_I189@PURE_QUANTA.Q_CAP(CHIPS)':
 'A': CDS_PINID='A';
NET_NAME
'P1V0_AUX_MODE'
 '@SCM_LIB.SCM(SCH_1):P1V0_AUX_MODE':
 C_SIGNAL='@scm_lib.scm(sch_1):p1v0_aux_mode';
NODE_NAME     PU42 7
 '@SCM_LIB.SCM(SCH_1):PAGE56_I15@PURE_QUANTA.NB695GDZ(CHIPS)':
 'MODE': CDS_PINID='MODE';
NODE_NAME     PR543 1
 '@SCM_LIB.SCM(SCH_1):PAGE56_I71@PURE_QUANTA.Q_RES(CHIPS)':
 'A': CDS_PINID='A';
NET_NAME
'P1V0_AUX_VCC'
 '@SCM_LIB.SCM(SCH_1):P1V0_AUX_VCC':
 C_SIGNAL='@scm_lib.scm(sch_1):p1v0_aux_vcc';
NODE_NAME     PC260 1
 '@SCM_LIB.SCM(SCH_1):PAGE56_I7@PURE_QUANTA.Q_CAP(CHIPS)':
 'A': CDS_PINID='A';
NODE_NAME     PR541 2
 '@SCM_LIB.SCM(SCH_1):PAGE56_I8@PURE_QUANTA.Q_RES(CHIPS)':
 'B': CDS_PINID='B';
NODE_NAME     PU42 10
 '@SCM_LIB.SCM(SCH_1):PAGE56_I15@PURE_QUANTA.NB695GDZ(CHIPS)':
 '3V3': CDS_PINID='\3v3\';
NODE_NAME     PU42 3
 '@SCM_LIB.SCM(SCH_1):PAGE56_I15@PURE_QUANTA.NB695GDZ(CHIPS)':
 'C1': CDS_PINID='C1';
NODE_NAME     PU42 6
 '@SCM_LIB.SCM(SCH_1):PAGE56_I15@PURE_QUANTA.NB695GDZ(CHIPS)':
 'LP#': CDS_PINID='\lp#\';
NET_NAME
'P1V0_SENSOR'
 '@SCM_LIB.SCM(SCH_1):P1V0_SENSOR':
 C_SIGNAL='@scm_lib.scm(sch_1):p1v0_sensor';
NODE_NAME     R796 2
 '@SCM_LIB.SCM(SCH_1):PAGE15_I255@PURE_QUANTA.Q_RES(CHIPS)':
 'B': CDS_PINID='B';
NODE_NAME     C311 1
 '@SCM_LIB.SCM(SCH_1):PAGE15_I256@PURE_QUANTA.Q_CAP(CHIPS)':
 'A': CDS_PINID='A';
NODE_NAME     U5 AB17
 '@SCM_LIB.SCM(SCH_1):PAGE15_I350@PURE_QUANTA.AST2600A3GP(CHIPS)':
 'ADC10||GPIU2||SALT11': CDS_PINID='\adc10||gpiu2||salt11\';
NET_NAME
'P1V0_STBY_DP_VCC10A'
 '@SCM_LIB.SCM(SCH_1):P1V0_STBY_DP_VCC10A':
 C_SIGNAL='@scm_lib.scm(sch_1):p1v0_stby_dp_vcc10a';
NODE_NAME     U5 T8
 '@SCM_LIB.SCM(SCH_1):PAGE16_I188@PURE_QUANTA.AST2600A3GP(CHIPS)':
 'DP_VCC10A': CDS_PINID='DP_VCC10A';
NODE_NAME     C97 1
 '@SCM_LIB.SCM(SCH_1):PAGE17_I169@PURE_QUANTA.Q_CAP(CHIPS)':
 'A': CDS_PINID='A';
NODE_NAME     L15 2
 '@SCM_LIB.SCM(SCH_1):PAGE17_I170@PURE_QUANTA.Q_INDUCTOR(CHIPS)':
 '2': CDS_PINID='\2\';
NODE_NAME     C90 1
 '@SCM_LIB.SCM(SCH_1):PAGE17_I173@PURE_QUANTA.Q_CAP(CHIPS)':
 'A': CDS_PINID='A';
NET_NAME
'P1V0_STBY_PE_VCC10A'
 '@SCM_LIB.SCM(SCH_1):P1V0_STBY_PE_VCC10A':
 C_SIGNAL='@scm_lib.scm(sch_1):p1v0_stby_pe_vcc10a';
NODE_NAME     U5 T9
 '@SCM_LIB.SCM(SCH_1):PAGE16_I188@PURE_QUANTA.AST2600A3GP(CHIPS)':
 'RC_VCC10A': CDS_PINID='RC_VCC10A';
NODE_NAME     C79 1
 '@SCM_LIB.SCM(SCH_1):PAGE17_I157@PURE_QUANTA.Q_CAP(CHIPS)':
 'A': CDS_PINID='A';
NODE_NAME     L13 2
 '@SCM_LIB.SCM(SCH_1):PAGE17_I158@PURE_QUANTA.Q_INDUCTOR(CHIPS)':
 '2': CDS_PINID='\2\';
NODE_NAME     C78 1
 '@SCM_LIB.SCM(SCH_1):PAGE17_I160@PURE_QUANTA.Q_CAP(CHIPS)':
 'A': CDS_PINID='A';
NET_NAME
'P1V0_STBY_PLAVDD'
 '@SCM_LIB.SCM(SCH_1):P1V0_STBY_PLAVDD':
 C_SIGNAL='@scm_lib.scm(sch_1):p1v0_stby_plavdd';
NODE_NAME     L8 2
 '@SCM_LIB.SCM(SCH_1):PAGE16_I29@PURE_QUANTA.Q_INDUCTOR(CHIPS)':
 '2': CDS_PINID='\2\';
NODE_NAME     C52 1
 '@SCM_LIB.SCM(SCH_1):PAGE16_I31@PURE_QUANTA.Q_CAP(CHIPS)':
 'A': CDS_PINID='A';
NODE_NAME     C54 1
 '@SCM_LIB.SCM(SCH_1):PAGE16_I32@PURE_QUANTA.Q_CAP(CHIPS)':
 'A': CDS_PINID='A';
NODE_NAME     C56 1
 '@SCM_LIB.SCM(SCH_1):PAGE16_I33@PURE_QUANTA.Q_CAP(CHIPS)':
 'A': CDS_PINID='A';
NODE_NAME     C59 1
 '@SCM_LIB.SCM(SCH_1):PAGE16_I79@PURE_QUANTA.Q_CAP(CHIPS)':
 'A': CDS_PINID='A';
NODE_NAME     C64 1
 '@SCM_LIB.SCM(SCH_1):PAGE16_I81@PURE_QUANTA.Q_CAP(CHIPS)':
 'A': CDS_PINID='A';
NODE_NAME     C68 1
 '@SCM_LIB.SCM(SCH_1):PAGE16_I82@PURE_QUANTA.Q_CAP(CHIPS)':
 'A': CDS_PINID='A';
NODE_NAME     U5 J9
 '@SCM_LIB.SCM(SCH_1):PAGE16_I188@PURE_QUANTA.AST2600A3GP(CHIPS)':
 'DPLLAVDD': CDS_PINID='DPLLAVDD';
NODE_NAME     U5 E7
 '@SCM_LIB.SCM(SCH_1):PAGE16_I188@PURE_QUANTA.AST2600A3GP(CHIPS)':
 'PLLAVDD_E7': CDS_PINID='PLLAVDD_E7';
NODE_NAME     U5 F7
 '@SCM_LIB.SCM(SCH_1):PAGE16_I188@PURE_QUANTA.AST2600A3GP(CHIPS)':
 'PLLAVDD_F7': CDS_PINID='PLLAVDD_F7';
NODE_NAME     U5 E9
 '@SCM_LIB.SCM(SCH_1):PAGE16_I188@PURE_QUANTA.AST2600A3GP(CHIPS)':
 'PLLDVDD_E9': CDS_PINID='PLLDVDD_E9';
NODE_NAME     U5 F9
 '@SCM_LIB.SCM(SCH_1):PAGE16_I188@PURE_QUANTA.AST2600A3GP(CHIPS)':
 'PLLDVDD_F9': CDS_PINID='PLLDVDD_F9';
NET_NAME
'P1V0_STBY_RC_VCC10A'
 '@SCM_LIB.SCM(SCH_1):P1V0_STBY_RC_VCC10A':
 C_SIGNAL='@scm_lib.scm(sch_1):p1v0_stby_rc_vcc10a';
NODE_NAME     U5 T10
 '@SCM_LIB.SCM(SCH_1):PAGE16_I188@PURE_QUANTA.AST2600A3GP(CHIPS)':
 'PE_VCC10A': CDS_PINID='PE_VCC10A';
NODE_NAME     L6 2
 '@SCM_LIB.SCM(SCH_1):PAGE17_I124@PURE_QUANTA.Q_INDUCTOR(CHIPS)':
 '2': CDS_PINID='\2\';
NODE_NAME     C50 1
 '@SCM_LIB.SCM(SCH_1):PAGE17_I126@PURE_QUANTA.Q_CAP(CHIPS)':
 'A': CDS_PINID='A';
NODE_NAME     C47 1
 '@SCM_LIB.SCM(SCH_1):PAGE17_I128@PURE_QUANTA.Q_CAP(CHIPS)':
 'A': CDS_PINID='A';
NET_NAME
'P1V2_AUX'
 '@SCM_LIB.SCM(SCH_1):P1V2_AUX':
 C_SIGNAL='@scm_lib.scm(sch_1):p1v2_aux',
 CDS_GLOBAL_NET='TRUE';
NODE_NAME     R795 1
 '@SCM_LIB.SCM(SCH_1):PAGE15_I252@PURE_QUANTA.Q_RES(CHIPS)':
 'A': CDS_PINID='A';
NODE_NAME     C55 1
 '@SCM_LIB.SCM(SCH_1):PAGE16_I23@PURE_QUANTA.Q_CAP(CHIPS)':
 'A': CDS_PINID='A';
NODE_NAME     L11 1
 '@SCM_LIB.SCM(SCH_1):PAGE16_I47@PURE_QUANTA.Q_INDUCTOR(CHIPS)':
 '1': CDS_PINID='\1\';
NODE_NAME     C58 1
 '@SCM_LIB.SCM(SCH_1):PAGE16_I52@PURE_QUANTA.Q_CAP(CHIPS)':
 'A': CDS_PINID='A';
NODE_NAME     C62 1
 '@SCM_LIB.SCM(SCH_1):PAGE16_I53@PURE_QUANTA.Q_CAP(CHIPS)':
 'A': CDS_PINID='A';
NODE_NAME     C66 1
 '@SCM_LIB.SCM(SCH_1):PAGE16_I54@PURE_QUANTA.Q_CAP(CHIPS)':
 'A': CDS_PINID='A';
NODE_NAME     C70 1
 '@SCM_LIB.SCM(SCH_1):PAGE16_I57@PURE_QUANTA.Q_CAP(CHIPS)':
 'A': CDS_PINID='A';
NODE_NAME     C72 1
 '@SCM_LIB.SCM(SCH_1):PAGE16_I58@PURE_QUANTA.Q_CAP(CHIPS)':
 'A': CDS_PINID='A';
NODE_NAME     C74 1
 '@SCM_LIB.SCM(SCH_1):PAGE16_I66@PURE_QUANTA.Q_CAP(CHIPS)':
 'A': CDS_PINID='A';
NODE_NAME     C91 1
 '@SCM_LIB.SCM(SCH_1):PAGE16_I151@PURE_QUANTA.Q_CAP(CHIPS)':
 'A': CDS_PINID='A';
NODE_NAME     C98 1
 '@SCM_LIB.SCM(SCH_1):PAGE16_I163@PURE_QUANTA.Q_CAP(CHIPS)':
 'A': CDS_PINID='A';
NODE_NAME     C103 1
 '@SCM_LIB.SCM(SCH_1):PAGE16_I164@PURE_QUANTA.Q_CAP(CHIPS)':
 'A': CDS_PINID='A';
NODE_NAME     C107 1
 '@SCM_LIB.SCM(SCH_1):PAGE16_I165@PURE_QUANTA.Q_CAP(CHIPS)':
 'A': CDS_PINID='A';
NODE_NAME     C112 1
 '@SCM_LIB.SCM(SCH_1):PAGE16_I166@PURE_QUANTA.Q_CAP(CHIPS)':
 'A': CDS_PINID='A';
NODE_NAME     C117 1
 '@SCM_LIB.SCM(SCH_1):PAGE16_I167@PURE_QUANTA.Q_CAP(CHIPS)':
 'A': CDS_PINID='A';
NODE_NAME     C122 1
 '@SCM_LIB.SCM(SCH_1):PAGE16_I168@PURE_QUANTA.Q_CAP(CHIPS)':
 'A': CDS_PINID='A';
NODE_NAME     C127 1
 '@SCM_LIB.SCM(SCH_1):PAGE16_I173@PURE_QUANTA.Q_CAP(CHIPS)':
 'A': CDS_PINID='A';
NODE_NAME     C129 1
 '@SCM_LIB.SCM(SCH_1):PAGE16_I174@PURE_QUANTA.Q_CAP(CHIPS)':
 'A': CDS_PINID='A';
NODE_NAME     C84 1
 '@SCM_LIB.SCM(SCH_1):PAGE16_I179@PURE_QUANTA.Q_CAP(CHIPS)':
 'A': CDS_PINID='A';
NODE_NAME     C82 1
 '@SCM_LIB.SCM(SCH_1):PAGE16_I180@PURE_QUANTA.Q_CAP(CHIPS)':
 'A': CDS_PINID='A';
NODE_NAME     C76 1
 '@SCM_LIB.SCM(SCH_1):PAGE16_I183@PURE_QUANTA.Q_CAP(CHIPS)':
 'A': CDS_PINID='A';
NODE_NAME     U5 K16
 '@SCM_LIB.SCM(SCH_1):PAGE16_I188@PURE_QUANTA.AST2600A3GP(CHIPS)':
 'IV12D_K16': CDS_PINID='IV12D_K16';
NODE_NAME     U5 K17
 '@SCM_LIB.SCM(SCH_1):PAGE16_I188@PURE_QUANTA.AST2600A3GP(CHIPS)':
 'IV12D_K17': CDS_PINID='IV12D_K17';
NODE_NAME     U5 K18
 '@SCM_LIB.SCM(SCH_1):PAGE16_I188@PURE_QUANTA.AST2600A3GP(CHIPS)':
 'IV12D_K18': CDS_PINID='IV12D_K18';
NODE_NAME     U5 K19
 '@SCM_LIB.SCM(SCH_1):PAGE16_I188@PURE_QUANTA.AST2600A3GP(CHIPS)':
 'IV12D_K19': CDS_PINID='IV12D_K19';
NODE_NAME     U5 L14
 '@SCM_LIB.SCM(SCH_1):PAGE16_I188@PURE_QUANTA.AST2600A3GP(CHIPS)':
 'IV12D_L14': CDS_PINID='IV12D_L14';
NODE_NAME     U5 L21
 '@SCM_LIB.SCM(SCH_1):PAGE16_I188@PURE_QUANTA.AST2600A3GP(CHIPS)':
 'IV12D_L21': CDS_PINID='IV12D_L21';
NODE_NAME     U5 M14
 '@SCM_LIB.SCM(SCH_1):PAGE16_I188@PURE_QUANTA.AST2600A3GP(CHIPS)':
 'IV12D_M14': CDS_PINID='IV12D_M14';
NODE_NAME     U5 M21
 '@SCM_LIB.SCM(SCH_1):PAGE16_I188@PURE_QUANTA.AST2600A3GP(CHIPS)':
 'IV12D_M21': CDS_PINID='IV12D_M21';
NODE_NAME     U5 N14
 '@SCM_LIB.SCM(SCH_1):PAGE16_I188@PURE_QUANTA.AST2600A3GP(CHIPS)':
 'IV12D_N14': CDS_PINID='IV12D_N14';
NODE_NAME     U5 N21
 '@SCM_LIB.SCM(SCH_1):PAGE16_I188@PURE_QUANTA.AST2600A3GP(CHIPS)':
 'IV12D_N21': CDS_PINID='IV12D_N21';
NODE_NAME     U5 P14
 '@SCM_LIB.SCM(SCH_1):PAGE16_I188@PURE_QUANTA.AST2600A3GP(CHIPS)':
 'IV12D_P14': CDS_PINID='IV12D_P14';
NODE_NAME     U5 P21
 '@SCM_LIB.SCM(SCH_1):PAGE16_I188@PURE_QUANTA.AST2600A3GP(CHIPS)':
 'IV12D_P21': CDS_PINID='IV12D_P21';
NODE_NAME     U5 R14
 '@SCM_LIB.SCM(SCH_1):PAGE16_I188@PURE_QUANTA.AST2600A3GP(CHIPS)':
 'IV12D_R14': CDS_PINID='IV12D_R14';
NODE_NAME     U5 R21
 '@SCM_LIB.SCM(SCH_1):PAGE16_I188@PURE_QUANTA.AST2600A3GP(CHIPS)':
 'IV12D_R21': CDS_PINID='IV12D_R21';
NODE_NAME     U5 T14
 '@SCM_LIB.SCM(SCH_1):PAGE16_I188@PURE_QUANTA.AST2600A3GP(CHIPS)':
 'IV12D_T14': CDS_PINID='IV12D_T14';
NODE_NAME     U5 T21
 '@SCM_LIB.SCM(SCH_1):PAGE16_I188@PURE_QUANTA.AST2600A3GP(CHIPS)':
 'IV12D_T21': CDS_PINID='IV12D_T21';
NODE_NAME     U5 U15
 '@SCM_LIB.SCM(SCH_1):PAGE16_I188@PURE_QUANTA.AST2600A3GP(CHIPS)':
 'IV12D_U15': CDS_PINID='IV12D_U15';
NODE_NAME     U5 U16
 '@SCM_LIB.SCM(SCH_1):PAGE16_I188@PURE_QUANTA.AST2600A3GP(CHIPS)':
 'IV12D_U16': CDS_PINID='IV12D_U16';
NODE_NAME     U5 U17
 '@SCM_LIB.SCM(SCH_1):PAGE16_I188@PURE_QUANTA.AST2600A3GP(CHIPS)':
 'IV12D_U17': CDS_PINID='IV12D_U17';
NODE_NAME     U5 U18
 '@SCM_LIB.SCM(SCH_1):PAGE16_I188@PURE_QUANTA.AST2600A3GP(CHIPS)':
 'IV12D_U18': CDS_PINID='IV12D_U18';
NODE_NAME     U5 G6
 '@SCM_LIB.SCM(SCH_1):PAGE16_I188@PURE_QUANTA.AST2600A3GP(CHIPS)':
 'MVDD_G6': CDS_PINID='MVDD_G6';
NODE_NAME     U5 H6
 '@SCM_LIB.SCM(SCH_1):PAGE16_I188@PURE_QUANTA.AST2600A3GP(CHIPS)':
 'MVDD_H6': CDS_PINID='MVDD_H6';
NODE_NAME     U5 J6
 '@SCM_LIB.SCM(SCH_1):PAGE16_I188@PURE_QUANTA.AST2600A3GP(CHIPS)':
 'MVDD_J6': CDS_PINID='MVDD_J6';
NODE_NAME     U5 K6
 '@SCM_LIB.SCM(SCH_1):PAGE16_I188@PURE_QUANTA.AST2600A3GP(CHIPS)':
 'MVDD_K6': CDS_PINID='MVDD_K6';
NODE_NAME     U5 L6
 '@SCM_LIB.SCM(SCH_1):PAGE16_I188@PURE_QUANTA.AST2600A3GP(CHIPS)':
 'MVDD_L6': CDS_PINID='MVDD_L6';
NODE_NAME     U5 P6
 '@SCM_LIB.SCM(SCH_1):PAGE16_I188@PURE_QUANTA.AST2600A3GP(CHIPS)':
 'MVDD_P6': CDS_PINID='MVDD_P6';
NODE_NAME     U5 R6
 '@SCM_LIB.SCM(SCH_1):PAGE16_I188@PURE_QUANTA.AST2600A3GP(CHIPS)':
 'MVDD_R6': CDS_PINID='MVDD_R6';
NODE_NAME     U5 T6
 '@SCM_LIB.SCM(SCH_1):PAGE16_I188@PURE_QUANTA.AST2600A3GP(CHIPS)':
 'MVDD_T6': CDS_PINID='MVDD_T6';
NODE_NAME     R280 1
 '@SCM_LIB.SCM(SCH_1):PAGE17_I94@PURE_QUANTA.Q_RES(CHIPS)':
 'A': CDS_PINID='A';
NODE_NAME     R278 1
 '@SCM_LIB.SCM(SCH_1):PAGE17_I101@PURE_QUANTA.Q_RES(CHIPS)':
 'A': CDS_PINID='A';
NODE_NAME     R782 1
 '@SCM_LIB.SCM(SCH_1):PAGE17_I264@PURE_QUANTA.Q_RES(CHIPS)':
 'A': CDS_PINID='A';
NODE_NAME     R784 1
 '@SCM_LIB.SCM(SCH_1):PAGE17_I267@PURE_QUANTA.Q_RES(CHIPS)':
 'A': CDS_PINID='A';
NODE_NAME     L2 1
 '@SCM_LIB.SCM(SCH_1):PAGE17_I272@PURE_QUANTA.Q_INDUCTOR(CHIPS)':
 '1': CDS_PINID='\1\';
NODE_NAME     C1 1
 '@SCM_LIB.SCM(SCH_1):PAGE20_I4@PURE_QUANTA.Q_CAP(CHIPS)':
 'A': CDS_PINID='A';
NODE_NAME     C2 1
 '@SCM_LIB.SCM(SCH_1):PAGE20_I5@PURE_QUANTA.Q_CAP(CHIPS)':
 'A': CDS_PINID='A';
NODE_NAME     C3 1
 '@SCM_LIB.SCM(SCH_1):PAGE20_I6@PURE_QUANTA.Q_CAP(CHIPS)':
 'A': CDS_PINID='A';
NODE_NAME     C4 1
 '@SCM_LIB.SCM(SCH_1):PAGE20_I7@PURE_QUANTA.Q_CAP(CHIPS)':
 'A': CDS_PINID='A';
NODE_NAME     C5 1
 '@SCM_LIB.SCM(SCH_1):PAGE20_I23@PURE_QUANTA.Q_CAP(CHIPS)':
 'A': CDS_PINID='A';
NODE_NAME     C7 1
 '@SCM_LIB.SCM(SCH_1):PAGE20_I24@PURE_QUANTA.Q_CAP(CHIPS)':
 'A': CDS_PINID='A';
NODE_NAME     C9 1
 '@SCM_LIB.SCM(SCH_1):PAGE20_I25@PURE_QUANTA.Q_CAP(CHIPS)':
 'A': CDS_PINID='A';
NODE_NAME     R324 1
 '@SCM_LIB.SCM(SCH_1):PAGE20_I28@PURE_QUANTA.Q_RES(CHIPS)':
 'A': CDS_PINID='A';
NODE_NAME     C169 1
 '@SCM_LIB.SCM(SCH_1):PAGE20_I34@PURE_QUANTA.Q_CAP(CHIPS)':
 'A': CDS_PINID='A';
NODE_NAME     C229 2
 '@SCM_LIB.SCM(SCH_1):PAGE20_I107@PURE_QUANTA.Q_CAP(CHIPS)':
 'B': CDS_PINID='B';
NODE_NAME     R9 2
 '@SCM_LIB.SCM(SCH_1):PAGE20_I111@PURE_QUANTA.Q_RES(CHIPS)':
 'B': CDS_PINID='B';
NODE_NAME     C16 1
 '@SCM_LIB.SCM(SCH_1):PAGE20_I113@PURE_QUANTA.Q_CAP(CHIPS)':
 'A': CDS_PINID='A';
NODE_NAME     R375 2
 '@SCM_LIB.SCM(SCH_1):PAGE20_I115@PURE_QUANTA.Q_RES(CHIPS)':
 'B': CDS_PINID='B';
NODE_NAME     R374 2
 '@SCM_LIB.SCM(SCH_1):PAGE20_I127@PURE_QUANTA.Q_RES(CHIPS)':
 'B': CDS_PINID='B';
NODE_NAME     R373 2
 '@SCM_LIB.SCM(SCH_1):PAGE20_I128@PURE_QUANTA.Q_RES(CHIPS)':
 'B': CDS_PINID='B';
NODE_NAME     R372 2
 '@SCM_LIB.SCM(SCH_1):PAGE20_I129@PURE_QUANTA.Q_RES(CHIPS)':
 'B': CDS_PINID='B';
NODE_NAME     R371 2
 '@SCM_LIB.SCM(SCH_1):PAGE20_I130@PURE_QUANTA.Q_RES(CHIPS)':
 'B': CDS_PINID='B';
NODE_NAME     R370 2
 '@SCM_LIB.SCM(SCH_1):PAGE20_I131@PURE_QUANTA.Q_RES(CHIPS)':
 'B': CDS_PINID='B';
NODE_NAME     R369 2
 '@SCM_LIB.SCM(SCH_1):PAGE20_I132@PURE_QUANTA.Q_RES(CHIPS)':
 'B': CDS_PINID='B';
NODE_NAME     C15 1
 '@SCM_LIB.SCM(SCH_1):PAGE20_I134@PURE_QUANTA.Q_CAP(CHIPS)':
 'A': CDS_PINID='A';
NODE_NAME     R368 2
 '@SCM_LIB.SCM(SCH_1):PAGE20_I135@PURE_QUANTA.Q_RES(CHIPS)':
 'B': CDS_PINID='B';
NODE_NAME     R367 2
 '@SCM_LIB.SCM(SCH_1):PAGE20_I136@PURE_QUANTA.Q_RES(CHIPS)':
 'B': CDS_PINID='B';
NODE_NAME     R366 2
 '@SCM_LIB.SCM(SCH_1):PAGE20_I137@PURE_QUANTA.Q_RES(CHIPS)':
 'B': CDS_PINID='B';
NODE_NAME     R365 2
 '@SCM_LIB.SCM(SCH_1):PAGE20_I138@PURE_QUANTA.Q_RES(CHIPS)':
 'B': CDS_PINID='B';
NODE_NAME     R364 2
 '@SCM_LIB.SCM(SCH_1):PAGE20_I165@PURE_QUANTA.Q_RES(CHIPS)':
 'B': CDS_PINID='B';
NODE_NAME     R363 2
 '@SCM_LIB.SCM(SCH_1):PAGE20_I166@PURE_QUANTA.Q_RES(CHIPS)':
 'B': CDS_PINID='B';
NODE_NAME     R361 2
 '@SCM_LIB.SCM(SCH_1):PAGE20_I167@PURE_QUANTA.Q_RES(CHIPS)':
 'B': CDS_PINID='B';
NODE_NAME     R362 2
 '@SCM_LIB.SCM(SCH_1):PAGE20_I168@PURE_QUANTA.Q_RES(CHIPS)':
 'B': CDS_PINID='B';
NODE_NAME     R360 2
 '@SCM_LIB.SCM(SCH_1):PAGE20_I169@PURE_QUANTA.Q_RES(CHIPS)':
 'B': CDS_PINID='B';
NODE_NAME     R359 2
 '@SCM_LIB.SCM(SCH_1):PAGE20_I170@PURE_QUANTA.Q_RES(CHIPS)':
 'B': CDS_PINID='B';
NODE_NAME     R358 2
 '@SCM_LIB.SCM(SCH_1):PAGE20_I178@PURE_QUANTA.Q_RES(CHIPS)':
 'B': CDS_PINID='B';
NODE_NAME     R357 2
 '@SCM_LIB.SCM(SCH_1):PAGE20_I179@PURE_QUANTA.Q_RES(CHIPS)':
 'B': CDS_PINID='B';
NODE_NAME     R356 2
 '@SCM_LIB.SCM(SCH_1):PAGE20_I180@PURE_QUANTA.Q_RES(CHIPS)':
 'B': CDS_PINID='B';
NODE_NAME     R354 2
 '@SCM_LIB.SCM(SCH_1):PAGE20_I181@PURE_QUANTA.Q_RES(CHIPS)':
 'B': CDS_PINID='B';
NODE_NAME     R355 2
 '@SCM_LIB.SCM(SCH_1):PAGE20_I182@PURE_QUANTA.Q_RES(CHIPS)':
 'B': CDS_PINID='B';
NODE_NAME     R353 2
 '@SCM_LIB.SCM(SCH_1):PAGE20_I183@PURE_QUANTA.Q_RES(CHIPS)':
 'B': CDS_PINID='B';
NODE_NAME     R352 2
 '@SCM_LIB.SCM(SCH_1):PAGE20_I184@PURE_QUANTA.Q_RES(CHIPS)':
 'B': CDS_PINID='B';
NODE_NAME     C13 1
 '@SCM_LIB.SCM(SCH_1):PAGE20_I186@PURE_QUANTA.Q_CAP(CHIPS)':
 'A': CDS_PINID='A';
NODE_NAME     C14 1
 '@SCM_LIB.SCM(SCH_1):PAGE20_I187@PURE_QUANTA.Q_CAP(CHIPS)':
 'A': CDS_PINID='A';
NODE_NAME     C17 1
 '@SCM_LIB.SCM(SCH_1):PAGE20_I190@PURE_QUANTA.Q_CAP(CHIPS)':
 'A': CDS_PINID='A';
NODE_NAME     C18 1
 '@SCM_LIB.SCM(SCH_1):PAGE20_I192@PURE_QUANTA.Q_CAP(CHIPS)':
 'A': CDS_PINID='A';
NODE_NAME     R351 2
 '@SCM_LIB.SCM(SCH_1):PAGE20_I194@PURE_QUANTA.Q_RES(CHIPS)':
 'B': CDS_PINID='B';
NODE_NAME     U1 B3
 '@SCM_LIB.SCM(SCH_1):PAGE20_I196@PURE_QUANTA.K4A8G165WCBCTD(CHIPS)':
 'VDD0': CDS_PINID='VDD0';
NODE_NAME     U1 B9
 '@SCM_LIB.SCM(SCH_1):PAGE20_I196@PURE_QUANTA.K4A8G165WCBCTD(CHIPS)':
 'VDD1': CDS_PINID='VDD1';
NODE_NAME     U1 D1
 '@SCM_LIB.SCM(SCH_1):PAGE20_I196@PURE_QUANTA.K4A8G165WCBCTD(CHIPS)':
 'VDD2': CDS_PINID='VDD2';
NODE_NAME     U1 G7
 '@SCM_LIB.SCM(SCH_1):PAGE20_I196@PURE_QUANTA.K4A8G165WCBCTD(CHIPS)':
 'VDD3': CDS_PINID='VDD3';
NODE_NAME     U1 J1
 '@SCM_LIB.SCM(SCH_1):PAGE20_I196@PURE_QUANTA.K4A8G165WCBCTD(CHIPS)':
 'VDD4': CDS_PINID='VDD4';
NODE_NAME     U1 J9
 '@SCM_LIB.SCM(SCH_1):PAGE20_I196@PURE_QUANTA.K4A8G165WCBCTD(CHIPS)':
 'VDD5': CDS_PINID='VDD5';
NODE_NAME     U1 L1
 '@SCM_LIB.SCM(SCH_1):PAGE20_I196@PURE_QUANTA.K4A8G165WCBCTD(CHIPS)':
 'VDD6': CDS_PINID='VDD6';
NODE_NAME     U1 L9
 '@SCM_LIB.SCM(SCH_1):PAGE20_I196@PURE_QUANTA.K4A8G165WCBCTD(CHIPS)':
 'VDD7': CDS_PINID='VDD7';
NODE_NAME     U1 R1
 '@SCM_LIB.SCM(SCH_1):PAGE20_I196@PURE_QUANTA.K4A8G165WCBCTD(CHIPS)':
 'VDD8': CDS_PINID='VDD8';
NODE_NAME     U1 T9
 '@SCM_LIB.SCM(SCH_1):PAGE20_I196@PURE_QUANTA.K4A8G165WCBCTD(CHIPS)':
 'VDD9': CDS_PINID='VDD9';
NODE_NAME     U1 A1
 '@SCM_LIB.SCM(SCH_1):PAGE20_I196@PURE_QUANTA.K4A8G165WCBCTD(CHIPS)':
 'VDDQ0': CDS_PINID='VDDQ0';
NODE_NAME     U1 A9
 '@SCM_LIB.SCM(SCH_1):PAGE20_I196@PURE_QUANTA.K4A8G165WCBCTD(CHIPS)':
 'VDDQ1': CDS_PINID='VDDQ1';
NODE_NAME     U1 C1
 '@SCM_LIB.SCM(SCH_1):PAGE20_I196@PURE_QUANTA.K4A8G165WCBCTD(CHIPS)':
 'VDDQ2': CDS_PINID='VDDQ2';
NODE_NAME     U1 D9
 '@SCM_LIB.SCM(SCH_1):PAGE20_I196@PURE_QUANTA.K4A8G165WCBCTD(CHIPS)':
 'VDDQ3': CDS_PINID='VDDQ3';
NODE_NAME     U1 F2
 '@SCM_LIB.SCM(SCH_1):PAGE20_I196@PURE_QUANTA.K4A8G165WCBCTD(CHIPS)':
 'VDDQ4': CDS_PINID='VDDQ4';
NODE_NAME     U1 F8
 '@SCM_LIB.SCM(SCH_1):PAGE20_I196@PURE_QUANTA.K4A8G165WCBCTD(CHIPS)':
 'VDDQ5': CDS_PINID='VDDQ5';
NODE_NAME     U1 G1
 '@SCM_LIB.SCM(SCH_1):PAGE20_I196@PURE_QUANTA.K4A8G165WCBCTD(CHIPS)':
 'VDDQ6': CDS_PINID='VDDQ6';
NODE_NAME     U1 G9
 '@SCM_LIB.SCM(SCH_1):PAGE20_I196@PURE_QUANTA.K4A8G165WCBCTD(CHIPS)':
 'VDDQ7': CDS_PINID='VDDQ7';
NODE_NAME     U1 J2
 '@SCM_LIB.SCM(SCH_1):PAGE20_I196@PURE_QUANTA.K4A8G165WCBCTD(CHIPS)':
 'VDDQ8': CDS_PINID='VDDQ8';
NODE_NAME     U1 J8
 '@SCM_LIB.SCM(SCH_1):PAGE20_I196@PURE_QUANTA.K4A8G165WCBCTD(CHIPS)':
 'VDDQ9': CDS_PINID='VDDQ9';
NODE_NAME     C225 1
 '@SCM_LIB.SCM(SCH_1):PAGE20_I197@PURE_QUANTA.Q_CAP(CHIPS)':
 'A': CDS_PINID='A';
NODE_NAME     C222 1
 '@SCM_LIB.SCM(SCH_1):PAGE20_I198@PURE_QUANTA.Q_CAP(CHIPS)':
 'A': CDS_PINID='A';
NODE_NAME     C221 1
 '@SCM_LIB.SCM(SCH_1):PAGE20_I199@PURE_QUANTA.Q_CAP(CHIPS)':
 'A': CDS_PINID='A';
NODE_NAME     PU41 12
 '@SCM_LIB.SCM(SCH_1):PAGE55_I15@PURE_QUANTA.NB695GDZ(CHIPS)':
 'VOUT': CDS_PINID='VOUT';
NODE_NAME     PL31 2
 '@SCM_LIB.SCM(SCH_1):PAGE55_I21@PURE_QUANTA.Q_INDUCTOR(CHIPS)':
 '2': CDS_PINID='\2\';
NODE_NAME     PC255 1
 '@SCM_LIB.SCM(SCH_1):PAGE55_I23@PURE_QUANTA.Q_CAP(CHIPS)':
 'A': CDS_PINID='A';
NODE_NAME     PC256 1
 '@SCM_LIB.SCM(SCH_1):PAGE55_I24@PURE_QUANTA.Q_CAP(CHIPS)':
 'A': CDS_PINID='A';
NODE_NAME     PC257 1
 '@SCM_LIB.SCM(SCH_1):PAGE55_I25@PURE_QUANTA.Q_CAP(CHIPS)':
 'A': CDS_PINID='A';
NODE_NAME     PC258 1
 '@SCM_LIB.SCM(SCH_1):PAGE55_I28@PURE_QUANTA.Q_CAP(CHIPS)':
 'A': CDS_PINID='A';
NODE_NAME     PC259 1
 '@SCM_LIB.SCM(SCH_1):PAGE55_I29@PURE_QUANTA.Q_CAP(CHIPS)':
 'A': CDS_PINID='A';
NODE_NAME     C131 1
 '@SCM_LIB.SCM(SCH_1):PAGE16_I192@PURE_QUANTA.Q_CAP(CHIPS)':
 'A': CDS_PINID='A';
NODE_NAME     C132 1
 '@SCM_LIB.SCM(SCH_1):PAGE16_I193@PURE_QUANTA.Q_CAP(CHIPS)':
 'A': CDS_PINID='A';
NET_NAME
'P1V2_AUX_MODE'
 '@SCM_LIB.SCM(SCH_1):P1V2_AUX_MODE':
 C_SIGNAL='@scm_lib.scm(sch_1):p1v2_aux_mode';
NODE_NAME     PR496 1
 '@SCM_LIB.SCM(SCH_1):PAGE55_I6@PURE_QUANTA.Q_RES(CHIPS)':
 'A': CDS_PINID='A';
NODE_NAME     PU41 7
 '@SCM_LIB.SCM(SCH_1):PAGE55_I15@PURE_QUANTA.NB695GDZ(CHIPS)':
 'MODE': CDS_PINID='MODE';
NET_NAME
'P1V2_AUX_VCC'
 '@SCM_LIB.SCM(SCH_1):P1V2_AUX_VCC':
 C_SIGNAL='@scm_lib.scm(sch_1):p1v2_aux_vcc';
NODE_NAME     PC250 1
 '@SCM_LIB.SCM(SCH_1):PAGE55_I7@PURE_QUANTA.Q_CAP(CHIPS)':
 'A': CDS_PINID='A';
NODE_NAME     PR539 2
 '@SCM_LIB.SCM(SCH_1):PAGE55_I8@PURE_QUANTA.Q_RES(CHIPS)':
 'B': CDS_PINID='B';
NODE_NAME     PU41 10
 '@SCM_LIB.SCM(SCH_1):PAGE55_I15@PURE_QUANTA.NB695GDZ(CHIPS)':
 '3V3': CDS_PINID='\3v3\';
NODE_NAME     PU41 6
 '@SCM_LIB.SCM(SCH_1):PAGE55_I15@PURE_QUANTA.NB695GDZ(CHIPS)':
 'LP#': CDS_PINID='\lp#\';
NET_NAME
'P1V2_P1V0_I3C_VDDL1'
 '@SCM_LIB.SCM(SCH_1):P1V2_P1V0_I3C_VDDL1':
 C_SIGNAL='@scm_lib.scm(sch_1):p1v2_p1v0_i3c_vddl1',
 CDS_GLOBAL_NET='TRUE';
NODE_NAME     R194 1
 '@SCM_LIB.SCM(SCH_1):PAGE14_I171@PURE_QUANTA.Q_RES(CHIPS)':
 'A': CDS_PINID='A';
NODE_NAME     R195 1
 '@SCM_LIB.SCM(SCH_1):PAGE14_I172@PURE_QUANTA.Q_RES(CHIPS)':
 'A': CDS_PINID='A';
NODE_NAME     R190 1
 '@SCM_LIB.SCM(SCH_1):PAGE14_I173@PURE_QUANTA.Q_RES(CHIPS)':
 'A': CDS_PINID='A';
NODE_NAME     R191 1
 '@SCM_LIB.SCM(SCH_1):PAGE14_I174@PURE_QUANTA.Q_RES(CHIPS)':
 'A': CDS_PINID='A';
NODE_NAME     U5 V22
 '@SCM_LIB.SCM(SCH_1):PAGE16_I188@PURE_QUANTA.AST2600A3GP(CHIPS)':
 'I3CVDDL1': CDS_PINID='I3CVDDL1';
NODE_NAME     R279 2
 '@SCM_LIB.SCM(SCH_1):PAGE17_I95@PURE_QUANTA.Q_RES(CHIPS)':
 'B': CDS_PINID='B';
NODE_NAME     C139 1
 '@SCM_LIB.SCM(SCH_1):PAGE17_I98@PURE_QUANTA.Q_CAP(CHIPS)':
 'A': CDS_PINID='A';
NODE_NAME     R278 2
 '@SCM_LIB.SCM(SCH_1):PAGE17_I101@PURE_QUANTA.Q_RES(CHIPS)':
 'B': CDS_PINID='B';
NODE_NAME     R188 1
 '@SCM_LIB.SCM(SCH_1):PAGE14_I183@PURE_QUANTA.Q_RES(CHIPS)':
 'A': CDS_PINID='A';
NODE_NAME     R189 1
 '@SCM_LIB.SCM(SCH_1):PAGE14_I188@PURE_QUANTA.Q_RES(CHIPS)':
 'A': CDS_PINID='A';
NODE_NAME     R196 1
 '@SCM_LIB.SCM(SCH_1):PAGE14_I189@PURE_QUANTA.Q_RES(CHIPS)':
 'A': CDS_PINID='A';
NODE_NAME     R197 1
 '@SCM_LIB.SCM(SCH_1):PAGE14_I190@PURE_QUANTA.Q_RES(CHIPS)':
 'A': CDS_PINID='A';
NET_NAME
'P1V2_P1V0_I3C_VDDL2'
 '@SCM_LIB.SCM(SCH_1):P1V2_P1V0_I3C_VDDL2':
 C_SIGNAL='@scm_lib.scm(sch_1):p1v2_p1v0_i3c_vddl2',
 CDS_GLOBAL_NET='TRUE';
NODE_NAME     U5 U21
 '@SCM_LIB.SCM(SCH_1):PAGE16_I188@PURE_QUANTA.AST2600A3GP(CHIPS)':
 'I3CVDDL2': CDS_PINID='I3CVDDL2';
NODE_NAME     R281 2
 '@SCM_LIB.SCM(SCH_1):PAGE17_I92@PURE_QUANTA.Q_RES(CHIPS)':
 'B': CDS_PINID='B';
NODE_NAME     R280 2
 '@SCM_LIB.SCM(SCH_1):PAGE17_I94@PURE_QUANTA.Q_RES(CHIPS)':
 'B': CDS_PINID='B';
NODE_NAME     C140 1
 '@SCM_LIB.SCM(SCH_1):PAGE17_I97@PURE_QUANTA.Q_CAP(CHIPS)':
 'A': CDS_PINID='A';
NET_NAME
'P1V2_SENSOR'
 '@SCM_LIB.SCM(SCH_1):P1V2_SENSOR':
 C_SIGNAL='@scm_lib.scm(sch_1):p1v2_sensor';
NODE_NAME     C309 1
 '@SCM_LIB.SCM(SCH_1):PAGE15_I247@PURE_QUANTA.Q_CAP(CHIPS)':
 'A': CDS_PINID='A';
NODE_NAME     R795 2
 '@SCM_LIB.SCM(SCH_1):PAGE15_I252@PURE_QUANTA.Q_RES(CHIPS)':
 'B': CDS_PINID='B';
NODE_NAME     U5 AB18
 '@SCM_LIB.SCM(SCH_1):PAGE15_I350@PURE_QUANTA.AST2600A3GP(CHIPS)':
 'ADC6||GPIT6': CDS_PINID='\adc6||gpit6\';
NET_NAME
'P1V2_STBY_MVDD_CK'
 '@SCM_LIB.SCM(SCH_1):P1V2_STBY_MVDD_CK':
 C_SIGNAL='@scm_lib.scm(sch_1):p1v2_stby_mvdd_ck';
NODE_NAME     C63 1
 '@SCM_LIB.SCM(SCH_1):PAGE16_I46@PURE_QUANTA.Q_CAP(CHIPS)':
 'A': CDS_PINID='A';
NODE_NAME     L11 2
 '@SCM_LIB.SCM(SCH_1):PAGE16_I47@PURE_QUANTA.Q_INDUCTOR(CHIPS)':
 '2': CDS_PINID='\2\';
NODE_NAME     C67 1
 '@SCM_LIB.SCM(SCH_1):PAGE16_I48@PURE_QUANTA.Q_CAP(CHIPS)':
 'A': CDS_PINID='A';
NODE_NAME     C71 1
 '@SCM_LIB.SCM(SCH_1):PAGE16_I49@PURE_QUANTA.Q_CAP(CHIPS)':
 'A': CDS_PINID='A';
NODE_NAME     C73 1
 '@SCM_LIB.SCM(SCH_1):PAGE16_I51@PURE_QUANTA.Q_CAP(CHIPS)':
 'A': CDS_PINID='A';
NODE_NAME     U5 M6
 '@SCM_LIB.SCM(SCH_1):PAGE16_I188@PURE_QUANTA.AST2600A3GP(CHIPS)':
 'MVDD_CK': CDS_PINID='MVDD_CK';
NET_NAME
'P1V8_AUX'
 '@SCM_LIB.SCM(SCH_1):P1V8_AUX':
 C_SIGNAL='@scm_lib.scm(sch_1):p1v8_aux',
 CDS_GLOBAL_NET='TRUE';
NODE_NAME     R154 1
 '@SCM_LIB.SCM(SCH_1):PAGE13_I3@PURE_QUANTA.Q_RES(CHIPS)':
 'A': CDS_PINID='A';
NODE_NAME     R208 1
 '@SCM_LIB.SCM(SCH_1):PAGE15_I2@PURE_QUANTA.Q_RES(CHIPS)':
 'A': CDS_PINID='A';
NODE_NAME     R214 1
 '@SCM_LIB.SCM(SCH_1):PAGE15_I32@PURE_QUANTA.Q_RES(CHIPS)':
 'A': CDS_PINID='A';
NODE_NAME     L3 1
 '@SCM_LIB.SCM(SCH_1):PAGE15_I65@PURE_QUANTA.Q_INDUCTOR(CHIPS)':
 '1': CDS_PINID='\1\';
NODE_NAME     R793 1
 '@SCM_LIB.SCM(SCH_1):PAGE15_I244@PURE_QUANTA.Q_RES(CHIPS)':
 'A': CDS_PINID='A';
NODE_NAME     L10 1
 '@SCM_LIB.SCM(SCH_1):PAGE16_I24@PURE_QUANTA.Q_INDUCTOR(CHIPS)':
 '1': CDS_PINID='\1\';
NODE_NAME     C89 1
 '@SCM_LIB.SCM(SCH_1):PAGE16_I118@PURE_QUANTA.Q_CAP(CHIPS)':
 'A': CDS_PINID='A';
NODE_NAME     C95 1
 '@SCM_LIB.SCM(SCH_1):PAGE16_I119@PURE_QUANTA.Q_CAP(CHIPS)':
 'A': CDS_PINID='A';
NODE_NAME     C102 1
 '@SCM_LIB.SCM(SCH_1):PAGE16_I126@PURE_QUANTA.Q_CAP(CHIPS)':
 'A': CDS_PINID='A';
NODE_NAME     C106 1
 '@SCM_LIB.SCM(SCH_1):PAGE16_I127@PURE_QUANTA.Q_CAP(CHIPS)':
 'A': CDS_PINID='A';
NODE_NAME     C111 1
 '@SCM_LIB.SCM(SCH_1):PAGE16_I128@PURE_QUANTA.Q_CAP(CHIPS)':
 'A': CDS_PINID='A';
NODE_NAME     C116 1
 '@SCM_LIB.SCM(SCH_1):PAGE16_I129@PURE_QUANTA.Q_CAP(CHIPS)':
 'A': CDS_PINID='A';
NODE_NAME     C121 1
 '@SCM_LIB.SCM(SCH_1):PAGE16_I131@PURE_QUANTA.Q_CAP(CHIPS)':
 'A': CDS_PINID='A';
NODE_NAME     C126 1
 '@SCM_LIB.SCM(SCH_1):PAGE16_I143@PURE_QUANTA.Q_CAP(CHIPS)':
 'A': CDS_PINID='A';
NODE_NAME     C87 1
 '@SCM_LIB.SCM(SCH_1):PAGE16_I147@PURE_QUANTA.Q_CAP(CHIPS)':
 'A': CDS_PINID='A';
NODE_NAME     C93 1
 '@SCM_LIB.SCM(SCH_1):PAGE16_I148@PURE_QUANTA.Q_CAP(CHIPS)':
 'A': CDS_PINID='A';
NODE_NAME     C100 1
 '@SCM_LIB.SCM(SCH_1):PAGE16_I152@PURE_QUANTA.Q_CAP(CHIPS)':
 'A': CDS_PINID='A';
NODE_NAME     C105 1
 '@SCM_LIB.SCM(SCH_1):PAGE16_I153@PURE_QUANTA.Q_CAP(CHIPS)':
 'A': CDS_PINID='A';
NODE_NAME     C109 1
 '@SCM_LIB.SCM(SCH_1):PAGE16_I156@PURE_QUANTA.Q_CAP(CHIPS)':
 'A': CDS_PINID='A';
NODE_NAME     C114 1
 '@SCM_LIB.SCM(SCH_1):PAGE16_I158@PURE_QUANTA.Q_CAP(CHIPS)':
 'A': CDS_PINID='A';
NODE_NAME     C119 1
 '@SCM_LIB.SCM(SCH_1):PAGE16_I159@PURE_QUANTA.Q_CAP(CHIPS)':
 'A': CDS_PINID='A';
NODE_NAME     C124 1
 '@SCM_LIB.SCM(SCH_1):PAGE16_I169@PURE_QUANTA.Q_CAP(CHIPS)':
 'A': CDS_PINID='A';
NODE_NAME     U5 H8
 '@SCM_LIB.SCM(SCH_1):PAGE16_I188@PURE_QUANTA.AST2600A3GP(CHIPS)':
 'PV18D_H8': CDS_PINID='PV18D_H8';
NODE_NAME     U5 J8
 '@SCM_LIB.SCM(SCH_1):PAGE16_I188@PURE_QUANTA.AST2600A3GP(CHIPS)':
 'PV18D_J8': CDS_PINID='PV18D_J8';
NODE_NAME     U5 N12
 '@SCM_LIB.SCM(SCH_1):PAGE16_I188@PURE_QUANTA.AST2600A3GP(CHIPS)':
 'PV18D_N12': CDS_PINID='PV18D_N12';
NODE_NAME     U5 P12
 '@SCM_LIB.SCM(SCH_1):PAGE16_I188@PURE_QUANTA.AST2600A3GP(CHIPS)':
 'PV18D_P12': CDS_PINID='PV18D_P12';
NODE_NAME     U5 R12
 '@SCM_LIB.SCM(SCH_1):PAGE16_I188@PURE_QUANTA.AST2600A3GP(CHIPS)':
 'PV18D_R12': CDS_PINID='PV18D_R12';
NODE_NAME     U5 H12
 '@SCM_LIB.SCM(SCH_1):PAGE16_I188@PURE_QUANTA.AST2600A3GP(CHIPS)':
 'PV18D_RGM_H12': CDS_PINID='PV18D_RGM_H12';
NODE_NAME     U5 J12
 '@SCM_LIB.SCM(SCH_1):PAGE16_I188@PURE_QUANTA.AST2600A3GP(CHIPS)':
 'PV18D_RGM_J12': CDS_PINID='PV18D_RGM_J12';
NODE_NAME     U5 L13
 '@SCM_LIB.SCM(SCH_1):PAGE16_I188@PURE_QUANTA.AST2600A3GP(CHIPS)':
 'PV18D_SLI_L13': CDS_PINID='PV18D_SLI_L13';
NODE_NAME     U5 M13
 '@SCM_LIB.SCM(SCH_1):PAGE16_I188@PURE_QUANTA.AST2600A3GP(CHIPS)':
 'PV18D_SLI_M13': CDS_PINID='PV18D_SLI_M13';
NODE_NAME     U5 N13
 '@SCM_LIB.SCM(SCH_1):PAGE16_I188@PURE_QUANTA.AST2600A3GP(CHIPS)':
 'PV18D_SLI_N13': CDS_PINID='PV18D_SLI_N13';
NODE_NAME     U5 P13
 '@SCM_LIB.SCM(SCH_1):PAGE16_I188@PURE_QUANTA.AST2600A3GP(CHIPS)':
 'PV18D_SLI_P13': CDS_PINID='PV18D_SLI_P13';
NODE_NAME     U5 R13
 '@SCM_LIB.SCM(SCH_1):PAGE16_I188@PURE_QUANTA.AST2600A3GP(CHIPS)':
 'PV18D_SLI_R13': CDS_PINID='PV18D_SLI_R13';
NODE_NAME     U5 T13
 '@SCM_LIB.SCM(SCH_1):PAGE16_I188@PURE_QUANTA.AST2600A3GP(CHIPS)':
 'PV18D_SLI_T13': CDS_PINID='PV18D_SLI_T13';
NODE_NAME     U5 U13
 '@SCM_LIB.SCM(SCH_1):PAGE16_I188@PURE_QUANTA.AST2600A3GP(CHIPS)':
 'PV18D_SLI_U13': CDS_PINID='PV18D_SLI_U13';
NODE_NAME     U5 V13
 '@SCM_LIB.SCM(SCH_1):PAGE16_I188@PURE_QUANTA.AST2600A3GP(CHIPS)':
 'PV18D_SLI_V13': CDS_PINID='PV18D_SLI_V13';
NODE_NAME     U5 W13
 '@SCM_LIB.SCM(SCH_1):PAGE16_I188@PURE_QUANTA.AST2600A3GP(CHIPS)':
 'PV18D_SLI_W13': CDS_PINID='PV18D_SLI_W13';
NODE_NAME     U5 W14
 '@SCM_LIB.SCM(SCH_1):PAGE16_I188@PURE_QUANTA.AST2600A3GP(CHIPS)':
 'PV18D_SLI_W14': CDS_PINID='PV18D_SLI_W14';
NODE_NAME     U5 U6
 '@SCM_LIB.SCM(SCH_1):PAGE16_I188@PURE_QUANTA.AST2600A3GP(CHIPS)':
 'PV18D_U6': CDS_PINID='PV18D_U6';
NODE_NAME     U5 V6
 '@SCM_LIB.SCM(SCH_1):PAGE16_I188@PURE_QUANTA.AST2600A3GP(CHIPS)':
 'PV18D_V6': CDS_PINID='PV18D_V6';
NODE_NAME     L5 1
 '@SCM_LIB.SCM(SCH_1):PAGE17_I120@PURE_QUANTA.Q_INDUCTOR(CHIPS)':
 '1': CDS_PINID='\1\';
NODE_NAME     R232 1
 '@SCM_LIB.SCM(SCH_1):PAGE17_I136@PURE_QUANTA.Q_RES(CHIPS)':
 'A': CDS_PINID='A';
NODE_NAME     L14 1
 '@SCM_LIB.SCM(SCH_1):PAGE17_I154@PURE_QUANTA.Q_INDUCTOR(CHIPS)':
 '1': CDS_PINID='\1\';
NODE_NAME     L16 1
 '@SCM_LIB.SCM(SCH_1):PAGE17_I166@PURE_QUANTA.Q_INDUCTOR(CHIPS)':
 '1': CDS_PINID='\1\';
NODE_NAME     R783 1
 '@SCM_LIB.SCM(SCH_1):PAGE17_I260@PURE_QUANTA.Q_RES(CHIPS)':
 'A': CDS_PINID='A';
NODE_NAME     R781 1
 '@SCM_LIB.SCM(SCH_1):PAGE17_I263@PURE_QUANTA.Q_RES(CHIPS)':
 'A': CDS_PINID='A';
NODE_NAME     Q5 4
 '@SCM_LIB.SCM(SCH_1):PAGE17_I274@PURE_QUANTA.MOSFET_NCH_4D1S(CHIPS)':
 '4': CDS_PINID='\4\';
NODE_NAME     R645 1
 '@SCM_LIB.SCM(SCH_1):PAGE17_I278@PURE_QUANTA.Q_RES(CHIPS)':
 'A': CDS_PINID='A';
NODE_NAME     U41 1
 '@SCM_LIB.SCM(SCH_1):PAGE54_I96@PURE_QUANTA.RT9059GQW(CHIPS)':
 'VOUT1': CDS_PINID='VOUT1';
NODE_NAME     U41 2
 '@SCM_LIB.SCM(SCH_1):PAGE54_I96@PURE_QUANTA.RT9059GQW(CHIPS)':
 'VOUT2': CDS_PINID='VOUT2';
NODE_NAME     U41 3
 '@SCM_LIB.SCM(SCH_1):PAGE54_I96@PURE_QUANTA.RT9059GQW(CHIPS)':
 'VOUT3': CDS_PINID='VOUT3';
NODE_NAME     R831 1
 '@SCM_LIB.SCM(SCH_1):PAGE54_I98@PURE_QUANTA.Q_RES(CHIPS)':
 'A': CDS_PINID='A';
NODE_NAME     C142 1
 '@SCM_LIB.SCM(SCH_1):PAGE54_I104@PURE_QUANTA.Q_CAP(CHIPS)':
 'A': CDS_PINID='A';
NODE_NAME     C294 1
 '@SCM_LIB.SCM(SCH_1):PAGE54_I105@PURE_QUANTA.Q_CAP(CHIPS)':
 'A': CDS_PINID='A';
NODE_NAME     R856 1
 '@SCM_LIB.SCM(SCH_1):PAGE14_I220@PURE_QUANTA.Q_RES(CHIPS)':
 'A': CDS_PINID='A';
NODE_NAME     R854 1
 '@SCM_LIB.SCM(SCH_1):PAGE14_I221@PURE_QUANTA.Q_RES(CHIPS)':
 'A': CDS_PINID='A';
NODE_NAME     R858 1
 '@SCM_LIB.SCM(SCH_1):PAGE14_I222@PURE_QUANTA.Q_RES(CHIPS)':
 'A': CDS_PINID='A';
NODE_NAME     R885 1
 '@SCM_LIB.SCM(SCH_1):PAGE14_I231@PURE_QUANTA.Q_RES(CHIPS)':
 'A': CDS_PINID='A';
NET_NAME
'P1V8_BMC_USB2AV18'
 '@SCM_LIB.SCM(SCH_1):P1V8_BMC_USB2AV18':
 C_SIGNAL='@scm_lib.scm(sch_1):p1v8_bmc_usb2av18';
NODE_NAME     L3 2
 '@SCM_LIB.SCM(SCH_1):PAGE15_I65@PURE_QUANTA.Q_INDUCTOR(CHIPS)':
 '2': CDS_PINID='\2\';
NODE_NAME     C41 1
 '@SCM_LIB.SCM(SCH_1):PAGE15_I68@PURE_QUANTA.Q_CAP(CHIPS)':
 'A': CDS_PINID='A';
NODE_NAME     U5 K10
 '@SCM_LIB.SCM(SCH_1):PAGE15_I350@PURE_QUANTA.AST2600A3GP(CHIPS)':
 'USB2AV18': CDS_PINID='USB2AV18';
NODE_NAME     C40 1
 '@SCM_LIB.SCM(SCH_1):PAGE15_I368@PURE_QUANTA.Q_CAP(CHIPS)':
 'A': CDS_PINID='A';
NET_NAME
'P1V8_SENSOR'
 '@SCM_LIB.SCM(SCH_1):P1V8_SENSOR':
 C_SIGNAL='@scm_lib.scm(sch_1):p1v8_sensor';
NODE_NAME     C307 1
 '@SCM_LIB.SCM(SCH_1):PAGE15_I240@PURE_QUANTA.Q_CAP(CHIPS)':
 'A': CDS_PINID='A';
NODE_NAME     R794 1
 '@SCM_LIB.SCM(SCH_1):PAGE15_I242@PURE_QUANTA.Q_RES(CHIPS)':
 'A': CDS_PINID='A';
NODE_NAME     R793 2
 '@SCM_LIB.SCM(SCH_1):PAGE15_I244@PURE_QUANTA.Q_RES(CHIPS)':
 'B': CDS_PINID='B';
NODE_NAME     U5 AC19
 '@SCM_LIB.SCM(SCH_1):PAGE15_I350@PURE_QUANTA.AST2600A3GP(CHIPS)':
 'ADC4||GPIT4': CDS_PINID='\adc4||gpit4\';
NET_NAME
'P1V8_STBY_AVDDPLL'
 '@SCM_LIB.SCM(SCH_1):P1V8_STBY_AVDDPLL':
 C_SIGNAL='@scm_lib.scm(sch_1):p1v8_stby_avddpll';
NODE_NAME     U5 N5
 '@SCM_LIB.SCM(SCH_1):PAGE16_I188@PURE_QUANTA.AST2600A3GP(CHIPS)':
 'AVDDPLL': CDS_PINID='AVDDPLL';
NODE_NAME     C49 1
 '@SCM_LIB.SCM(SCH_1):PAGE17_I118@PURE_QUANTA.Q_CAP(CHIPS)':
 'A': CDS_PINID='A';
NODE_NAME     L5 2
 '@SCM_LIB.SCM(SCH_1):PAGE17_I120@PURE_QUANTA.Q_INDUCTOR(CHIPS)':
 '2': CDS_PINID='\2\';
NODE_NAME     C46 1
 '@SCM_LIB.SCM(SCH_1):PAGE17_I122@PURE_QUANTA.Q_CAP(CHIPS)':
 'A': CDS_PINID='A';
NET_NAME
'P1V8_STBY_DP_VCC18A'
 '@SCM_LIB.SCM(SCH_1):P1V8_STBY_DP_VCC18A':
 C_SIGNAL='@scm_lib.scm(sch_1):p1v8_stby_dp_vcc18a';
NODE_NAME     U5 V8
 '@SCM_LIB.SCM(SCH_1):PAGE16_I188@PURE_QUANTA.AST2600A3GP(CHIPS)':
 'DP_VCC18A': CDS_PINID='DP_VCC18A';
NODE_NAME     C130 1
 '@SCM_LIB.SCM(SCH_1):PAGE17_I163@PURE_QUANTA.Q_CAP(CHIPS)':
 'A': CDS_PINID='A';
NODE_NAME     C128 1
 '@SCM_LIB.SCM(SCH_1):PAGE17_I165@PURE_QUANTA.Q_CAP(CHIPS)':
 'A': CDS_PINID='A';
NODE_NAME     L16 2
 '@SCM_LIB.SCM(SCH_1):PAGE17_I166@PURE_QUANTA.Q_INDUCTOR(CHIPS)':
 '2': CDS_PINID='\2\';
NET_NAME
'P1V8_STBY_PE_VCC18A'
 '@SCM_LIB.SCM(SCH_1):P1V8_STBY_PE_VCC18A':
 C_SIGNAL='@scm_lib.scm(sch_1):p1v8_stby_pe_vcc18a';
NODE_NAME     L10 2
 '@SCM_LIB.SCM(SCH_1):PAGE16_I24@PURE_QUANTA.Q_INDUCTOR(CHIPS)':
 '2': CDS_PINID='\2\';
NODE_NAME     C61 1
 '@SCM_LIB.SCM(SCH_1):PAGE16_I55@PURE_QUANTA.Q_CAP(CHIPS)':
 'A': CDS_PINID='A';
NODE_NAME     C69 1
 '@SCM_LIB.SCM(SCH_1):PAGE16_I59@PURE_QUANTA.Q_CAP(CHIPS)':
 'A': CDS_PINID='A';
NODE_NAME     U5 V9
 '@SCM_LIB.SCM(SCH_1):PAGE16_I188@PURE_QUANTA.AST2600A3GP(CHIPS)':
 'RC_VCC18A': CDS_PINID='RC_VCC18A';
NET_NAME
'P1V8_STBY_RC_VCC18A'
 '@SCM_LIB.SCM(SCH_1):P1V8_STBY_RC_VCC18A':
 C_SIGNAL='@scm_lib.scm(sch_1):p1v8_stby_rc_vcc18a';
NODE_NAME     U5 V10
 '@SCM_LIB.SCM(SCH_1):PAGE16_I188@PURE_QUANTA.AST2600A3GP(CHIPS)':
 'PE_VCC18A': CDS_PINID='PE_VCC18A';
NODE_NAME     C81 1
 '@SCM_LIB.SCM(SCH_1):PAGE17_I151@PURE_QUANTA.Q_CAP(CHIPS)':
 'A': CDS_PINID='A';
NODE_NAME     C80 1
 '@SCM_LIB.SCM(SCH_1):PAGE17_I153@PURE_QUANTA.Q_CAP(CHIPS)':
 'A': CDS_PINID='A';
NODE_NAME     L14 2
 '@SCM_LIB.SCM(SCH_1):PAGE17_I154@PURE_QUANTA.Q_INDUCTOR(CHIPS)':
 '2': CDS_PINID='\2\';
NET_NAME
'P2E_GPU_RX_DN'
 '@SCM_LIB.SCM(SCH_1):P2E_GPU_RX_DN':
 C_SIGNAL='@scm_lib.scm(sch_1):p2e_gpu_rx_dn';
NODE_NAME     GF1 A66
 '@SCM_LIB.SCM(SCH_1):PAGE10_I553@PURE_QUANTA.FCONN168_ME1016810202011_SCM(CHIPS)':
 'PCIE_HPM_RXN_2': CDS_PINID='PCIE_HPM_RXN_2';
NODE_NAME     U5 AD3
 '@SCM_LIB.SCM(SCH_1):PAGE12_I436@PURE_QUANTA.AST2600A3GP(CHIPS)':
 'RCRXN': CDS_PINID='RCRXN';
NET_NAME
'P2E_GPU_RX_DP'
 '@SCM_LIB.SCM(SCH_1):P2E_GPU_RX_DP':
 C_SIGNAL='@scm_lib.scm(sch_1):p2e_gpu_rx_dp';
NODE_NAME     GF1 A65
 '@SCM_LIB.SCM(SCH_1):PAGE10_I553@PURE_QUANTA.FCONN168_ME1016810202011_SCM(CHIPS)':
 'PCIE_HPM_RXP_2': CDS_PINID='PCIE_HPM_RXP_2';
NODE_NAME     U5 AD2
 '@SCM_LIB.SCM(SCH_1):PAGE12_I436@PURE_QUANTA.AST2600A3GP(CHIPS)':
 'RCRXP': CDS_PINID='RCRXP';
NET_NAME
'P2E_GPU_TX_C_DN'
 '@SCM_LIB.SCM(SCH_1):P2E_GPU_TX_C_DN':
 C_SIGNAL='@scm_lib.scm(sch_1):p2e_gpu_tx_c_dn';
NODE_NAME     GF1 B66
 '@SCM_LIB.SCM(SCH_1):PAGE10_I553@PURE_QUANTA.FCONN168_ME1016810202011_SCM(CHIPS)':
 'PCIE_HPM_TXN_2': CDS_PINID='PCIE_HPM_TXN_2';
NODE_NAME     C271 2
 '@SCM_LIB.SCM(SCH_1):PAGE12_I429@PURE_QUANTA.Q_CAP(CHIPS)':
 'B': CDS_PINID='B';
NET_NAME
'P2E_GPU_TX_C_DP'
 '@SCM_LIB.SCM(SCH_1):P2E_GPU_TX_C_DP':
 C_SIGNAL='@scm_lib.scm(sch_1):p2e_gpu_tx_c_dp';
NODE_NAME     GF1 B65
 '@SCM_LIB.SCM(SCH_1):PAGE10_I553@PURE_QUANTA.FCONN168_ME1016810202011_SCM(CHIPS)':
 'PCIE_HPM_TXP_2': CDS_PINID='PCIE_HPM_TXP_2';
NODE_NAME     C272 2
 '@SCM_LIB.SCM(SCH_1):PAGE12_I428@PURE_QUANTA.Q_CAP(CHIPS)':
 'B': CDS_PINID='B';
NET_NAME
'P2E_GPU_TX_DN'
 '@SCM_LIB.SCM(SCH_1):P2E_GPU_TX_DN':
 C_SIGNAL='@scm_lib.scm(sch_1):p2e_gpu_tx_dn';
NODE_NAME     C271 1
 '@SCM_LIB.SCM(SCH_1):PAGE12_I429@PURE_QUANTA.Q_CAP(CHIPS)':
 'A': CDS_PINID='A';
NODE_NAME     U5 AF2
 '@SCM_LIB.SCM(SCH_1):PAGE12_I436@PURE_QUANTA.AST2600A3GP(CHIPS)':
 'RCTXP': CDS_PINID='RCTXP';
NET_NAME
'P2E_GPU_TX_DP'
 '@SCM_LIB.SCM(SCH_1):P2E_GPU_TX_DP':
 C_SIGNAL='@scm_lib.scm(sch_1):p2e_gpu_tx_dp';
NODE_NAME     C272 1
 '@SCM_LIB.SCM(SCH_1):PAGE12_I428@PURE_QUANTA.Q_CAP(CHIPS)':
 'A': CDS_PINID='A';
NODE_NAME     U5 AF3
 '@SCM_LIB.SCM(SCH_1):PAGE12_I436@PURE_QUANTA.AST2600A3GP(CHIPS)':
 'RCTXN': CDS_PINID='RCTXN';
NET_NAME
'P2E_PCH_RX_DN'
 '@SCM_LIB.SCM(SCH_1):P2E_PCH_RX_DN':
 C_SIGNAL='@scm_lib.scm(sch_1):p2e_pch_rx_dn';
NODE_NAME     GF1 A18
 '@SCM_LIB.SCM(SCH_1):PAGE10_I553@PURE_QUANTA.FCONN168_ME1016810202011_SCM(CHIPS)':
 'PCIE_BMC_TX_DN': CDS_PINID='PCIE_BMC_TX_DN';
NODE_NAME     U5 AF6
 '@SCM_LIB.SCM(SCH_1):PAGE12_I436@PURE_QUANTA.AST2600A3GP(CHIPS)':
 'PERXN': CDS_PINID='PERXN';
NET_NAME
'P2E_PCH_RX_DP'
 '@SCM_LIB.SCM(SCH_1):P2E_PCH_RX_DP':
 C_SIGNAL='@scm_lib.scm(sch_1):p2e_pch_rx_dp';
NODE_NAME     GF1 A17
 '@SCM_LIB.SCM(SCH_1):PAGE10_I553@PURE_QUANTA.FCONN168_ME1016810202011_SCM(CHIPS)':
 'PCIE_BMC_TX_DP': CDS_PINID='PCIE_BMC_TX_DP';
NODE_NAME     U5 AF5
 '@SCM_LIB.SCM(SCH_1):PAGE12_I436@PURE_QUANTA.AST2600A3GP(CHIPS)':
 'PERXP': CDS_PINID='PERXP';
NET_NAME
'P2E_PCH_TX_C_DN'
 '@SCM_LIB.SCM(SCH_1):P2E_PCH_TX_C_DN':
 C_SIGNAL='@scm_lib.scm(sch_1):p2e_pch_tx_c_dn';
NODE_NAME     GF1 A21
 '@SCM_LIB.SCM(SCH_1):PAGE10_I553@PURE_QUANTA.FCONN168_ME1016810202011_SCM(CHIPS)':
 'PCIE_BMC_RX_DN': CDS_PINID='PCIE_BMC_RX_DN';
NODE_NAME     C25 2
 '@SCM_LIB.SCM(SCH_1):PAGE12_I153@PURE_QUANTA.Q_CAP(CHIPS)':
 'B': CDS_PINID='B';
NET_NAME
'P2E_PCH_TX_C_DP'
 '@SCM_LIB.SCM(SCH_1):P2E_PCH_TX_C_DP':
 C_SIGNAL='@scm_lib.scm(sch_1):p2e_pch_tx_c_dp';
NODE_NAME     GF1 A20
 '@SCM_LIB.SCM(SCH_1):PAGE10_I553@PURE_QUANTA.FCONN168_ME1016810202011_SCM(CHIPS)':
 'PCIE_BMC_RX_DP': CDS_PINID='PCIE_BMC_RX_DP';
NODE_NAME     C24 2
 '@SCM_LIB.SCM(SCH_1):PAGE12_I152@PURE_QUANTA.Q_CAP(CHIPS)':
 'B': CDS_PINID='B';
NET_NAME
'P2E_PCH_TX_DN'
 '@SCM_LIB.SCM(SCH_1):P2E_PCH_TX_DN':
 C_SIGNAL='@scm_lib.scm(sch_1):p2e_pch_tx_dn';
NODE_NAME     C25 1
 '@SCM_LIB.SCM(SCH_1):PAGE12_I153@PURE_QUANTA.Q_CAP(CHIPS)':
 'A': CDS_PINID='A';
NODE_NAME     U5 AE5
 '@SCM_LIB.SCM(SCH_1):PAGE12_I436@PURE_QUANTA.AST2600A3GP(CHIPS)':
 'PETXN': CDS_PINID='PETXN';
NET_NAME
'P2E_PCH_TX_DP'
 '@SCM_LIB.SCM(SCH_1):P2E_PCH_TX_DP':
 C_SIGNAL='@scm_lib.scm(sch_1):p2e_pch_tx_dp';
NODE_NAME     C24 1
 '@SCM_LIB.SCM(SCH_1):PAGE12_I152@PURE_QUANTA.Q_CAP(CHIPS)':
 'A': CDS_PINID='A';
NODE_NAME     U5 AE4
 '@SCM_LIB.SCM(SCH_1):PAGE12_I436@PURE_QUANTA.AST2600A3GP(CHIPS)':
 'PETXP': CDS_PINID='PETXP';
NET_NAME
'P2V5_AUX'
 '@SCM_LIB.SCM(SCH_1):P2V5_AUX':
 C_SIGNAL='@scm_lib.scm(sch_1):p2v5_aux',
 CDS_GLOBAL_NET='TRUE';
NODE_NAME     R156 1
 '@SCM_LIB.SCM(SCH_1):PAGE13_I4@PURE_QUANTA.Q_RES(CHIPS)':
 'A': CDS_PINID='A';
NODE_NAME     R791 1
 '@SCM_LIB.SCM(SCH_1):PAGE15_I245@PURE_QUANTA.Q_RES(CHIPS)':
 'A': CDS_PINID='A';
NODE_NAME     R780 1
 '@SCM_LIB.SCM(SCH_1):PAGE17_I256@PURE_QUANTA.Q_RES(CHIPS)':
 'A': CDS_PINID='A';
NODE_NAME     R779 1
 '@SCM_LIB.SCM(SCH_1):PAGE17_I259@PURE_QUANTA.Q_RES(CHIPS)':
 'A': CDS_PINID='A';
NODE_NAME     C6 1
 '@SCM_LIB.SCM(SCH_1):PAGE20_I19@PURE_QUANTA.Q_CAP(CHIPS)':
 'A': CDS_PINID='A';
NODE_NAME     C8 1
 '@SCM_LIB.SCM(SCH_1):PAGE20_I21@PURE_QUANTA.Q_CAP(CHIPS)':
 'A': CDS_PINID='A';
NODE_NAME     U1 B1
 '@SCM_LIB.SCM(SCH_1):PAGE20_I196@PURE_QUANTA.K4A8G165WCBCTD(CHIPS)':
 'VPP0': CDS_PINID='VPP0';
NODE_NAME     U1 R9
 '@SCM_LIB.SCM(SCH_1):PAGE20_I196@PURE_QUANTA.K4A8G165WCBCTD(CHIPS)':
 'VPP1': CDS_PINID='VPP1';
NODE_NAME     U39 1
 '@SCM_LIB.SCM(SCH_1):PAGE53_I60@PURE_QUANTA.RT9059GQW(CHIPS)':
 'VOUT1': CDS_PINID='VOUT1';
NODE_NAME     U39 2
 '@SCM_LIB.SCM(SCH_1):PAGE53_I60@PURE_QUANTA.RT9059GQW(CHIPS)':
 'VOUT2': CDS_PINID='VOUT2';
NODE_NAME     U39 3
 '@SCM_LIB.SCM(SCH_1):PAGE53_I60@PURE_QUANTA.RT9059GQW(CHIPS)':
 'VOUT3': CDS_PINID='VOUT3';
NODE_NAME     R829 1
 '@SCM_LIB.SCM(SCH_1):PAGE53_I62@PURE_QUANTA.Q_RES(CHIPS)':
 'A': CDS_PINID='A';
NODE_NAME     C289 1
 '@SCM_LIB.SCM(SCH_1):PAGE53_I69@PURE_QUANTA.Q_CAP(CHIPS)':
 'A': CDS_PINID='A';
NODE_NAME     C291 1
 '@SCM_LIB.SCM(SCH_1):PAGE53_I70@PURE_QUANTA.Q_CAP(CHIPS)':
 'A': CDS_PINID='A';
NET_NAME
'P2V5_SENSOR'
 '@SCM_LIB.SCM(SCH_1):P2V5_SENSOR':
 C_SIGNAL='@scm_lib.scm(sch_1):p2v5_sensor';
NODE_NAME     C303 1
 '@SCM_LIB.SCM(SCH_1):PAGE15_I235@PURE_QUANTA.Q_CAP(CHIPS)':
 'A': CDS_PINID='A';
NODE_NAME     R792 1
 '@SCM_LIB.SCM(SCH_1):PAGE15_I236@PURE_QUANTA.Q_RES(CHIPS)':
 'A': CDS_PINID='A';
NODE_NAME     R791 2
 '@SCM_LIB.SCM(SCH_1):PAGE15_I245@PURE_QUANTA.Q_RES(CHIPS)':
 'B': CDS_PINID='B';
NODE_NAME     U5 AD19
 '@SCM_LIB.SCM(SCH_1):PAGE15_I350@PURE_QUANTA.AST2600A3GP(CHIPS)':
 'ADC3||GPIT3': CDS_PINID='\adc3||gpit3\';
NET_NAME
'P3V3_AUX'
 '@SCM_LIB.SCM(SCH_1):P3V3_AUX':
 C_SIGNAL='@scm_lib.scm(sch_1):p3v3_aux',
 CDS_GLOBAL_NET='TRUE';
NODE_NAME     R75 1
 '@SCM_LIB.SCM(SCH_1):PAGE11_I110@PURE_QUANTA.Q_RES(CHIPS)':
 'A': CDS_PINID='A';
NODE_NAME     R74 1
 '@SCM_LIB.SCM(SCH_1):PAGE11_I117@PURE_QUANTA.Q_RES(CHIPS)':
 'A': CDS_PINID='A';
NODE_NAME     R73 1
 '@SCM_LIB.SCM(SCH_1):PAGE11_I118@PURE_QUANTA.Q_RES(CHIPS)':
 'A': CDS_PINID='A';
NODE_NAME     R77 1
 '@SCM_LIB.SCM(SCH_1):PAGE11_I128@PURE_QUANTA.Q_RES(CHIPS)':
 'A': CDS_PINID='A';
NODE_NAME     R78 1
 '@SCM_LIB.SCM(SCH_1):PAGE11_I129@PURE_QUANTA.Q_RES(CHIPS)':
 'A': CDS_PINID='A';
NODE_NAME     R79 1
 '@SCM_LIB.SCM(SCH_1):PAGE11_I130@PURE_QUANTA.Q_RES(CHIPS)':
 'A': CDS_PINID='A';
NODE_NAME     R44 1
 '@SCM_LIB.SCM(SCH_1):PAGE11_I175@PURE_QUANTA.Q_RES(CHIPS)':
 'A': CDS_PINID='A';
NODE_NAME     R45 1
 '@SCM_LIB.SCM(SCH_1):PAGE11_I176@PURE_QUANTA.Q_RES(CHIPS)':
 'A': CDS_PINID='A';
NODE_NAME     R68 1
 '@SCM_LIB.SCM(SCH_1):PAGE11_I179@PURE_QUANTA.Q_RES(CHIPS)':
 'A': CDS_PINID='A';
NODE_NAME     R163 1
 '@SCM_LIB.SCM(SCH_1):PAGE11_I212@PURE_QUANTA.Q_RES(CHIPS)':
 'A': CDS_PINID='A';
NODE_NAME     R101 1
 '@SCM_LIB.SCM(SCH_1):PAGE11_I214@PURE_QUANTA.Q_RES(CHIPS)':
 'A': CDS_PINID='A';
NODE_NAME     R161 1
 '@SCM_LIB.SCM(SCH_1):PAGE11_I218@PURE_QUANTA.Q_RES(CHIPS)':
 'A': CDS_PINID='A';
NODE_NAME     R103 1
 '@SCM_LIB.SCM(SCH_1):PAGE11_I219@PURE_QUANTA.Q_RES(CHIPS)':
 'A': CDS_PINID='A';
NODE_NAME     R41 1
 '@SCM_LIB.SCM(SCH_1):PAGE11_I225@PURE_QUANTA.Q_RES(CHIPS)':
 'A': CDS_PINID='A';
NODE_NAME     R69 1
 '@SCM_LIB.SCM(SCH_1):PAGE11_I227@PURE_QUANTA.Q_RES(CHIPS)':
 'A': CDS_PINID='A';
NODE_NAME     R76 1
 '@SCM_LIB.SCM(SCH_1):PAGE11_I230@PURE_QUANTA.Q_RES(CHIPS)':
 'A': CDS_PINID='A';
NODE_NAME     R82 1
 '@SCM_LIB.SCM(SCH_1):PAGE11_I232@PURE_QUANTA.Q_RES(CHIPS)':
 'A': CDS_PINID='A';
NODE_NAME     R828 1
 '@SCM_LIB.SCM(SCH_1):PAGE11_I241@PURE_QUANTA.Q_RES(CHIPS)':
 'A': CDS_PINID='A';
NODE_NAME     R81 1
 '@SCM_LIB.SCM(SCH_1):PAGE11_I245@PURE_QUANTA.Q_RES(CHIPS)':
 'A': CDS_PINID='A';
NODE_NAME     R62 1
 '@SCM_LIB.SCM(SCH_1):PAGE12_I350@PURE_QUANTA.Q_RES(CHIPS)':
 'A': CDS_PINID='A';
NODE_NAME     R706 1
 '@SCM_LIB.SCM(SCH_1):PAGE12_I354@PURE_QUANTA.Q_RES(CHIPS)':
 'A': CDS_PINID='A';
NODE_NAME     R155 1
 '@SCM_LIB.SCM(SCH_1):PAGE13_I5@PURE_QUANTA.Q_RES(CHIPS)':
 'A': CDS_PINID='A';
NODE_NAME     R167 1
 '@SCM_LIB.SCM(SCH_1):PAGE13_I33@PURE_QUANTA.Q_RES(CHIPS)':
 'A': CDS_PINID='A';
NODE_NAME     R238 1
 '@SCM_LIB.SCM(SCH_1):PAGE13_I184@PURE_QUANTA.Q_RES(CHIPS)':
 'A': CDS_PINID='A';
NODE_NAME     R239 1
 '@SCM_LIB.SCM(SCH_1):PAGE13_I185@PURE_QUANTA.Q_RES(CHIPS)':
 'A': CDS_PINID='A';
NODE_NAME     R241 1
 '@SCM_LIB.SCM(SCH_1):PAGE13_I186@PURE_QUANTA.Q_RES(CHIPS)':
 'A': CDS_PINID='A';
NODE_NAME     R240 1
 '@SCM_LIB.SCM(SCH_1):PAGE13_I187@PURE_QUANTA.Q_RES(CHIPS)':
 'A': CDS_PINID='A';
NODE_NAME     R683 1
 '@SCM_LIB.SCM(SCH_1):PAGE13_I188@PURE_QUANTA.Q_RES(CHIPS)':
 'A': CDS_PINID='A';
NODE_NAME     R38 1
 '@SCM_LIB.SCM(SCH_1):PAGE13_I200@PURE_QUANTA.Q_RES(CHIPS)':
 'A': CDS_PINID='A';
NODE_NAME     R61 1
 '@SCM_LIB.SCM(SCH_1):PAGE13_I204@PURE_QUANTA.Q_RES(CHIPS)':
 'A': CDS_PINID='A';
NODE_NAME     R774 1
 '@SCM_LIB.SCM(SCH_1):PAGE13_I213@PURE_QUANTA.Q_RES(CHIPS)':
 'A': CDS_PINID='A';
NODE_NAME     R821 1
 '@SCM_LIB.SCM(SCH_1):PAGE13_I220@PURE_QUANTA.Q_RES(CHIPS)':
 'A': CDS_PINID='A';
NODE_NAME     R55 1
 '@SCM_LIB.SCM(SCH_1):PAGE13_I278@PURE_QUANTA.Q_RES(CHIPS)':
 'A': CDS_PINID='A';
NODE_NAME     R56 1
 '@SCM_LIB.SCM(SCH_1):PAGE13_I279@PURE_QUANTA.Q_RES(CHIPS)':
 'A': CDS_PINID='A';
NODE_NAME     R446 1
 '@SCM_LIB.SCM(SCH_1):PAGE13_I299@PURE_QUANTA.Q_RES(CHIPS)':
 'A': CDS_PINID='A';
NODE_NAME     R452 1
 '@SCM_LIB.SCM(SCH_1):PAGE13_I339@PURE_QUANTA.Q_RES(CHIPS)':
 'A': CDS_PINID='A';
NODE_NAME     R816 1
 '@SCM_LIB.SCM(SCH_1):PAGE13_I353@PURE_QUANTA.Q_RES(CHIPS)':
 'A': CDS_PINID='A';
NODE_NAME     R805 1
 '@SCM_LIB.SCM(SCH_1):PAGE13_I356@PURE_QUANTA.Q_RES(CHIPS)':
 'A': CDS_PINID='A';
NODE_NAME     R686 1
 '@SCM_LIB.SCM(SCH_1):PAGE14_I164@PURE_QUANTA.Q_RES(CHIPS)':
 'A': CDS_PINID='A';
NODE_NAME     R687 1
 '@SCM_LIB.SCM(SCH_1):PAGE14_I166@PURE_QUANTA.Q_RES(CHIPS)':
 'A': CDS_PINID='A';
NODE_NAME     R207 1
 '@SCM_LIB.SCM(SCH_1):PAGE15_I4@PURE_QUANTA.Q_RES(CHIPS)':
 'A': CDS_PINID='A';
NODE_NAME     R213 1
 '@SCM_LIB.SCM(SCH_1):PAGE15_I34@PURE_QUANTA.Q_RES(CHIPS)':
 'A': CDS_PINID='A';
NODE_NAME     L4 1
 '@SCM_LIB.SCM(SCH_1):PAGE15_I82@PURE_QUANTA.Q_INDUCTOR(CHIPS)':
 '1': CDS_PINID='\1\';
NODE_NAME     R717 1
 '@SCM_LIB.SCM(SCH_1):PAGE15_I174@PURE_QUANTA.Q_RES(CHIPS)':
 'A': CDS_PINID='A';
NODE_NAME     R789 1
 '@SCM_LIB.SCM(SCH_1):PAGE15_I219@PURE_QUANTA.Q_RES(CHIPS)':
 'A': CDS_PINID='A';
NODE_NAME     L12 1
 '@SCM_LIB.SCM(SCH_1):PAGE16_I99@PURE_QUANTA.Q_INDUCTOR(CHIPS)':
 '1': CDS_PINID='\1\';
NODE_NAME     C88 1
 '@SCM_LIB.SCM(SCH_1):PAGE16_I123@PURE_QUANTA.Q_CAP(CHIPS)':
 'A': CDS_PINID='A';
NODE_NAME     C94 1
 '@SCM_LIB.SCM(SCH_1):PAGE16_I124@PURE_QUANTA.Q_CAP(CHIPS)':
 'A': CDS_PINID='A';
NODE_NAME     C101 1
 '@SCM_LIB.SCM(SCH_1):PAGE16_I132@PURE_QUANTA.Q_CAP(CHIPS)':
 'A': CDS_PINID='A';
NODE_NAME     C110 1
 '@SCM_LIB.SCM(SCH_1):PAGE16_I133@PURE_QUANTA.Q_CAP(CHIPS)':
 'A': CDS_PINID='A';
NODE_NAME     C115 1
 '@SCM_LIB.SCM(SCH_1):PAGE16_I135@PURE_QUANTA.Q_CAP(CHIPS)':
 'A': CDS_PINID='A';
NODE_NAME     U5 H15
 '@SCM_LIB.SCM(SCH_1):PAGE16_I188@PURE_QUANTA.AST2600A3GP(CHIPS)':
 'PV33D_H15': CDS_PINID='PV33D_H15';
NODE_NAME     U5 H16
 '@SCM_LIB.SCM(SCH_1):PAGE16_I188@PURE_QUANTA.AST2600A3GP(CHIPS)':
 'PV33D_H16': CDS_PINID='PV33D_H16';
NODE_NAME     U5 H17
 '@SCM_LIB.SCM(SCH_1):PAGE16_I188@PURE_QUANTA.AST2600A3GP(CHIPS)':
 'PV33D_H17': CDS_PINID='PV33D_H17';
NODE_NAME     U5 N22
 '@SCM_LIB.SCM(SCH_1):PAGE16_I188@PURE_QUANTA.AST2600A3GP(CHIPS)':
 'PV33D_N22': CDS_PINID='PV33D_N22';
NODE_NAME     U5 P22
 '@SCM_LIB.SCM(SCH_1):PAGE16_I188@PURE_QUANTA.AST2600A3GP(CHIPS)':
 'PV33D_P22': CDS_PINID='PV33D_P22';
NODE_NAME     U5 R22
 '@SCM_LIB.SCM(SCH_1):PAGE16_I188@PURE_QUANTA.AST2600A3GP(CHIPS)':
 'PV33D_R22': CDS_PINID='PV33D_R22';
NODE_NAME     U5 T22
 '@SCM_LIB.SCM(SCH_1):PAGE16_I188@PURE_QUANTA.AST2600A3GP(CHIPS)':
 'PV33D_T22': CDS_PINID='PV33D_T22';
NODE_NAME     U5 W16
 '@SCM_LIB.SCM(SCH_1):PAGE16_I188@PURE_QUANTA.AST2600A3GP(CHIPS)':
 'PV33D_W16': CDS_PINID='PV33D_W16';
NODE_NAME     U5 W17
 '@SCM_LIB.SCM(SCH_1):PAGE16_I188@PURE_QUANTA.AST2600A3GP(CHIPS)':
 'PV33D_W17': CDS_PINID='PV33D_W17';
NODE_NAME     U5 W18
 '@SCM_LIB.SCM(SCH_1):PAGE16_I188@PURE_QUANTA.AST2600A3GP(CHIPS)':
 'PV33D_W18': CDS_PINID='PV33D_W18';
NODE_NAME     U5 W19
 '@SCM_LIB.SCM(SCH_1):PAGE16_I188@PURE_QUANTA.AST2600A3GP(CHIPS)':
 'PV33D_W19': CDS_PINID='PV33D_W19';
NODE_NAME     R231 1
 '@SCM_LIB.SCM(SCH_1):PAGE17_I131@PURE_QUANTA.Q_RES(CHIPS)':
 'A': CDS_PINID='A';
NODE_NAME     L9 1
 '@SCM_LIB.SCM(SCH_1):PAGE17_I142@PURE_QUANTA.Q_INDUCTOR(CHIPS)':
 '1': CDS_PINID='\1\';
NODE_NAME     L7 1
 '@SCM_LIB.SCM(SCH_1):PAGE17_I146@PURE_QUANTA.Q_INDUCTOR(CHIPS)':
 '1': CDS_PINID='\1\';
NODE_NAME     R646 2
 '@SCM_LIB.SCM(SCH_1):PAGE17_I279@PURE_QUANTA.Q_RES(CHIPS)':
 'B': CDS_PINID='B';
NODE_NAME     C228 1
 '@SCM_LIB.SCM(SCH_1):PAGE21_I21@PURE_QUANTA.Q_CAP(CHIPS)':
 'A': CDS_PINID='A';
NODE_NAME     R662 1
 '@SCM_LIB.SCM(SCH_1):PAGE21_I58@PURE_QUANTA.Q_RES(CHIPS)':
 'A': CDS_PINID='A';
NODE_NAME     R663 1
 '@SCM_LIB.SCM(SCH_1):PAGE21_I59@PURE_QUANTA.Q_RES(CHIPS)':
 'A': CDS_PINID='A';
NODE_NAME     R661 1
 '@SCM_LIB.SCM(SCH_1):PAGE21_I60@PURE_QUANTA.Q_RES(CHIPS)':
 'A': CDS_PINID='A';
NODE_NAME     R660 1
 '@SCM_LIB.SCM(SCH_1):PAGE21_I61@PURE_QUANTA.Q_RES(CHIPS)':
 'A': CDS_PINID='A';
NODE_NAME     R658 1
 '@SCM_LIB.SCM(SCH_1):PAGE21_I62@PURE_QUANTA.Q_RES(CHIPS)':
 'A': CDS_PINID='A';
NODE_NAME     R657 1
 '@SCM_LIB.SCM(SCH_1):PAGE21_I63@PURE_QUANTA.Q_RES(CHIPS)':
 'A': CDS_PINID='A';
NODE_NAME     R659 1
 '@SCM_LIB.SCM(SCH_1):PAGE21_I64@PURE_QUANTA.Q_RES(CHIPS)':
 'A': CDS_PINID='A';
NODE_NAME     R656 1
 '@SCM_LIB.SCM(SCH_1):PAGE21_I66@PURE_QUANTA.Q_RES(CHIPS)':
 'A': CDS_PINID='A';
NODE_NAME     R655 1
 '@SCM_LIB.SCM(SCH_1):PAGE21_I67@PURE_QUANTA.Q_RES(CHIPS)':
 'A': CDS_PINID='A';
NODE_NAME     C235 1
 '@SCM_LIB.SCM(SCH_1):PAGE21_I80@PURE_QUANTA.Q_CAP(CHIPS)':
 'A': CDS_PINID='A';
NODE_NAME     C234 1
 '@SCM_LIB.SCM(SCH_1):PAGE21_I81@PURE_QUANTA.Q_CAP(CHIPS)':
 'A': CDS_PINID='A';
NODE_NAME     C147 1
 '@SCM_LIB.SCM(SCH_1):PAGE22_I17@PURE_QUANTA.Q_CAP(CHIPS)':
 'A': CDS_PINID='A';
NODE_NAME     C34 1
 '@SCM_LIB.SCM(SCH_1):PAGE22_I42@PURE_QUANTA.Q_CAP(CHIPS)':
 'A': CDS_PINID='A';
NODE_NAME     R710 1
 '@SCM_LIB.SCM(SCH_1):PAGE22_I55@PURE_QUANTA.Q_RES(CHIPS)':
 'A': CDS_PINID='A';
NODE_NAME     C253 1
 '@SCM_LIB.SCM(SCH_1):PAGE22_I57@PURE_QUANTA.Q_CAP(CHIPS)':
 'A': CDS_PINID='A';
NODE_NAME     R124 1
 '@SCM_LIB.SCM(SCH_1):PAGE22_I67@PURE_QUANTA.Q_RES(CHIPS)':
 'A': CDS_PINID='A';
NODE_NAME     R633 1
 '@SCM_LIB.SCM(SCH_1):PAGE22_I81@PURE_QUANTA.Q_RES(CHIPS)':
 'A': CDS_PINID='A';
NODE_NAME     R751 1
 '@SCM_LIB.SCM(SCH_1):PAGE22_I83@PURE_QUANTA.Q_RES(CHIPS)':
 'A': CDS_PINID='A';
NODE_NAME     U6 5
 '@SCM_LIB.SCM(SCH_1):PAGE22_I87@PURE_QUANTA.74LVC2G07DW7(CHIPS)':
 'VCC': CDS_PINID='VCC';
NODE_NAME     U13 5
 '@SCM_LIB.SCM(SCH_1):PAGE22_I89@PURE_QUANTA.MC74VHC1G07DFT2G(CHIPS)':
 'VCC': CDS_PINID='VCC';
NODE_NAME     R563 1
 '@SCM_LIB.SCM(SCH_1):PAGE25_I3@PURE_QUANTA.Q_RES(CHIPS)':
 'A': CDS_PINID='A';
NODE_NAME     U44 5
 '@SCM_LIB.SCM(SCH_1):PAGE25_I61@PURE_QUANTA.SN74LVC1G07DCKR(CHIPS)':
 'VCC': CDS_PINID='VCC';
NODE_NAME     C304 1
 '@SCM_LIB.SCM(SCH_1):PAGE25_I65@PURE_QUANTA.Q_CAP(CHIPS)':
 'A': CDS_PINID='A';
NODE_NAME     R12 1
 '@SCM_LIB.SCM(SCH_1):PAGE26_I9@PURE_QUANTA.Q_RES(CHIPS)':
 'A': CDS_PINID='A';
NODE_NAME     R13 1
 '@SCM_LIB.SCM(SCH_1):PAGE26_I11@PURE_QUANTA.Q_RES(CHIPS)':
 'A': CDS_PINID='A';
NODE_NAME     R14 1
 '@SCM_LIB.SCM(SCH_1):PAGE26_I14@PURE_QUANTA.Q_RES(CHIPS)':
 'A': CDS_PINID='A';
NODE_NAME     U19 8
 '@SCM_LIB.SCM(SCH_1):PAGE26_I15@PURE_QUANTA.M24128BWDW6TP(CHIPS)':
 'VCC': CDS_PINID='VCC';
NODE_NAME     C192 1
 '@SCM_LIB.SCM(SCH_1):PAGE26_I17@PURE_QUANTA.Q_CAP(CHIPS)':
 'A': CDS_PINID='A';
NODE_NAME     R418 1
 '@SCM_LIB.SCM(SCH_1):PAGE26_I40@PURE_QUANTA.Q_RES(CHIPS)':
 'A': CDS_PINID='A';
NODE_NAME     R416 1
 '@SCM_LIB.SCM(SCH_1):PAGE26_I41@PURE_QUANTA.Q_RES(CHIPS)':
 'A': CDS_PINID='A';
NODE_NAME     C191 1
 '@SCM_LIB.SCM(SCH_1):PAGE26_I54@PURE_QUANTA.Q_CAP(CHIPS)':
 'A': CDS_PINID='A';
NODE_NAME     R269 1
 '@SCM_LIB.SCM(SCH_1):PAGE27_I84@PURE_QUANTA.Q_RES(CHIPS)':
 'A': CDS_PINID='A';
NODE_NAME     R267 1
 '@SCM_LIB.SCM(SCH_1):PAGE27_I85@PURE_QUANTA.Q_RES(CHIPS)':
 'A': CDS_PINID='A';
NODE_NAME     R268 1
 '@SCM_LIB.SCM(SCH_1):PAGE27_I86@PURE_QUANTA.Q_RES(CHIPS)':
 'A': CDS_PINID='A';
NODE_NAME     R265 1
 '@SCM_LIB.SCM(SCH_1):PAGE27_I88@PURE_QUANTA.Q_RES(CHIPS)':
 'A': CDS_PINID='A';
NODE_NAME     R264 1
 '@SCM_LIB.SCM(SCH_1):PAGE27_I89@PURE_QUANTA.Q_RES(CHIPS)':
 'A': CDS_PINID='A';
NODE_NAME     R262 1
 '@SCM_LIB.SCM(SCH_1):PAGE27_I93@PURE_QUANTA.Q_RES(CHIPS)':
 'A': CDS_PINID='A';
NODE_NAME     R261 1
 '@SCM_LIB.SCM(SCH_1):PAGE27_I94@PURE_QUANTA.Q_RES(CHIPS)':
 'A': CDS_PINID='A';
NODE_NAME     R266 1
 '@SCM_LIB.SCM(SCH_1):PAGE27_I95@PURE_QUANTA.Q_RES(CHIPS)':
 'A': CDS_PINID='A';
NODE_NAME     R259 1
 '@SCM_LIB.SCM(SCH_1):PAGE27_I96@PURE_QUANTA.Q_RES(CHIPS)':
 'A': CDS_PINID='A';
NODE_NAME     R260 1
 '@SCM_LIB.SCM(SCH_1):PAGE27_I97@PURE_QUANTA.Q_RES(CHIPS)':
 'A': CDS_PINID='A';
NODE_NAME     R258 1
 '@SCM_LIB.SCM(SCH_1):PAGE27_I98@PURE_QUANTA.Q_RES(CHIPS)':
 'A': CDS_PINID='A';
NODE_NAME     R257 1
 '@SCM_LIB.SCM(SCH_1):PAGE27_I99@PURE_QUANTA.Q_RES(CHIPS)':
 'A': CDS_PINID='A';
NODE_NAME     R256 1
 '@SCM_LIB.SCM(SCH_1):PAGE27_I100@PURE_QUANTA.Q_RES(CHIPS)':
 'A': CDS_PINID='A';
NODE_NAME     R254 1
 '@SCM_LIB.SCM(SCH_1):PAGE27_I101@PURE_QUANTA.Q_RES(CHIPS)':
 'A': CDS_PINID='A';
NODE_NAME     R255 1
 '@SCM_LIB.SCM(SCH_1):PAGE27_I102@PURE_QUANTA.Q_RES(CHIPS)':
 'A': CDS_PINID='A';
NODE_NAME     R253 1
 '@SCM_LIB.SCM(SCH_1):PAGE27_I103@PURE_QUANTA.Q_RES(CHIPS)':
 'A': CDS_PINID='A';
NODE_NAME     R252 1
 '@SCM_LIB.SCM(SCH_1):PAGE27_I105@PURE_QUANTA.Q_RES(CHIPS)':
 'A': CDS_PINID='A';
NODE_NAME     R250 1
 '@SCM_LIB.SCM(SCH_1):PAGE27_I106@PURE_QUANTA.Q_RES(CHIPS)':
 'A': CDS_PINID='A';
NODE_NAME     R248 1
 '@SCM_LIB.SCM(SCH_1):PAGE27_I107@PURE_QUANTA.Q_RES(CHIPS)':
 'A': CDS_PINID='A';
NODE_NAME     R249 1
 '@SCM_LIB.SCM(SCH_1):PAGE27_I108@PURE_QUANTA.Q_RES(CHIPS)':
 'A': CDS_PINID='A';
NODE_NAME     R247 1
 '@SCM_LIB.SCM(SCH_1):PAGE27_I109@PURE_QUANTA.Q_RES(CHIPS)':
 'A': CDS_PINID='A';
NODE_NAME     R246 1
 '@SCM_LIB.SCM(SCH_1):PAGE27_I145@PURE_QUANTA.Q_RES(CHIPS)':
 'A': CDS_PINID='A';
NODE_NAME     R245 1
 '@SCM_LIB.SCM(SCH_1):PAGE27_I146@PURE_QUANTA.Q_RES(CHIPS)':
 'A': CDS_PINID='A';
NODE_NAME     R244 1
 '@SCM_LIB.SCM(SCH_1):PAGE27_I147@PURE_QUANTA.Q_RES(CHIPS)':
 'A': CDS_PINID='A';
NODE_NAME     R699 1
 '@SCM_LIB.SCM(SCH_1):PAGE27_I163@PURE_QUANTA.Q_RES(CHIPS)':
 'A': CDS_PINID='A';
NODE_NAME     R842 1
 '@SCM_LIB.SCM(SCH_1):PAGE27_I168@PURE_QUANTA.Q_RES(CHIPS)':
 'A': CDS_PINID='A';
NODE_NAME     R843 1
 '@SCM_LIB.SCM(SCH_1):PAGE27_I177@PURE_QUANTA.Q_RES(CHIPS)':
 'A': CDS_PINID='A';
NODE_NAME     R844 1
 '@SCM_LIB.SCM(SCH_1):PAGE27_I179@PURE_QUANTA.Q_RES(CHIPS)':
 'A': CDS_PINID='A';
NODE_NAME     R846 1
 '@SCM_LIB.SCM(SCH_1):PAGE27_I181@PURE_QUANTA.Q_RES(CHIPS)':
 'A': CDS_PINID='A';
NODE_NAME     R848 1
 '@SCM_LIB.SCM(SCH_1):PAGE27_I182@PURE_QUANTA.Q_RES(CHIPS)':
 'A': CDS_PINID='A';
NODE_NAME     R851 1
 '@SCM_LIB.SCM(SCH_1):PAGE27_I184@PURE_QUANTA.Q_RES(CHIPS)':
 'A': CDS_PINID='A';
NODE_NAME     R430 1
 '@SCM_LIB.SCM(SCH_1):PAGE27_I188@PURE_QUANTA.Q_RES(CHIPS)':
 'A': CDS_PINID='A';
NODE_NAME     R42 1
 '@SCM_LIB.SCM(SCH_1):PAGE27_I222@PURE_QUANTA.Q_RES(CHIPS)':
 'A': CDS_PINID='A';
NODE_NAME     R383 1
 '@SCM_LIB.SCM(SCH_1):PAGE28_I42@PURE_QUANTA.Q_RES(CHIPS)':
 'A': CDS_PINID='A';
NODE_NAME     R299 1
 '@SCM_LIB.SCM(SCH_1):PAGE28_I91@PURE_QUANTA.Q_RES(CHIPS)':
 'A': CDS_PINID='A';
NODE_NAME     R298 1
 '@SCM_LIB.SCM(SCH_1):PAGE28_I96@PURE_QUANTA.Q_RES(CHIPS)':
 'A': CDS_PINID='A';
NODE_NAME     C159 1
 '@SCM_LIB.SCM(SCH_1):PAGE28_I98@PURE_QUANTA.Q_CAP(CHIPS)':
 'A': CDS_PINID='A';
NODE_NAME     U37 1
 '@SCM_LIB.SCM(SCH_1):PAGE28_I99@PURE_QUANTA.PCA9517ADP(CHIPS)':
 'VCCA': CDS_PINID='VCCA';
NODE_NAME     U37 8
 '@SCM_LIB.SCM(SCH_1):PAGE28_I99@PURE_QUANTA.PCA9517ADP(CHIPS)':
 'VCCB': CDS_PINID='VCCB';
NODE_NAME     C158 1
 '@SCM_LIB.SCM(SCH_1):PAGE28_I101@PURE_QUANTA.Q_CAP(CHIPS)':
 'A': CDS_PINID='A';
NODE_NAME     R295 1
 '@SCM_LIB.SCM(SCH_1):PAGE28_I113@PURE_QUANTA.Q_RES(CHIPS)':
 'A': CDS_PINID='A';
NODE_NAME     U40 24
 '@SCM_LIB.SCM(SCH_1):PAGE28_I141@PURE_QUANTA.PCA9555PW(CHIPS)':
 'VDD': CDS_PINID='VDD';
NODE_NAME     C300 1
 '@SCM_LIB.SCM(SCH_1):PAGE28_I146@PURE_QUANTA.Q_CAP(CHIPS)':
 'A': CDS_PINID='A';
NODE_NAME     R667 1
 '@SCM_LIB.SCM(SCH_1):PAGE28_I147@PURE_QUANTA.Q_RES(CHIPS)':
 'A': CDS_PINID='A';
NODE_NAME     R736 1
 '@SCM_LIB.SCM(SCH_1):PAGE28_I162@PURE_QUANTA.Q_RES(CHIPS)':
 'A': CDS_PINID='A';
NODE_NAME     R735 1
 '@SCM_LIB.SCM(SCH_1):PAGE28_I166@PURE_QUANTA.Q_RES(CHIPS)':
 'A': CDS_PINID='A';
NODE_NAME     R740 1
 '@SCM_LIB.SCM(SCH_1):PAGE28_I168@PURE_QUANTA.Q_RES(CHIPS)':
 'A': CDS_PINID='A';
NODE_NAME     R739 1
 '@SCM_LIB.SCM(SCH_1):PAGE28_I169@PURE_QUANTA.Q_RES(CHIPS)':
 'A': CDS_PINID='A';
NODE_NAME     R738 1
 '@SCM_LIB.SCM(SCH_1):PAGE28_I171@PURE_QUANTA.Q_RES(CHIPS)':
 'A': CDS_PINID='A';
NODE_NAME     U23 5
 '@SCM_LIB.SCM(SCH_1):PAGE28_I180@PURE_QUANTA.74LVC1G07W57(CHIPS)':
 'VCC': CDS_PINID='VCC';
NODE_NAME     C157 1
 '@SCM_LIB.SCM(SCH_1):PAGE28_I181@PURE_QUANTA.Q_CAP(CHIPS)':
 'A': CDS_PINID='A';
NODE_NAME     C237 1
 '@SCM_LIB.SCM(SCH_1):PAGE29_I146@PURE_QUANTA.Q_CAP(CHIPS)':
 'A': CDS_PINID='A';
NODE_NAME     C236 1
 '@SCM_LIB.SCM(SCH_1):PAGE29_I148@PURE_QUANTA.Q_CAP(CHIPS)':
 'A': CDS_PINID='A';
NODE_NAME     C219 1
 '@SCM_LIB.SCM(SCH_1):PAGE29_I150@PURE_QUANTA.Q_CAP(CHIPS)':
 'A': CDS_PINID='A';
NODE_NAME     R712 1
 '@SCM_LIB.SCM(SCH_1):PAGE29_I153@PURE_QUANTA.Q_RES(CHIPS)':
 'A': CDS_PINID='A';
NODE_NAME     R274 1
 '@SCM_LIB.SCM(SCH_1):PAGE29_I157@PURE_QUANTA.Q_RES(CHIPS)':
 'A': CDS_PINID='A';
NODE_NAME     C149 1
 '@SCM_LIB.SCM(SCH_1):PAGE29_I161@PURE_QUANTA.Q_CAP(CHIPS)':
 'A': CDS_PINID='A';
NODE_NAME     U36 5
 '@SCM_LIB.SCM(SCH_1):PAGE29_I164@PURE_QUANTA.74HC1G126GW(CHIPS)':
 '5': CDS_PINID='\5\';
NODE_NAME     R193 1
 '@SCM_LIB.SCM(SCH_1):PAGE29_I166@PURE_QUANTA.Q_RES(CHIPS)':
 'A': CDS_PINID='A';
NODE_NAME     C148 1
 '@SCM_LIB.SCM(SCH_1):PAGE29_I172@PURE_QUANTA.Q_CAP(CHIPS)':
 'A': CDS_PINID='A';
NODE_NAME     U29 5
 '@SCM_LIB.SCM(SCH_1):PAGE29_I174@PURE_QUANTA.74HC1G126GW(CHIPS)':
 '5': CDS_PINID='\5\';
NODE_NAME     R730 1
 '@SCM_LIB.SCM(SCH_1):PAGE29_I204@PURE_QUANTA.Q_RES(CHIPS)':
 'A': CDS_PINID='A';
NODE_NAME     U22 1
 '@SCM_LIB.SCM(SCH_1):PAGE29_I206@PURE_QUANTA.PI3PCIE3212ZBEX(CHIPS)':
 'VDD0': CDS_PINID='VDD0';
NODE_NAME     U22 6
 '@SCM_LIB.SCM(SCH_1):PAGE29_I206@PURE_QUANTA.PI3PCIE3212ZBEX(CHIPS)':
 'VDD1': CDS_PINID='VDD1';
NODE_NAME     U22 10
 '@SCM_LIB.SCM(SCH_1):PAGE29_I206@PURE_QUANTA.PI3PCIE3212ZBEX(CHIPS)':
 'VDD2': CDS_PINID='VDD2';
NODE_NAME     R67 1
 '@SCM_LIB.SCM(SCH_1):PAGE30_I146@PURE_QUANTA.Q_RES(CHIPS)':
 'A': CDS_PINID='A';
NODE_NAME     C175 1
 '@SCM_LIB.SCM(SCH_1):PAGE30_I151@PURE_QUANTA.Q_CAP(CHIPS)':
 'A': CDS_PINID='A';
NODE_NAME     R737 1
 '@SCM_LIB.SCM(SCH_1):PAGE30_I192@PURE_QUANTA.Q_RES(CHIPS)':
 'A': CDS_PINID='A';
NODE_NAME     R742 1
 '@SCM_LIB.SCM(SCH_1):PAGE30_I195@PURE_QUANTA.Q_RES(CHIPS)':
 'A': CDS_PINID='A';
NODE_NAME     R741 1
 '@SCM_LIB.SCM(SCH_1):PAGE30_I197@PURE_QUANTA.Q_RES(CHIPS)':
 'A': CDS_PINID='A';
NODE_NAME     C268 1
 '@SCM_LIB.SCM(SCH_1):PAGE30_I229@PURE_QUANTA.Q_CAP(CHIPS)':
 'A': CDS_PINID='A';
NODE_NAME     R72 1
 '@SCM_LIB.SCM(SCH_1):PAGE30_I231@PURE_QUANTA.Q_RES(CHIPS)':
 'A': CDS_PINID='A';
NODE_NAME     R765 1
 '@SCM_LIB.SCM(SCH_1):PAGE30_I239@PURE_QUANTA.Q_RES(CHIPS)':
 'A': CDS_PINID='A';
NODE_NAME     U24 5
 '@SCM_LIB.SCM(SCH_1):PAGE30_I246@PURE_QUANTA.74LVC2G07DW7(CHIPS)':
 'VCC': CDS_PINID='VCC';
NODE_NAME     U47 5
 '@SCM_LIB.SCM(SCH_1):PAGE30_I247@PURE_QUANTA.74LVC2G07DW7(CHIPS)':
 'VCC': CDS_PINID='VCC';
NODE_NAME     U2 8
 '@SCM_LIB.SCM(SCH_1):PAGE30_I250@PURE_QUANTA.FSA3357K8X(CHIPS)':
 'VCC': CDS_PINID='VCC';
NODE_NAME     U3 8
 '@SCM_LIB.SCM(SCH_1):PAGE30_I251@PURE_QUANTA.FSA3357K8X(CHIPS)':
 'VCC': CDS_PINID='VCC';
NODE_NAME     C20 1
 '@SCM_LIB.SCM(SCH_1):PAGE30_I254@PURE_QUANTA.Q_CAP(CHIPS)':
 'A': CDS_PINID='A';
NODE_NAME     C19 1
 '@SCM_LIB.SCM(SCH_1):PAGE30_I261@PURE_QUANTA.Q_CAP(CHIPS)':
 'A': CDS_PINID='A';
NODE_NAME     C501 1
 '@SCM_LIB.SCM(SCH_1):PAGE31_I11@PURE_QUANTA.Q_CAP(CHIPS)':
 'A': CDS_PINID='A';
NODE_NAME     C500 1
 '@SCM_LIB.SCM(SCH_1):PAGE31_I17@PURE_QUANTA.Q_CAP(CHIPS)':
 'A': CDS_PINID='A';
NODE_NAME     U50 5
 '@SCM_LIB.SCM(SCH_1):PAGE31_I23@PURE_QUANTA.NC7SB3157(CHIPS)':
 'VCC': CDS_PINID='VCC';
NODE_NAME     U51 5
 '@SCM_LIB.SCM(SCH_1):PAGE31_I24@PURE_QUANTA.NC7SB3157(CHIPS)':
 'VCC': CDS_PINID='VCC';
NODE_NAME     R226 1
 '@SCM_LIB.SCM(SCH_1):PAGE32_I103@PURE_QUANTA.Q_RES(CHIPS)':
 'A': CDS_PINID='A';
NODE_NAME     R227 1
 '@SCM_LIB.SCM(SCH_1):PAGE32_I104@PURE_QUANTA.Q_RES(CHIPS)':
 'A': CDS_PINID='A';
NODE_NAME     R230 1
 '@SCM_LIB.SCM(SCH_1):PAGE32_I105@PURE_QUANTA.Q_RES(CHIPS)':
 'A': CDS_PINID='A';
NODE_NAME     R625 1
 '@SCM_LIB.SCM(SCH_1):PAGE34_I17@PURE_QUANTA.Q_RES(CHIPS)':
 'A': CDS_PINID='A';
NODE_NAME     R806 1
 '@SCM_LIB.SCM(SCH_1):PAGE34_I119@PURE_QUANTA.Q_RES(CHIPS)':
 'A': CDS_PINID='A';
NODE_NAME     C318 1
 '@SCM_LIB.SCM(SCH_1):PAGE34_I122@PURE_QUANTA.Q_CAP(CHIPS)':
 'A': CDS_PINID='A';
NODE_NAME     OSC2 4
 '@SCM_LIB.SCM(SCH_1):PAGE34_I127@PURE_QUANTA.OSC4_7X25000018(CHIPS)':
 'VDD': CDS_PINID='VDD';
NODE_NAME     R305 1
 '@SCM_LIB.SCM(SCH_1):PAGE41_I71@PURE_QUANTA.Q_RES(CHIPS)':
 'A': CDS_PINID='A';
NODE_NAME     R525 1
 '@SCM_LIB.SCM(SCH_1):PAGE41_I72@PURE_QUANTA.Q_RES(CHIPS)':
 'A': CDS_PINID='A';
NODE_NAME     R304 1
 '@SCM_LIB.SCM(SCH_1):PAGE41_I73@PURE_QUANTA.Q_RES(CHIPS)':
 'A': CDS_PINID='A';
NODE_NAME     R308 1
 '@SCM_LIB.SCM(SCH_1):PAGE41_I74@PURE_QUANTA.Q_RES(CHIPS)':
 'A': CDS_PINID='A';
NODE_NAME     R301 1
 '@SCM_LIB.SCM(SCH_1):PAGE41_I75@PURE_QUANTA.Q_RES(CHIPS)':
 'A': CDS_PINID='A';
NODE_NAME     R307 1
 '@SCM_LIB.SCM(SCH_1):PAGE41_I76@PURE_QUANTA.Q_RES(CHIPS)':
 'A': CDS_PINID='A';
NODE_NAME     C145 1
 '@SCM_LIB.SCM(SCH_1):PAGE41_I99@PURE_QUANTA.Q_CAP(CHIPS)':
 'A': CDS_PINID='A';
NODE_NAME     C194 1
 '@SCM_LIB.SCM(SCH_1):PAGE41_I101@PURE_QUANTA.Q_CAP(CHIPS)':
 'A': CDS_PINID='A';
NODE_NAME     L19 1
 '@SCM_LIB.SCM(SCH_1):PAGE41_I107@PURE_QUANTA.Q_INDUCTOR(CHIPS)':
 '1': CDS_PINID='\1\';
NODE_NAME     R627 1
 '@SCM_LIB.SCM(SCH_1):PAGE42_I7@PURE_QUANTA.Q_RES(CHIPS)':
 'A': CDS_PINID='A';
NODE_NAME     R621 1
 '@SCM_LIB.SCM(SCH_1):PAGE42_I13@PURE_QUANTA.Q_RES(CHIPS)':
 'A': CDS_PINID='A';
NODE_NAME     R608 1
 '@SCM_LIB.SCM(SCH_1):PAGE42_I27@PURE_QUANTA.Q_RES(CHIPS)':
 'A': CDS_PINID='A';
NODE_NAME     R607 1
 '@SCM_LIB.SCM(SCH_1):PAGE42_I29@PURE_QUANTA.Q_RES(CHIPS)':
 'A': CDS_PINID='A';
NODE_NAME     R595 1
 '@SCM_LIB.SCM(SCH_1):PAGE42_I37@PURE_QUANTA.Q_RES(CHIPS)':
 'A': CDS_PINID='A';
NODE_NAME     R593 1
 '@SCM_LIB.SCM(SCH_1):PAGE42_I39@PURE_QUANTA.Q_RES(CHIPS)':
 'A': CDS_PINID='A';
NODE_NAME     R641 1
 '@SCM_LIB.SCM(SCH_1):PAGE42_I53@PURE_QUANTA.Q_RES(CHIPS)':
 'A': CDS_PINID='A';
NODE_NAME     R640 1
 '@SCM_LIB.SCM(SCH_1):PAGE42_I56@PURE_QUANTA.Q_RES(CHIPS)':
 'A': CDS_PINID='A';
NODE_NAME     R749 1
 '@SCM_LIB.SCM(SCH_1):PAGE42_I61@PURE_QUANTA.Q_RES(CHIPS)':
 'A': CDS_PINID='A';
NODE_NAME     R835 1
 '@SCM_LIB.SCM(SCH_1):PAGE42_I63@PURE_QUANTA.Q_RES(CHIPS)':
 'A': CDS_PINID='A';
NODE_NAME     R319 1
 '@SCM_LIB.SCM(SCH_1):PAGE42_I65@PURE_QUANTA.Q_RES(CHIPS)':
 'A': CDS_PINID='A';
NODE_NAME     U30 16
 '@SCM_LIB.SCM(SCH_1):PAGE44_I271@PURE_QUANTA.IDTQS3VH257PAG(CHIPS)':
 'VCC': CDS_PINID='VCC';
NODE_NAME     C255 1
 '@SCM_LIB.SCM(SCH_1):PAGE44_I278@PURE_QUANTA.Q_CAP(CHIPS)':
 'A': CDS_PINID='A';
NODE_NAME     C146 1
 '@SCM_LIB.SCM(SCH_1):PAGE44_I292@PURE_QUANTA.Q_CAP(CHIPS)':
 'A': CDS_PINID='A';
NODE_NAME     U21 16
 '@SCM_LIB.SCM(SCH_1):PAGE44_I296@PURE_QUANTA.IDTQS3VH257PAG(CHIPS)':
 'VCC': CDS_PINID='VCC';
NODE_NAME     R870 1
 '@SCM_LIB.SCM(SCH_1):PAGE44_I315@PURE_QUANTA.Q_RES(CHIPS)':
 'A': CDS_PINID='A';
NODE_NAME     R488 1
 '@SCM_LIB.SCM(SCH_1):PAGE45_I33@PURE_QUANTA.Q_RES(CHIPS)':
 'A': CDS_PINID='A';
NODE_NAME     R490 1
 '@SCM_LIB.SCM(SCH_1):PAGE45_I34@PURE_QUANTA.Q_RES(CHIPS)':
 'A': CDS_PINID='A';
NODE_NAME     R492 1
 '@SCM_LIB.SCM(SCH_1):PAGE45_I35@PURE_QUANTA.Q_RES(CHIPS)':
 'A': CDS_PINID='A';
NODE_NAME     C244 1
 '@SCM_LIB.SCM(SCH_1):PAGE45_I42@PURE_QUANTA.Q_CAP(CHIPS)':
 'A': CDS_PINID='A';
NODE_NAME     C246 1
 '@SCM_LIB.SCM(SCH_1):PAGE45_I45@PURE_QUANTA.Q_CAP(CHIPS)':
 'A': CDS_PINID='A';
NODE_NAME     R496 1
 '@SCM_LIB.SCM(SCH_1):PAGE45_I48@PURE_QUANTA.Q_RES(CHIPS)':
 'A': CDS_PINID='A';
NODE_NAME     J40 2
 '@SCM_LIB.SCM(SCH_1):PAGE45_I53@PURE_QUANTA.SCONN16_ACASPI006P06(CHIPS)':
 'VCC': CDS_PINID='VCC';
NODE_NAME     J5 7
 '@SCM_LIB.SCM(SCH_1):PAGE46_I56@PURE_QUANTA.SCONN11_9192031111LF(CHIPS)':
 '7': CDS_PINID='\7\';
NODE_NAME     C249 1
 '@SCM_LIB.SCM(SCH_1):PAGE46_I67@PURE_QUANTA.Q_CAP(CHIPS)':
 'A': CDS_PINID='A';
NODE_NAME     C248 1
 '@SCM_LIB.SCM(SCH_1):PAGE46_I69@PURE_QUANTA.Q_CAP(CHIPS)':
 'A': CDS_PINID='A';
NODE_NAME     R464 1
 '@SCM_LIB.SCM(SCH_1):PAGE46_I75@PURE_QUANTA.Q_RES(CHIPS)':
 'A': CDS_PINID='A';
NODE_NAME     R497 1
 '@SCM_LIB.SCM(SCH_1):PAGE46_I78@PURE_QUANTA.Q_RES(CHIPS)':
 'A': CDS_PINID='A';
NODE_NAME     R59 1
 '@SCM_LIB.SCM(SCH_1):PAGE46_I98@PURE_QUANTA.Q_RES(CHIPS)':
 'A': CDS_PINID='A';
NODE_NAME     C144 1
 '@SCM_LIB.SCM(SCH_1):PAGE46_I102@PURE_QUANTA.Q_CAP(CHIPS)':
 'A': CDS_PINID='A';
NODE_NAME     R50 1
 '@SCM_LIB.SCM(SCH_1):PAGE46_I104@PURE_QUANTA.Q_RES(CHIPS)':
 'A': CDS_PINID='A';
NODE_NAME     C143 1
 '@SCM_LIB.SCM(SCH_1):PAGE46_I108@PURE_QUANTA.Q_CAP(CHIPS)':
 'A': CDS_PINID='A';
NODE_NAME     J10 7
 '@SCM_LIB.SCM(SCH_1):PAGE46_I113@PURE_QUANTA.SCONN11_9192031111LF(CHIPS)':
 '7': CDS_PINID='\7\';
NODE_NAME     R136 1
 '@SCM_LIB.SCM(SCH_1):PAGE46_I132@PURE_QUANTA.Q_RES(CHIPS)':
 'A': CDS_PINID='A';
NODE_NAME     R126 2
 '@SCM_LIB.SCM(SCH_1):PAGE46_I134@PURE_QUANTA.Q_RES(CHIPS)':
 'B': CDS_PINID='B';
NODE_NAME     U9 5
 '@SCM_LIB.SCM(SCH_1):PAGE49_I5@PURE_QUANTA.MC74VHC1G32DTT1G(CHIPS)':
 'VCC': CDS_PINID='VCC';
NODE_NAME     U8 5
 '@SCM_LIB.SCM(SCH_1):PAGE49_I11@PURE_QUANTA.74LVC1G126SE7(CHIPS)':
 'VCC': CDS_PINID='VCC';
NODE_NAME     C274 1
 '@SCM_LIB.SCM(SCH_1):PAGE49_I13@PURE_QUANTA.Q_CAP(CHIPS)':
 'A': CDS_PINID='A';
NODE_NAME     D19 A
 '@SCM_LIB.SCM(SCH_1):PAGE49_I50@PURE_QUANTA.Q_LED(CHIPS)':
 'A': CDS_PINID='A';
NODE_NAME     D18 A
 '@SCM_LIB.SCM(SCH_1):PAGE49_I51@PURE_QUANTA.Q_LED(CHIPS)':
 'A': CDS_PINID='A';
NODE_NAME     C276 1
 '@SCM_LIB.SCM(SCH_1):PAGE49_I75@PURE_QUANTA.Q_CAP(CHIPS)':
 'A': CDS_PINID='A';
NODE_NAME     R43 2
 '@SCM_LIB.SCM(SCH_1):PAGE49_I79@PURE_QUANTA.Q_RES(CHIPS)':
 'B': CDS_PINID='B';
NODE_NAME     C200 1
 '@SCM_LIB.SCM(SCH_1):PAGE50_I43@PURE_QUANTA.Q_CAP(CHIPS)':
 'A': CDS_PINID='A';
NODE_NAME     U32 5
 '@SCM_LIB.SCM(SCH_1):PAGE50_I49@PURE_QUANTA.74LVC1G17GW(CHIPS)':
 'VCC': CDS_PINID='VCC';
NODE_NAME     C201 1
 '@SCM_LIB.SCM(SCH_1):PAGE50_I51@PURE_QUANTA.Q_CAP(CHIPS)':
 'A': CDS_PINID='A';
NODE_NAME     R504 1
 '@SCM_LIB.SCM(SCH_1):PAGE50_I82@PURE_QUANTA.Q_RES(CHIPS)':
 'A': CDS_PINID='A';
NODE_NAME     R768 1
 '@SCM_LIB.SCM(SCH_1):PAGE50_I89@PURE_QUANTA.Q_RES(CHIPS)':
 'A': CDS_PINID='A';
NODE_NAME     U31 5
 '@SCM_LIB.SCM(SCH_1):PAGE50_I151@PURE_QUANTA.74LVC1G07GW(CHIPS)':
 'VCC': CDS_PINID='VCC';
NODE_NAME     U48 2
 '@SCM_LIB.SCM(SCH_1):PAGE50_I161@PURE_QUANTA.BAS70057F(CHIPS)':
 'A': CDS_PINID='A';
NODE_NAME     PR242 1
 '@SCM_LIB.SCM(SCH_1):PAGE52_I13@PURE_QUANTA.Q_RES(CHIPS)':
 'A': CDS_PINID='A';
NODE_NAME     PC225 1
 '@SCM_LIB.SCM(SCH_1):PAGE52_I23@PURE_QUANTA.Q_CAP(CHIPS)':
 'A': CDS_PINID='A';
NODE_NAME     PR534 2
 '@SCM_LIB.SCM(SCH_1):PAGE52_I25@PURE_QUANTA.Q_RES(CHIPS)':
 'B': CDS_PINID='B';
NODE_NAME     PC226 1
 '@SCM_LIB.SCM(SCH_1):PAGE52_I35@PURE_QUANTA.Q_CAP(CHIPS)':
 'A': CDS_PINID='A';
NODE_NAME     PC227 1
 '@SCM_LIB.SCM(SCH_1):PAGE52_I36@PURE_QUANTA.Q_CAP(CHIPS)':
 'A': CDS_PINID='A';
NODE_NAME     PC228 1
 '@SCM_LIB.SCM(SCH_1):PAGE52_I37@PURE_QUANTA.Q_CAP(CHIPS)':
 'A': CDS_PINID='A';
NODE_NAME     PC229 1
 '@SCM_LIB.SCM(SCH_1):PAGE52_I38@PURE_QUANTA.Q_CAP(CHIPS)':
 'A': CDS_PINID='A';
NODE_NAME     C240 1
 '@SCM_LIB.SCM(SCH_1):PAGE52_I63@PURE_QUANTA.Q_CAP(CHIPS)':
 'A': CDS_PINID='A';
NODE_NAME     U14 5
 '@SCM_LIB.SCM(SCH_1):PAGE52_I79@PURE_QUANTA.AP22811AW57(CHIPS)':
 'IN': CDS_PINID='\in\';
NODE_NAME     PC239 2
 '@SCM_LIB.SCM(SCH_1):PAGE52_I91@PURE_QUANTA.Q_CAP(CHIPS)':
 'B': CDS_PINID='B';
NODE_NAME     PL35 2
 '@SCM_LIB.SCM(SCH_1):PAGE52_I92@PURE_QUANTA.Q_INDUCTOR(CHIPS)':
 '2': CDS_PINID='\2\';
NODE_NAME     U39 7
 '@SCM_LIB.SCM(SCH_1):PAGE53_I60@PURE_QUANTA.RT9059GQW(CHIPS)':
 'VIN1': CDS_PINID='VIN1';
NODE_NAME     U39 8
 '@SCM_LIB.SCM(SCH_1):PAGE53_I60@PURE_QUANTA.RT9059GQW(CHIPS)':
 'VIN2': CDS_PINID='VIN2';
NODE_NAME     U39 9
 '@SCM_LIB.SCM(SCH_1):PAGE53_I60@PURE_QUANTA.RT9059GQW(CHIPS)':
 'VIN3': CDS_PINID='VIN3';
NODE_NAME     U41 7
 '@SCM_LIB.SCM(SCH_1):PAGE54_I96@PURE_QUANTA.RT9059GQW(CHIPS)':
 'VIN1': CDS_PINID='VIN1';
NODE_NAME     U41 8
 '@SCM_LIB.SCM(SCH_1):PAGE54_I96@PURE_QUANTA.RT9059GQW(CHIPS)':
 'VIN2': CDS_PINID='VIN2';
NODE_NAME     U41 9
 '@SCM_LIB.SCM(SCH_1):PAGE54_I96@PURE_QUANTA.RT9059GQW(CHIPS)':
 'VIN3': CDS_PINID='VIN3';
NODE_NAME     PR498 1
 '@SCM_LIB.SCM(SCH_1):PAGE55_I18@PURE_QUANTA.Q_RES(CHIPS)':
 'A': CDS_PINID='A';
NODE_NAME     PR274 1
 '@SCM_LIB.SCM(SCH_1):PAGE55_I45@PURE_QUANTA.Q_RES(CHIPS)':
 'A': CDS_PINID='A';
NODE_NAME     PR500 1
 '@SCM_LIB.SCM(SCH_1):PAGE56_I18@PURE_QUANTA.Q_RES(CHIPS)':
 'A': CDS_PINID='A';
NODE_NAME     PR193 1
 '@SCM_LIB.SCM(SCH_1):PAGE56_I47@PURE_QUANTA.Q_RES(CHIPS)':
 'A': CDS_PINID='A';
NODE_NAME     R52 1
 '@SCM_LIB.SCM(SCH_1):PAGE26_I67@PURE_QUANTA.Q_RES(CHIPS)':
 'A': CDS_PINID='A';
NODE_NAME     R400 1
 '@SCM_LIB.SCM(SCH_1):PAGE12_I454@PURE_QUANTA.Q_RES(CHIPS)':
 'A': CDS_PINID='A';
NODE_NAME     C293 1
 '@SCM_LIB.SCM(SCH_1):PAGE54_I106@PURE_QUANTA.Q_CAP(CHIPS)':
 'A': CDS_PINID='A';
NODE_NAME     R406 1
 '@SCM_LIB.SCM(SCH_1):PAGE54_I108@PURE_QUANTA.Q_RES(CHIPS)':
 'A': CDS_PINID='A';
NODE_NAME     R403 1
 '@SCM_LIB.SCM(SCH_1):PAGE53_I68@PURE_QUANTA.Q_RES(CHIPS)':
 'A': CDS_PINID='A';
NODE_NAME     C288 1
 '@SCM_LIB.SCM(SCH_1):PAGE53_I71@PURE_QUANTA.Q_CAP(CHIPS)':
 'A': CDS_PINID='A';
NODE_NAME     R408 1
 '@SCM_LIB.SCM(SCH_1):PAGE46_I139@PURE_QUANTA.Q_RES(CHIPS)':
 'A': CDS_PINID='A';
NODE_NAME     R414 1
 '@SCM_LIB.SCM(SCH_1):PAGE46_I140@PURE_QUANTA.Q_RES(CHIPS)':
 'A': CDS_PINID='A';
NODE_NAME     R140 1
 '@SCM_LIB.SCM(SCH_1):PAGE27_I228@PURE_QUANTA.Q_RES(CHIPS)':
 'A': CDS_PINID='A';
NODE_NAME     R753 1
 '@SCM_LIB.SCM(SCH_1):PAGE27_I233@PURE_QUANTA.Q_RES(CHIPS)':
 'A': CDS_PINID='A';
NODE_NAME     D20 1
 '@SCM_LIB.SCM(SCH_1):PAGE32_I144@PURE_QUANTA.SCHOTTKY_12(CHIPS)':
 'A': CDS_PINID='A';
NODE_NAME     U17 2
 '@SCM_LIB.SCM(SCH_1):PAGE45_I54@PURE_QUANTA.MX25L51245GMI10G(CHIPS)':
 'VCC': CDS_PINID='VCC';
NODE_NAME     R538 1
 '@SCM_LIB.SCM(SCH_1):PAGE31_I25@PURE_QUANTA.Q_RES(CHIPS)':
 'A': CDS_PINID='A';
NODE_NAME     U54 8
 '@SCM_LIB.SCM(SCH_1):PAGE25_I138@PURE_QUANTA.74LVC1G74DP(CHIPS)':
 'VCC': CDS_PINID='VCC';
NODE_NAME     C312 1
 '@SCM_LIB.SCM(SCH_1):PAGE25_I146@PURE_QUANTA.Q_CAP(CHIPS)':
 'A': CDS_PINID='A';
NODE_NAME     U55 5
 '@SCM_LIB.SCM(SCH_1):PAGE25_I150@PURE_QUANTA.SN74LVC1G14DCKR(CHIPS)':
 'VCC': CDS_PINID='VCC';
NODE_NAME     C313 1
 '@SCM_LIB.SCM(SCH_1):PAGE25_I154@PURE_QUANTA.Q_CAP(CHIPS)':
 'A': CDS_PINID='A';
NODE_NAME     R554 1
 '@SCM_LIB.SCM(SCH_1):PAGE25_I156@PURE_QUANTA.Q_RES(CHIPS)':
 'A': CDS_PINID='A';
NODE_NAME     R521 1
 '@SCM_LIB.SCM(SCH_1):PAGE27_I234@PURE_QUANTA.Q_RES(CHIPS)':
 'A': CDS_PINID='A';
NODE_NAME     R145 1
 '@SCM_LIB.SCM(SCH_1):PAGE27_I235@PURE_QUANTA.Q_RES(CHIPS)':
 'A': CDS_PINID='A';
NODE_NAME     R149 1
 '@SCM_LIB.SCM(SCH_1):PAGE27_I236@PURE_QUANTA.Q_RES(CHIPS)':
 'A': CDS_PINID='A';
NODE_NAME     R610 1
 '@SCM_LIB.SCM(SCH_1):PAGE27_I237@PURE_QUANTA.Q_RES(CHIPS)':
 'A': CDS_PINID='A';
NODE_NAME     R692 1
 '@SCM_LIB.SCM(SCH_1):PAGE27_I238@PURE_QUANTA.Q_RES(CHIPS)':
 'A': CDS_PINID='A';
NODE_NAME     R422 1
 '@SCM_LIB.SCM(SCH_1):PAGE27_I239@PURE_QUANTA.Q_RES(CHIPS)':
 'A': CDS_PINID='A';
NODE_NAME     R428 1
 '@SCM_LIB.SCM(SCH_1):PAGE27_I240@PURE_QUANTA.Q_RES(CHIPS)':
 'A': CDS_PINID='A';
NODE_NAME     R429 1
 '@SCM_LIB.SCM(SCH_1):PAGE27_I241@PURE_QUANTA.Q_RES(CHIPS)':
 'A': CDS_PINID='A';
NODE_NAME     R438 1
 '@SCM_LIB.SCM(SCH_1):PAGE27_I242@PURE_QUANTA.Q_RES(CHIPS)':
 'A': CDS_PINID='A';
NODE_NAME     U43 6
 '@SCM_LIB.SCM(SCH_1):PAGE22_I90@PURE_QUANTA.TPS3808G18DBVR(CHIPS)':
 'VDD': CDS_PINID='VDD';
NODE_NAME     J4 2
 '@SCM_LIB.SCM(SCH_1):PAGE21_I84@PURE_QUANTA.SCONN67_NASA0S6730TS67(CHIPS)':
 '2': CDS_PINID='\2\';
NODE_NAME     J4 4
 '@SCM_LIB.SCM(SCH_1):PAGE21_I84@PURE_QUANTA.SCONN67_NASA0S6730TS67(CHIPS)':
 '4': CDS_PINID='\4\';
NODE_NAME     J4 72
 '@SCM_LIB.SCM(SCH_1):PAGE21_I84@PURE_QUANTA.SCONN67_NASA0S6730TS67(CHIPS)':
 '72': CDS_PINID='\72\';
NODE_NAME     J4 74
 '@SCM_LIB.SCM(SCH_1):PAGE21_I84@PURE_QUANTA.SCONN67_NASA0S6730TS67(CHIPS)':
 '74': CDS_PINID='\74\';
NODE_NAME     R543 1
 '@SCM_LIB.SCM(SCH_1):PAGE21_I147@PURE_QUANTA.Q_RES(CHIPS)':
 'A': CDS_PINID='A';
NODE_NAME     U7 5
 '@SCM_LIB.SCM(SCH_1):PAGE31_I27@PURE_QUANTA.NC7SB3157(CHIPS)':
 'VCC': CDS_PINID='VCC';
NODE_NAME     C11 1
 '@SCM_LIB.SCM(SCH_1):PAGE31_I31@PURE_QUANTA.Q_CAP(CHIPS)':
 'A': CDS_PINID='A';
NODE_NAME     U20 5
 '@SCM_LIB.SCM(SCH_1):PAGE31_I38@PURE_QUANTA.NC7SB3157(CHIPS)':
 'VCC': CDS_PINID='VCC';
NODE_NAME     C231 1
 '@SCM_LIB.SCM(SCH_1):PAGE31_I45@PURE_QUANTA.Q_CAP(CHIPS)':
 'A': CDS_PINID='A';
NODE_NAME     R183 1
 '@SCM_LIB.SCM(SCH_1):PAGE34_I139@PURE_QUANTA.Q_RES(CHIPS)':
 'A': CDS_PINID='A';
NODE_NAME     C120 1
 '@SCM_LIB.SCM(SCH_1):PAGE16_I190@PURE_QUANTA.Q_CAP(CHIPS)':
 'A': CDS_PINID='A';
NODE_NAME     C125 1
 '@SCM_LIB.SCM(SCH_1):PAGE16_I191@PURE_QUANTA.Q_CAP(CHIPS)':
 'A': CDS_PINID='A';
NODE_NAME     R867 1
 '@SCM_LIB.SCM(SCH_1):PAGE21_I161@PURE_QUANTA.Q_RES(CHIPS)':
 'A': CDS_PINID='A';
NODE_NAME     R615 1
 '@SCM_LIB.SCM(SCH_1):PAGE48_I33@PURE_QUANTA.Q_RES(CHIPS)':
 'A': CDS_PINID='A';
NODE_NAME     R881 1
 '@SCM_LIB.SCM(SCH_1):PAGE48_I42@PURE_QUANTA.Q_RES(CHIPS)':
 'A': CDS_PINID='A';
NODE_NAME     R624 1
 '@SCM_LIB.SCM(SCH_1):PAGE48_I48@PURE_QUANTA.Q_RES(CHIPS)':
 'A': CDS_PINID='A';
NODE_NAME     R508 1
 '@SCM_LIB.SCM(SCH_1):PAGE48_I51@PURE_QUANTA.Q_RES(CHIPS)':
 'A': CDS_PINID='A';
NODE_NAME     R404 1
 '@SCM_LIB.SCM(SCH_1):PAGE21_I166@PURE_QUANTA.Q_RES(CHIPS)':
 'A': CDS_PINID='A';
NODE_NAME     R58 1
 '@SCM_LIB.SCM(SCH_1):PAGE21_I168@PURE_QUANTA.Q_RES(CHIPS)':
 'A': CDS_PINID='A';
NODE_NAME     R169 1
 '@SCM_LIB.SCM(SCH_1):PAGE11_I256@PURE_QUANTA.Q_RES(CHIPS)':
 'A': CDS_PINID='A';
NODE_NAME     R586 1
 '@SCM_LIB.SCM(SCH_1):PAGE42_I67@PURE_QUANTA.Q_RES(CHIPS)':
 'A': CDS_PINID='A';
NODE_NAME     R462 1
 '@SCM_LIB.SCM(SCH_1):PAGE15_I391@PURE_QUANTA.Q_RES(CHIPS)':
 'A': CDS_PINID='A';
NODE_NAME     U15 5
 '@SCM_LIB.SCM(SCH_1):PAGE15_I393@PURE_QUANTA.74LVC1G08GW(CHIPS)':
 'VCC': CDS_PINID='VCC';
NODE_NAME     C26 1
 '@SCM_LIB.SCM(SCH_1):PAGE15_I398@PURE_QUANTA.Q_CAP(CHIPS)':
 'A': CDS_PINID='A';
NODE_NAME     U16 5
 '@SCM_LIB.SCM(SCH_1):PAGE50_I227@PURE_QUANTA.74LVC1G07GW(CHIPS)':
 'VCC': CDS_PINID='VCC';
NODE_NAME     C29 1
 '@SCM_LIB.SCM(SCH_1):PAGE50_I232@PURE_QUANTA.Q_CAP(CHIPS)':
 'A': CDS_PINID='A';
NODE_NAME     R391 1
 '@SCM_LIB.SCM(SCH_1):PAGE50_I235@PURE_QUANTA.Q_RES(CHIPS)':
 'A': CDS_PINID='A';
NODE_NAME     Q4 S
 '@SCM_LIB.SCM(SCH_1):PAGE17_I289@PURE_QUANTA.MOSFET_PCH_GDS(CHIPS)':
 'S': CDS_PINID='S';
NODE_NAME     R11 1
 '@SCM_LIB.SCM(SCH_1):PAGE21_I172@PURE_QUANTA.Q_RES(CHIPS)':
 'A': CDS_PINID='A';
NODE_NAME     R557 1
 '@SCM_LIB.SCM(SCH_1):PAGE21_I173@PURE_QUANTA.Q_RES(CHIPS)':
 'A': CDS_PINID='A';
NODE_NAME     R558 1
 '@SCM_LIB.SCM(SCH_1):PAGE21_I174@PURE_QUANTA.Q_RES(CHIPS)':
 'A': CDS_PINID='A';
NODE_NAME     R181 1
 '@SCM_LIB.SCM(SCH_1):PAGE25_I170@PURE_QUANTA.Q_RES(CHIPS)':
 'A': CDS_PINID='A';
NODE_NAME     R592 1
 '@SCM_LIB.SCM(SCH_1):PAGE25_I171@PURE_QUANTA.Q_RES(CHIPS)':
 'A': CDS_PINID='A';
NODE_NAME     R90 1
 '@SCM_LIB.SCM(SCH_1):PAGE21_I182@PURE_QUANTA.Q_RES(CHIPS)':
 'A': CDS_PINID='A';
NODE_NAME     R630 1
 '@SCM_LIB.SCM(SCH_1):PAGE31_I79@PURE_QUANTA.Q_RES(CHIPS)':
 'A': CDS_PINID='A';
NODE_NAME     R396 1
 '@SCM_LIB.SCM(SCH_1):PAGE31_I80@PURE_QUANTA.Q_RES(CHIPS)':
 'A': CDS_PINID='A';
NODE_NAME     R472 1
 '@SCM_LIB.SCM(SCH_1):PAGE35_I136@PURE_QUANTA.Q_RES(CHIPS)':
 'A': CDS_PINID='A';
NODE_NAME     J14 1
 '@SCM_LIB.SCM(SCH_1):PAGE26_I71@PURE_QUANTA.CONN8_TSW10407FD(CHIPS)':
 '1': CDS_PINID='\1\';
NODE_NAME     U57 5
 '@SCM_LIB.SCM(SCH_1):PAGE50_I278@PURE_QUANTA.74LVC1G07GW(CHIPS)':
 'VCC': CDS_PINID='VCC';
NODE_NAME     C336 1
 '@SCM_LIB.SCM(SCH_1):PAGE50_I281@PURE_QUANTA.Q_CAP(CHIPS)':
 'A': CDS_PINID='A';
NODE_NAME     R883 1
 '@SCM_LIB.SCM(SCH_1):PAGE50_I284@PURE_QUANTA.Q_RES(CHIPS)':
 'A': CDS_PINID='A';
NODE_NAME     R886 1
 '@SCM_LIB.SCM(SCH_1):PAGE35_I151@PURE_QUANTA.Q_RES(CHIPS)':
 'A': CDS_PINID='A';
NODE_NAME     R251 1
 '@SCM_LIB.SCM(SCH_1):PAGE27_I247@PURE_QUANTA.Q_RES(CHIPS)':
 'A': CDS_PINID='A';
NODE_NAME     U58 5
 '@SCM_LIB.SCM(SCH_1):PAGE22_I94@PURE_QUANTA.MC74VHC1G32DTT1G(CHIPS)':
 'VCC': CDS_PINID='VCC';
NODE_NAME     C337 1
 '@SCM_LIB.SCM(SCH_1):PAGE22_I97@PURE_QUANTA.Q_CAP(CHIPS)':
 'A': CDS_PINID='A';
NODE_NAME     R888 1
 '@SCM_LIB.SCM(SCH_1):PAGE22_I102@PURE_QUANTA.Q_RES(CHIPS)':
 'A': CDS_PINID='A';
NODE_NAME     R887 1
 '@SCM_LIB.SCM(SCH_1):PAGE22_I106@PURE_QUANTA.Q_RES(CHIPS)':
 'A': CDS_PINID='A';
NET_NAME
'P3V3_AUX_CS'
 '@SCM_LIB.SCM(SCH_1):P3V3_AUX_CS':
 C_SIGNAL='@scm_lib.scm(sch_1):p3v3_aux_cs';
NODE_NAME     PU1 4
 '@SCM_LIB.SCM(SCH_1):PAGE52_I82@PURE_QUANTA.MPQ8626GDZ(CHIPS)':
 'CS': CDS_PINID='CS';
NODE_NAME     PR276 2
 '@SCM_LIB.SCM(SCH_1):PAGE52_I87@PURE_QUANTA.Q_RES(CHIPS)':
 'B': CDS_PINID='B';
NET_NAME
'P3V3_AUX_FB_RC'
 '@SCM_LIB.SCM(SCH_1):P3V3_AUX_FB_RC':
 C_SIGNAL='@scm_lib.scm(sch_1):p3v3_aux_fb_rc';
NODE_NAME     PR530 2
 '@SCM_LIB.SCM(SCH_1):PAGE52_I17@PURE_QUANTA.Q_RES(CHIPS)':
 'B': CDS_PINID='B';
NODE_NAME     PR534 1
 '@SCM_LIB.SCM(SCH_1):PAGE52_I25@PURE_QUANTA.Q_RES(CHIPS)':
 'A': CDS_PINID='A';
NODE_NAME     PU1 6
 '@SCM_LIB.SCM(SCH_1):PAGE52_I82@PURE_QUANTA.MPQ8626GDZ(CHIPS)':
 'FB': CDS_PINID='FB';
NODE_NAME     PC239 1
 '@SCM_LIB.SCM(SCH_1):PAGE52_I91@PURE_QUANTA.Q_CAP(CHIPS)':
 'A': CDS_PINID='A';
NET_NAME
'P3V3_AUX_MODE'
 '@SCM_LIB.SCM(SCH_1):P3V3_AUX_MODE':
 C_SIGNAL='@scm_lib.scm(sch_1):p3v3_aux_mode';
NODE_NAME     PU1 12
 '@SCM_LIB.SCM(SCH_1):PAGE52_I82@PURE_QUANTA.MPQ8626GDZ(CHIPS)':
 'MODE': CDS_PINID='MODE';
NODE_NAME     PR532 2
 '@SCM_LIB.SCM(SCH_1):PAGE52_I88@PURE_QUANTA.Q_RES(CHIPS)':
 'B': CDS_PINID='B';
NET_NAME
'P3V3_AUX_REF'
 '@SCM_LIB.SCM(SCH_1):P3V3_AUX_REF':
 C_SIGNAL='@scm_lib.scm(sch_1):p3v3_aux_ref';
NODE_NAME     PU1 8
 '@SCM_LIB.SCM(SCH_1):PAGE52_I82@PURE_QUANTA.MPQ8626GDZ(CHIPS)':
 'TRK_REF': CDS_PINID='TRK_REF';
NODE_NAME     PC273 1
 '@SCM_LIB.SCM(SCH_1):PAGE52_I86@PURE_QUANTA.Q_CAP(CHIPS)':
 'A': CDS_PINID='A';
NET_NAME
'P3V3_AUX_VCC'
 '@SCM_LIB.SCM(SCH_1):P3V3_AUX_VCC':
 C_SIGNAL='@scm_lib.scm(sch_1):p3v3_aux_vcc';
NODE_NAME     PC221 1
 '@SCM_LIB.SCM(SCH_1):PAGE52_I9@PURE_QUANTA.Q_CAP(CHIPS)':
 'A': CDS_PINID='A';
NODE_NAME     PU1 13
 '@SCM_LIB.SCM(SCH_1):PAGE52_I82@PURE_QUANTA.MPQ8626GDZ(CHIPS)':
 'VCC': CDS_PINID='VCC';
NET_NAME
'P3V3_BMC_USB2AV33'
 '@SCM_LIB.SCM(SCH_1):P3V3_BMC_USB2AV33':
 C_SIGNAL='@scm_lib.scm(sch_1):p3v3_bmc_usb2av33';
NODE_NAME     L4 2
 '@SCM_LIB.SCM(SCH_1):PAGE15_I82@PURE_QUANTA.Q_INDUCTOR(CHIPS)':
 '2': CDS_PINID='\2\';
NODE_NAME     C45 1
 '@SCM_LIB.SCM(SCH_1):PAGE15_I89@PURE_QUANTA.Q_CAP(CHIPS)':
 'A': CDS_PINID='A';
NODE_NAME     U5 J10
 '@SCM_LIB.SCM(SCH_1):PAGE15_I350@PURE_QUANTA.AST2600A3GP(CHIPS)':
 'USB2AV33': CDS_PINID='USB2AV33';
NODE_NAME     C44 1
 '@SCM_LIB.SCM(SCH_1):PAGE15_I369@PURE_QUANTA.Q_CAP(CHIPS)':
 'A': CDS_PINID='A';
NET_NAME
'P3V3_LDO'
 '@SCM_LIB.SCM(SCH_1):P3V3_LDO':
 C_SIGNAL='@scm_lib.scm(sch_1):p3v3_ldo',
 CDS_GLOBAL_NET='TRUE';
NODE_NAME     C298 1
 '@SCM_LIB.SCM(SCH_1):PAGE54_I112@PURE_QUANTA.Q_CAP(CHIPS)':
 'A': CDS_PINID='A';
NODE_NAME     U49 5
 '@SCM_LIB.SCM(SCH_1):PAGE54_I116@PURE_QUANTA.MC74VHC1G32DTT1G(CHIPS)':
 'VCC': CDS_PINID='VCC';
NODE_NAME     C302 1
 '@SCM_LIB.SCM(SCH_1):PAGE56_I64@PURE_QUANTA.Q_CAP(CHIPS)':
 'A': CDS_PINID='A';
NODE_NAME     U53 5
 '@SCM_LIB.SCM(SCH_1):PAGE56_I66@PURE_QUANTA.74LVC1G08GW(CHIPS)':
 'VCC': CDS_PINID='VCC';
NODE_NAME     C301 1
 '@SCM_LIB.SCM(SCH_1):PAGE55_I61@PURE_QUANTA.Q_CAP(CHIPS)':
 'A': CDS_PINID='A';
NODE_NAME     U52 5
 '@SCM_LIB.SCM(SCH_1):PAGE55_I63@PURE_QUANTA.74LVC1G08GW(CHIPS)':
 'VCC': CDS_PINID='VCC';
NODE_NAME     U42 5
 '@SCM_LIB.SCM(SCH_1):PAGE52_I104@PURE_QUANTA.MC74VHC1G32DTT1G(CHIPS)':
 'VCC': CDS_PINID='VCC';
NODE_NAME     C297 1
 '@SCM_LIB.SCM(SCH_1):PAGE52_I107@PURE_QUANTA.Q_CAP(CHIPS)':
 'A': CDS_PINID='A';
NODE_NAME     U18 5
 '@SCM_LIB.SCM(SCH_1):PAGE52_I114@PURE_QUANTA.74LVC1G08GW(CHIPS)':
 'VCC': CDS_PINID='VCC';
NODE_NAME     C296 1
 '@SCM_LIB.SCM(SCH_1):PAGE52_I119@PURE_QUANTA.Q_CAP(CHIPS)':
 'A': CDS_PINID='A';
NODE_NAME     U56 5
 '@SCM_LIB.SCM(SCH_1):PAGE51_I56@PURE_QUANTA.AP2205W57(CHIPS)':
 'VOUT': CDS_PINID='VOUT';
NODE_NAME     R631 1
 '@SCM_LIB.SCM(SCH_1):PAGE51_I62@PURE_QUANTA.Q_RES(CHIPS)':
 'A': CDS_PINID='A';
NODE_NAME     U28 5
 '@SCM_LIB.SCM(SCH_1):PAGE13_I435@PURE_QUANTA.74LVC1G66GV(CHIPS)':
 'VCC': CDS_PINID='VCC';
NODE_NAME     C180 1
 '@SCM_LIB.SCM(SCH_1):PAGE13_I440@PURE_QUANTA.Q_CAP(CHIPS)':
 'A': CDS_PINID='A';
NODE_NAME     C227 1
 '@SCM_LIB.SCM(SCH_1):PAGE51_I68@PURE_QUANTA.Q_CAP(CHIPS)':
 'A': CDS_PINID='A';
NET_NAME
'P3V3_P1V8_I2C_I3C'
 '@SCM_LIB.SCM(SCH_1):P3V3_P1V8_I2C_I3C':
 C_SIGNAL='@scm_lib.scm(sch_1):p3v3_p1v8_i2c_i3c',
 CDS_GLOBAL_NET='TRUE';
NODE_NAME     U5 F19
 '@SCM_LIB.SCM(SCH_1):PAGE16_I188@PURE_QUANTA.AST2600A3GP(CHIPS)':
 'I3CVDDH_F19': CDS_PINID='I3CVDDH_F19';
NODE_NAME     U5 F20
 '@SCM_LIB.SCM(SCH_1):PAGE16_I188@PURE_QUANTA.AST2600A3GP(CHIPS)':
 'I3CVDDH_F20': CDS_PINID='I3CVDDH_F20';
NODE_NAME     R231 2
 '@SCM_LIB.SCM(SCH_1):PAGE17_I131@PURE_QUANTA.Q_RES(CHIPS)':
 'B': CDS_PINID='B';
NODE_NAME     C57 1
 '@SCM_LIB.SCM(SCH_1):PAGE17_I133@PURE_QUANTA.Q_CAP(CHIPS)':
 'A': CDS_PINID='A';
NODE_NAME     C53 1
 '@SCM_LIB.SCM(SCH_1):PAGE17_I135@PURE_QUANTA.Q_CAP(CHIPS)':
 'A': CDS_PINID='A';
NODE_NAME     R232 2
 '@SCM_LIB.SCM(SCH_1):PAGE17_I136@PURE_QUANTA.Q_RES(CHIPS)':
 'B': CDS_PINID='B';
NET_NAME
'P3V3_P1V8_SD1VDD'
 '@SCM_LIB.SCM(SCH_1):P3V3_P1V8_SD1VDD':
 C_SIGNAL='@scm_lib.scm(sch_1):p3v3_p1v8_sd1vdd',
 CDS_GLOBAL_NET='TRUE';
NODE_NAME     R208 2
 '@SCM_LIB.SCM(SCH_1):PAGE15_I2@PURE_QUANTA.Q_RES(CHIPS)':
 'B': CDS_PINID='B';
NODE_NAME     R207 2
 '@SCM_LIB.SCM(SCH_1):PAGE15_I4@PURE_QUANTA.Q_RES(CHIPS)':
 'B': CDS_PINID='B';
NODE_NAME     C35 1
 '@SCM_LIB.SCM(SCH_1):PAGE15_I14@PURE_QUANTA.Q_CAP(CHIPS)':
 'A': CDS_PINID='A';
NODE_NAME     C36 1
 '@SCM_LIB.SCM(SCH_1):PAGE15_I16@PURE_QUANTA.Q_CAP(CHIPS)':
 'A': CDS_PINID='A';
NODE_NAME     U5 G21
 '@SCM_LIB.SCM(SCH_1):PAGE16_I188@PURE_QUANTA.AST2600A3GP(CHIPS)':
 'SD1VDD_G21': CDS_PINID='SD1VDD_G21';
NODE_NAME     U5 H21
 '@SCM_LIB.SCM(SCH_1):PAGE16_I188@PURE_QUANTA.AST2600A3GP(CHIPS)':
 'SD1VDD_H21': CDS_PINID='SD1VDD_H21';
NET_NAME
'P3V3_P1V8_SD2VDD'
 '@SCM_LIB.SCM(SCH_1):P3V3_P1V8_SD2VDD':
 C_SIGNAL='@scm_lib.scm(sch_1):p3v3_p1v8_sd2vdd',
 CDS_GLOBAL_NET='TRUE';
NODE_NAME     R214 2
 '@SCM_LIB.SCM(SCH_1):PAGE15_I32@PURE_QUANTA.Q_RES(CHIPS)':
 'B': CDS_PINID='B';
NODE_NAME     R213 2
 '@SCM_LIB.SCM(SCH_1):PAGE15_I34@PURE_QUANTA.Q_RES(CHIPS)':
 'B': CDS_PINID='B';
NODE_NAME     C38 1
 '@SCM_LIB.SCM(SCH_1):PAGE15_I36@PURE_QUANTA.Q_CAP(CHIPS)':
 'A': CDS_PINID='A';
NODE_NAME     C39 1
 '@SCM_LIB.SCM(SCH_1):PAGE15_I37@PURE_QUANTA.Q_CAP(CHIPS)':
 'A': CDS_PINID='A';
NODE_NAME     U5 H18
 '@SCM_LIB.SCM(SCH_1):PAGE16_I188@PURE_QUANTA.AST2600A3GP(CHIPS)':
 'SD2VDD_H18': CDS_PINID='SD2VDD_H18';
NODE_NAME     U5 H19
 '@SCM_LIB.SCM(SCH_1):PAGE16_I188@PURE_QUANTA.AST2600A3GP(CHIPS)':
 'SD2VDD_H19': CDS_PINID='SD2VDD_H19';
NET_NAME
'P3V3_P2V5_P1V8_RVDD'
 '@SCM_LIB.SCM(SCH_1):P3V3_P2V5_P1V8_RVDD':
 C_SIGNAL='@scm_lib.scm(sch_1):p3v3_p2v5_p1v8_rvdd',
 CDS_GLOBAL_NET='TRUE';
NODE_NAME     R154 2
 '@SCM_LIB.SCM(SCH_1):PAGE13_I3@PURE_QUANTA.Q_RES(CHIPS)':
 'B': CDS_PINID='B';
NODE_NAME     R156 2
 '@SCM_LIB.SCM(SCH_1):PAGE13_I4@PURE_QUANTA.Q_RES(CHIPS)':
 'B': CDS_PINID='B';
NODE_NAME     R155 2
 '@SCM_LIB.SCM(SCH_1):PAGE13_I5@PURE_QUANTA.Q_RES(CHIPS)':
 'B': CDS_PINID='B';
NODE_NAME     C30 1
 '@SCM_LIB.SCM(SCH_1):PAGE13_I29@PURE_QUANTA.Q_CAP(CHIPS)':
 'A': CDS_PINID='A';
NODE_NAME     C31 1
 '@SCM_LIB.SCM(SCH_1):PAGE13_I30@PURE_QUANTA.Q_CAP(CHIPS)':
 'A': CDS_PINID='A';
NODE_NAME     C32 1
 '@SCM_LIB.SCM(SCH_1):PAGE13_I31@PURE_QUANTA.Q_CAP(CHIPS)':
 'A': CDS_PINID='A';
NODE_NAME     C33 1
 '@SCM_LIB.SCM(SCH_1):PAGE13_I32@PURE_QUANTA.Q_CAP(CHIPS)':
 'A': CDS_PINID='A';
NODE_NAME     U5 J21
 '@SCM_LIB.SCM(SCH_1):PAGE16_I188@PURE_QUANTA.AST2600A3GP(CHIPS)':
 'RVDD_J21': CDS_PINID='RVDD_J21';
NODE_NAME     U5 K21
 '@SCM_LIB.SCM(SCH_1):PAGE16_I188@PURE_QUANTA.AST2600A3GP(CHIPS)':
 'RVDD_K21': CDS_PINID='RVDD_K21';
NODE_NAME     U5 L22
 '@SCM_LIB.SCM(SCH_1):PAGE16_I188@PURE_QUANTA.AST2600A3GP(CHIPS)':
 'RVDD_L22': CDS_PINID='RVDD_L22';
NODE_NAME     U5 M22
 '@SCM_LIB.SCM(SCH_1):PAGE16_I188@PURE_QUANTA.AST2600A3GP(CHIPS)':
 'RVDD_M22': CDS_PINID='RVDD_M22';
NET_NAME
'P3V3_RGM'
 '@SCM_LIB.SCM(SCH_1):P3V3_RGM':
 C_SIGNAL='@scm_lib.scm(sch_1):p3v3_rgm',
 CDS_GLOBAL_NET='TRUE';
NODE_NAME     R34 1
 '@SCM_LIB.SCM(SCH_1):PAGE11_I194@PURE_QUANTA.Q_RES(CHIPS)':
 'A': CDS_PINID='A';
NODE_NAME     R212 1
 '@SCM_LIB.SCM(SCH_1):PAGE15_I21@PURE_QUANTA.Q_RES(CHIPS)':
 'A': CDS_PINID='A';
NODE_NAME     C37 1
 '@SCM_LIB.SCM(SCH_1):PAGE15_I24@PURE_QUANTA.Q_CAP(CHIPS)':
 'A': CDS_PINID='A';
NODE_NAME     OSC1 4
 '@SCM_LIB.SCM(SCH_1):PAGE15_I39@PURE_QUANTA.OSC4_7X25000018(CHIPS)':
 'VDD': CDS_PINID='VDD';
NODE_NAME     R211 1
 '@SCM_LIB.SCM(SCH_1):PAGE15_I51@PURE_QUANTA.Q_RES(CHIPS)':
 'A': CDS_PINID='A';
NODE_NAME     R623 1
 '@SCM_LIB.SCM(SCH_1):PAGE15_I152@PURE_QUANTA.Q_RES(CHIPS)':
 'A': CDS_PINID='A';
NODE_NAME     R491 1
 '@SCM_LIB.SCM(SCH_1):PAGE15_I346@PURE_QUANTA.Q_RES(CHIPS)':
 'A': CDS_PINID='A';
NODE_NAME     C85 1
 '@SCM_LIB.SCM(SCH_1):PAGE16_I120@PURE_QUANTA.Q_CAP(CHIPS)':
 'A': CDS_PINID='A';
NODE_NAME     U5 K11
 '@SCM_LIB.SCM(SCH_1):PAGE16_I188@PURE_QUANTA.AST2600A3GP(CHIPS)':
 'PV33D_RGM_K11': CDS_PINID='PV33D_RGM_K11';
NODE_NAME     U5 K12
 '@SCM_LIB.SCM(SCH_1):PAGE16_I188@PURE_QUANTA.AST2600A3GP(CHIPS)':
 'PV33D_RGM_K12': CDS_PINID='PV33D_RGM_K12';
NODE_NAME     R287 1
 '@SCM_LIB.SCM(SCH_1):PAGE22_I5@PURE_QUANTA.Q_RES(CHIPS)':
 'A': CDS_PINID='A';
NODE_NAME     R289 1
 '@SCM_LIB.SCM(SCH_1):PAGE22_I7@PURE_QUANTA.Q_RES(CHIPS)':
 'A': CDS_PINID='A';
NODE_NAME     R291 1
 '@SCM_LIB.SCM(SCH_1):PAGE22_I9@PURE_QUANTA.Q_RES(CHIPS)':
 'A': CDS_PINID='A';
NODE_NAME     R31 1
 '@SCM_LIB.SCM(SCH_1):PAGE23_I27@PURE_QUANTA.Q_RES(CHIPS)':
 'A': CDS_PINID='A';
NODE_NAME     R32 1
 '@SCM_LIB.SCM(SCH_1):PAGE23_I50@PURE_QUANTA.Q_RES(CHIPS)':
 'A': CDS_PINID='A';
NODE_NAME     R86 1
 '@SCM_LIB.SCM(SCH_1):PAGE23_I51@PURE_QUANTA.Q_RES(CHIPS)':
 'A': CDS_PINID='A';
NODE_NAME     R754 1
 '@SCM_LIB.SCM(SCH_1):PAGE27_I213@PURE_QUANTA.Q_RES(CHIPS)':
 'A': CDS_PINID='A';
NODE_NAME     R758 1
 '@SCM_LIB.SCM(SCH_1):PAGE30_I221@PURE_QUANTA.Q_RES(CHIPS)':
 'A': CDS_PINID='A';
NODE_NAME     R203 1
 '@SCM_LIB.SCM(SCH_1):PAGE32_I117@PURE_QUANTA.Q_RES(CHIPS)':
 'A': CDS_PINID='A';
NODE_NAME     R523 1
 '@SCM_LIB.SCM(SCH_1):PAGE32_I119@PURE_QUANTA.Q_RES(CHIPS)':
 'A': CDS_PINID='A';
NODE_NAME     R204 1
 '@SCM_LIB.SCM(SCH_1):PAGE32_I120@PURE_QUANTA.Q_RES(CHIPS)':
 'A': CDS_PINID='A';
NODE_NAME     R834 1
 '@SCM_LIB.SCM(SCH_1):PAGE32_I131@PURE_QUANTA.Q_RES(CHIPS)':
 'A': CDS_PINID='A';
NODE_NAME     C251 1
 '@SCM_LIB.SCM(SCH_1):PAGE52_I66@PURE_QUANTA.Q_CAP(CHIPS)':
 'A': CDS_PINID='A';
NODE_NAME     U14 1
 '@SCM_LIB.SCM(SCH_1):PAGE52_I79@PURE_QUANTA.AP22811AW57(CHIPS)':
 'OUT': CDS_PINID='\out\';
NODE_NAME     R709 1
 '@SCM_LIB.SCM(SCH_1):PAGE52_I145@PURE_QUANTA.Q_RES(CHIPS)':
 'A': CDS_PINID='A';
NET_NAME
'P3V3_RTC_AUX'
 '@SCM_LIB.SCM(SCH_1):P3V3_RTC_AUX':
 C_SIGNAL='@scm_lib.scm(sch_1):p3v3_rtc_aux',
 CDS_GLOBAL_NET='TRUE';
NODE_NAME     C83 1
 '@SCM_LIB.SCM(SCH_1):PAGE16_I106@PURE_QUANTA.Q_CAP(CHIPS)':
 'A': CDS_PINID='A';
NODE_NAME     U5 V23
 '@SCM_LIB.SCM(SCH_1):PAGE16_I188@PURE_QUANTA.AST2600A3GP(CHIPS)':
 'BATVDD': CDS_PINID='BATVDD';
NODE_NAME     U48 3
 '@SCM_LIB.SCM(SCH_1):PAGE50_I161@PURE_QUANTA.BAS70057F(CHIPS)':
 'C': CDS_PINID='C';
NODE_NAME     C196 1
 '@SCM_LIB.SCM(SCH_1):PAGE50_I165@PURE_QUANTA.Q_CAP(CHIPS)':
 'A': CDS_PINID='A';
NET_NAME
'P3V3_SENSOR'
 '@SCM_LIB.SCM(SCH_1):P3V3_SENSOR':
 C_SIGNAL='@scm_lib.scm(sch_1):p3v3_sensor';
NODE_NAME     C299 1
 '@SCM_LIB.SCM(SCH_1):PAGE15_I215@PURE_QUANTA.Q_CAP(CHIPS)':
 'A': CDS_PINID='A';
NODE_NAME     R789 2
 '@SCM_LIB.SCM(SCH_1):PAGE15_I219@PURE_QUANTA.Q_RES(CHIPS)':
 'B': CDS_PINID='B';
NODE_NAME     R790 1
 '@SCM_LIB.SCM(SCH_1):PAGE15_I220@PURE_QUANTA.Q_RES(CHIPS)':
 'A': CDS_PINID='A';
NODE_NAME     U5 AE19
 '@SCM_LIB.SCM(SCH_1):PAGE15_I350@PURE_QUANTA.AST2600A3GP(CHIPS)':
 'ADC2||GPIT2': CDS_PINID='\adc2||gpit2\';
NET_NAME
'P3V3_STBY_DACAV33'
 '@SCM_LIB.SCM(SCH_1):P3V3_STBY_DACAV33':
 C_SIGNAL='@scm_lib.scm(sch_1):p3v3_stby_dacav33';
NODE_NAME     U5 V21
 '@SCM_LIB.SCM(SCH_1):PAGE16_I188@PURE_QUANTA.AST2600A3GP(CHIPS)':
 'DACAV33_V21': CDS_PINID='DACAV33_V21';
NODE_NAME     U5 W21
 '@SCM_LIB.SCM(SCH_1):PAGE16_I188@PURE_QUANTA.AST2600A3GP(CHIPS)':
 'DACAV33_W21': CDS_PINID='DACAV33_W21';
NODE_NAME     C51 1
 '@SCM_LIB.SCM(SCH_1):PAGE17_I145@PURE_QUANTA.Q_CAP(CHIPS)':
 'A': CDS_PINID='A';
NODE_NAME     L7 2
 '@SCM_LIB.SCM(SCH_1):PAGE17_I146@PURE_QUANTA.Q_INDUCTOR(CHIPS)':
 '2': CDS_PINID='\2\';
NODE_NAME     C48 1
 '@SCM_LIB.SCM(SCH_1):PAGE17_I148@PURE_QUANTA.Q_CAP(CHIPS)':
 'A': CDS_PINID='A';
NET_NAME
'P3V3_STBY_PLLAHVDD'
 '@SCM_LIB.SCM(SCH_1):P3V3_STBY_PLLAHVDD':
 C_SIGNAL='@scm_lib.scm(sch_1):p3v3_stby_pllahvdd';
NODE_NAME     U5 H14
 '@SCM_LIB.SCM(SCH_1):PAGE16_I188@PURE_QUANTA.AST2600A3GP(CHIPS)':
 'PLLAHVDD': CDS_PINID='PLLAHVDD';
NODE_NAME     C65 1
 '@SCM_LIB.SCM(SCH_1):PAGE17_I139@PURE_QUANTA.Q_CAP(CHIPS)':
 'A': CDS_PINID='A';
NODE_NAME     C60 1
 '@SCM_LIB.SCM(SCH_1):PAGE17_I141@PURE_QUANTA.Q_CAP(CHIPS)':
 'A': CDS_PINID='A';
NODE_NAME     L9 2
 '@SCM_LIB.SCM(SCH_1):PAGE17_I142@PURE_QUANTA.Q_INDUCTOR(CHIPS)':
 '2': CDS_PINID='\2\';
NODE_NAME     L2 2
 '@SCM_LIB.SCM(SCH_1):PAGE17_I272@PURE_QUANTA.Q_INDUCTOR(CHIPS)':
 '2': CDS_PINID='\2\';
NET_NAME
'P3V_BAT_R'
 '@SCM_LIB.SCM(SCH_1):P3V_BAT_R':
 C_SIGNAL='@scm_lib.scm(sch_1):p3v_bat_r';
NODE_NAME     C174 1
 '@SCM_LIB.SCM(SCH_1):PAGE10_I503@PURE_QUANTA.Q_CAP(CHIPS)':
 'A': CDS_PINID='A';
NODE_NAME     GF1 B41
 '@SCM_LIB.SCM(SCH_1):PAGE10_I553@PURE_QUANTA.FCONN168_ME1016810202011_SCM(CHIPS)':
 'P3V0_BAT': CDS_PINID='P3V0_BAT';
NODE_NAME     R777 1
 '@SCM_LIB.SCM(SCH_1):PAGE15_I289@PURE_QUANTA.Q_RES(CHIPS)':
 'A': CDS_PINID='A';
NODE_NAME     U48 1
 '@SCM_LIB.SCM(SCH_1):PAGE50_I161@PURE_QUANTA.BAS70057F(CHIPS)':
 'B': CDS_PINID='B';
NET_NAME
'P3V_BAT_R1'
 '@SCM_LIB.SCM(SCH_1):P3V_BAT_R1':
 C_SIGNAL='@scm_lib.scm(sch_1):p3v_bat_r1';
NODE_NAME     Q11 D
 '@SCM_LIB.SCM(SCH_1):PAGE15_I179@PURE_QUANTA.MOSFET_N_GSD(CHIPS)':
 'DRAIN': CDS_PINID='DRAIN';
NODE_NAME     R777 2
 '@SCM_LIB.SCM(SCH_1):PAGE15_I289@PURE_QUANTA.Q_RES(CHIPS)':
 'B': CDS_PINID='B';
NET_NAME
'P3V_BAT_SENSOR'
 '@SCM_LIB.SCM(SCH_1):P3V_BAT_SENSOR':
 C_SIGNAL='@scm_lib.scm(sch_1):p3v_bat_sensor';
NODE_NAME     Q11 S
 '@SCM_LIB.SCM(SCH_1):PAGE15_I179@PURE_QUANTA.MOSFET_N_GSD(CHIPS)':
 'SOURCE': CDS_PINID='SOURCE';
NODE_NAME     C275 1
 '@SCM_LIB.SCM(SCH_1):PAGE15_I180@PURE_QUANTA.Q_CAP(CHIPS)':
 'A': CDS_PINID='A';
NODE_NAME     R778 1
 '@SCM_LIB.SCM(SCH_1):PAGE15_I181@PURE_QUANTA.Q_RES(CHIPS)':
 'A': CDS_PINID='A';
NODE_NAME     U5 AE18
 '@SCM_LIB.SCM(SCH_1):PAGE15_I350@PURE_QUANTA.AST2600A3GP(CHIPS)':
 'ADC7||GPIT7': CDS_PINID='\adc7||gpit7\';
NET_NAME
'P5V_AUX'
 '@SCM_LIB.SCM(SCH_1):P5V_AUX':
 C_SIGNAL='@scm_lib.scm(sch_1):p5v_aux',
 CDS_GLOBAL_NET='TRUE';
NODE_NAME     R787 1
 '@SCM_LIB.SCM(SCH_1):PAGE15_I223@PURE_QUANTA.Q_RES(CHIPS)':
 'A': CDS_PINID='A';
NODE_NAME     R716 1
 '@SCM_LIB.SCM(SCH_1):PAGE17_I230@PURE_QUANTA.Q_RES(CHIPS)':
 'A': CDS_PINID='A';
NODE_NAME     C202 1
 '@SCM_LIB.SCM(SCH_1):PAGE23_I11@PURE_QUANTA.Q_CAP(CHIPS)':
 'A': CDS_PINID='A';
NODE_NAME     C203 1
 '@SCM_LIB.SCM(SCH_1):PAGE23_I12@PURE_QUANTA.Q_CAP(CHIPS)':
 'A': CDS_PINID='A';
NODE_NAME     R18 1
 '@SCM_LIB.SCM(SCH_1):PAGE23_I19@PURE_QUANTA.Q_RES(CHIPS)':
 'A': CDS_PINID='A';
NODE_NAME     R27 1
 '@SCM_LIB.SCM(SCH_1):PAGE23_I40@PURE_QUANTA.Q_RES(CHIPS)':
 'A': CDS_PINID='A';
NODE_NAME     D11 A
 '@SCM_LIB.SCM(SCH_1):PAGE23_I41@PURE_QUANTA.SCHOTTKY_AC(CHIPS)':
 'A': CDS_PINID='A';
NODE_NAME     D9 A
 '@SCM_LIB.SCM(SCH_1):PAGE23_I42@PURE_QUANTA.SCHOTTKY_AC(CHIPS)':
 'A': CDS_PINID='A';
NODE_NAME     D16 1
 '@SCM_LIB.SCM(SCH_1):PAGE23_I161@PURE_QUANTA.SCHOTTKY_12(CHIPS)':
 'A': CDS_PINID='A';
NODE_NAME     C172 1
 '@SCM_LIB.SCM(SCH_1):PAGE28_I35@PURE_QUANTA.Q_CAP(CHIPS)':
 'A': CDS_PINID='A';
NODE_NAME     C171 1
 '@SCM_LIB.SCM(SCH_1):PAGE28_I38@PURE_QUANTA.Q_CAP(CHIPS)':
 'A': CDS_PINID='A';
NODE_NAME     R376 1
 '@SCM_LIB.SCM(SCH_1):PAGE28_I62@PURE_QUANTA.Q_RES(CHIPS)':
 'A': CDS_PINID='A';
NODE_NAME     U10 1
 '@SCM_LIB.SCM(SCH_1):PAGE28_I179@PURE_QUANTA.NCP380HSNAJAAT1G(CHIPS)':
 'IN': CDS_PINID='\in\';
NODE_NAME     R814 1
 '@SCM_LIB.SCM(SCH_1):PAGE49_I36@PURE_QUANTA.Q_RES(CHIPS)':
 'A': CDS_PINID='A';
NODE_NAME     R815 1
 '@SCM_LIB.SCM(SCH_1):PAGE49_I40@PURE_QUANTA.Q_RES(CHIPS)':
 'A': CDS_PINID='A';
NODE_NAME     R568 2
 '@SCM_LIB.SCM(SCH_1):PAGE49_I59@PURE_QUANTA.Q_RES(CHIPS)':
 'B': CDS_PINID='B';
NODE_NAME     R569 2
 '@SCM_LIB.SCM(SCH_1):PAGE49_I60@PURE_QUANTA.Q_RES(CHIPS)':
 'B': CDS_PINID='B';
NODE_NAME     PC272 2
 '@SCM_LIB.SCM(SCH_1):PAGE51_I27@PURE_QUANTA.Q_CAP(CHIPS)':
 'B': CDS_PINID='B';
NODE_NAME     PL34 2
 '@SCM_LIB.SCM(SCH_1):PAGE51_I28@PURE_QUANTA.Q_INDUCTOR(CHIPS)':
 '2': CDS_PINID='\2\';
NODE_NAME     PR527 2
 '@SCM_LIB.SCM(SCH_1):PAGE51_I30@PURE_QUANTA.Q_RES(CHIPS)':
 'B': CDS_PINID='B';
NODE_NAME     PC212 1
 '@SCM_LIB.SCM(SCH_1):PAGE51_I31@PURE_QUANTA.Q_CAP(CHIPS)':
 'A': CDS_PINID='A';
NODE_NAME     PC213 1
 '@SCM_LIB.SCM(SCH_1):PAGE51_I32@PURE_QUANTA.Q_CAP(CHIPS)':
 'A': CDS_PINID='A';
NODE_NAME     PC214 1
 '@SCM_LIB.SCM(SCH_1):PAGE51_I33@PURE_QUANTA.Q_CAP(CHIPS)':
 'A': CDS_PINID='A';
NODE_NAME     PC215 1
 '@SCM_LIB.SCM(SCH_1):PAGE51_I36@PURE_QUANTA.Q_CAP(CHIPS)':
 'A': CDS_PINID='A';
NODE_NAME     PC217 1
 '@SCM_LIB.SCM(SCH_1):PAGE51_I37@PURE_QUANTA.Q_CAP(CHIPS)':
 'A': CDS_PINID='A';
NODE_NAME     U39 10
 '@SCM_LIB.SCM(SCH_1):PAGE53_I60@PURE_QUANTA.RT9059GQW(CHIPS)':
 'VDD': CDS_PINID='VDD';
NODE_NAME     U41 10
 '@SCM_LIB.SCM(SCH_1):PAGE54_I96@PURE_QUANTA.RT9059GQW(CHIPS)':
 'VDD': CDS_PINID='VDD';
NODE_NAME     PR275 1
 '@SCM_LIB.SCM(SCH_1):PAGE55_I48@PURE_QUANTA.Q_RES(CHIPS)':
 'A': CDS_PINID='A';
NODE_NAME     PR205 1
 '@SCM_LIB.SCM(SCH_1):PAGE56_I48@PURE_QUANTA.Q_RES(CHIPS)':
 'A': CDS_PINID='A';
NODE_NAME     C292 1
 '@SCM_LIB.SCM(SCH_1):PAGE54_I107@PURE_QUANTA.Q_CAP(CHIPS)':
 'A': CDS_PINID='A';
NODE_NAME     C287 1
 '@SCM_LIB.SCM(SCH_1):PAGE53_I67@PURE_QUANTA.Q_CAP(CHIPS)':
 'A': CDS_PINID='A';
NODE_NAME     R80 2
 '@SCM_LIB.SCM(SCH_1):PAGE50_I210@PURE_QUANTA.Q_RES(CHIPS)':
 'B': CDS_PINID='B';
NET_NAME
'P5V_AUX_CS'
 '@SCM_LIB.SCM(SCH_1):P5V_AUX_CS':
 C_SIGNAL='@scm_lib.scm(sch_1):p5v_aux_cs';
NODE_NAME     PR525 1
 '@SCM_LIB.SCM(SCH_1):PAGE51_I9@PURE_QUANTA.Q_RES(CHIPS)':
 'A': CDS_PINID='A';
NODE_NAME     PU38 3
 '@SCM_LIB.SCM(SCH_1):PAGE51_I42@PURE_QUANTA.MPQ8633AGLEC807Z(CHIPS)':
 'CS': CDS_PINID='CS';
NET_NAME
'P5V_AUX_FB'
 '@SCM_LIB.SCM(SCH_1):P5V_AUX_FB':
 C_SIGNAL='@scm_lib.scm(sch_1):p5v_aux_fb';
NODE_NAME     PR526 1
 '@SCM_LIB.SCM(SCH_1):PAGE51_I26@PURE_QUANTA.Q_RES(CHIPS)':
 'A': CDS_PINID='A';
NODE_NAME     PC272 1
 '@SCM_LIB.SCM(SCH_1):PAGE51_I27@PURE_QUANTA.Q_CAP(CHIPS)':
 'A': CDS_PINID='A';
NODE_NAME     PR527 1
 '@SCM_LIB.SCM(SCH_1):PAGE51_I30@PURE_QUANTA.Q_RES(CHIPS)':
 'A': CDS_PINID='A';
NODE_NAME     PU38 7
 '@SCM_LIB.SCM(SCH_1):PAGE51_I42@PURE_QUANTA.MPQ8633AGLEC807Z(CHIPS)':
 'FB': CDS_PINID='FB';
NET_NAME
'P5V_AUX_REF'
 '@SCM_LIB.SCM(SCH_1):P5V_AUX_REF':
 C_SIGNAL='@scm_lib.scm(sch_1):p5v_aux_ref';
NODE_NAME     PC271 1
 '@SCM_LIB.SCM(SCH_1):PAGE51_I22@PURE_QUANTA.Q_CAP(CHIPS)':
 'A': CDS_PINID='A';
NODE_NAME     PU38 5
 '@SCM_LIB.SCM(SCH_1):PAGE51_I42@PURE_QUANTA.MPQ8633AGLEC807Z(CHIPS)':
 'TRK_REF': CDS_PINID='TRK_REF';
NET_NAME
'P5V_AUX_VCC'
 '@SCM_LIB.SCM(SCH_1):P5V_AUX_VCC':
 C_SIGNAL='@scm_lib.scm(sch_1):p5v_aux_vcc',
 CDS_GLOBAL_NET='TRUE';
NODE_NAME     PC208 1
 '@SCM_LIB.SCM(SCH_1):PAGE51_I13@PURE_QUANTA.Q_CAP(CHIPS)':
 'A': CDS_PINID='A';
NODE_NAME     PR241 1
 '@SCM_LIB.SCM(SCH_1):PAGE51_I21@PURE_QUANTA.Q_RES(CHIPS)':
 'A': CDS_PINID='A';
NODE_NAME     PU38 19
 '@SCM_LIB.SCM(SCH_1):PAGE51_I42@PURE_QUANTA.MPQ8633AGLEC807Z(CHIPS)':
 'VCC': CDS_PINID='VCC';
NET_NAME
'P5V_SENSOR'
 '@SCM_LIB.SCM(SCH_1):P5V_SENSOR':
 C_SIGNAL='@scm_lib.scm(sch_1):p5v_sensor';
NODE_NAME     C295 1
 '@SCM_LIB.SCM(SCH_1):PAGE15_I207@PURE_QUANTA.Q_CAP(CHIPS)':
 'A': CDS_PINID='A';
NODE_NAME     R788 1
 '@SCM_LIB.SCM(SCH_1):PAGE15_I211@PURE_QUANTA.Q_RES(CHIPS)':
 'A': CDS_PINID='A';
NODE_NAME     R787 2
 '@SCM_LIB.SCM(SCH_1):PAGE15_I223@PURE_QUANTA.Q_RES(CHIPS)':
 'B': CDS_PINID='B';
NODE_NAME     U5 AC18
 '@SCM_LIB.SCM(SCH_1):PAGE15_I350@PURE_QUANTA.AST2600A3GP(CHIPS)':
 'ADC1||GPIT1': CDS_PINID='\adc1||gpit1\';
NET_NAME
'P5V_USB_REAR'
 '@SCM_LIB.SCM(SCH_1):P5V_USB_REAR':
 C_SIGNAL='@scm_lib.scm(sch_1):p5v_usb_rear',
 CDS_GLOBAL_NET='TRUE';
NODE_NAME     U10 6
 '@SCM_LIB.SCM(SCH_1):PAGE28_I179@PURE_QUANTA.NCP380HSNAJAAT1G(CHIPS)':
 'OUT': CDS_PINID='\out\';
NODE_NAME     U38 4
 '@SCM_LIB.SCM(SCH_1):PAGE29_I99@PURE_QUANTA.PRTR5V0U2X(CHIPS)':
 'VCC': CDS_PINID='VCC';
NODE_NAME     C179 1
 '@SCM_LIB.SCM(SCH_1):PAGE29_I193@PURE_QUANTA.Q_CAP(CHIPS)':
 'A': CDS_PINID='A';
NODE_NAME     C178 1
 '@SCM_LIB.SCM(SCH_1):PAGE29_I194@PURE_QUANTA.Q_CAP(CHIPS)':
 'A': CDS_PINID='A';
NODE_NAME     C177 1
 '@SCM_LIB.SCM(SCH_1):PAGE29_I219@PURE_QUANTA.Q_CAP(CHIPS)':
 'A': CDS_PINID='A';
NODE_NAME     C327 1
 '@SCM_LIB.SCM(SCH_1):PAGE29_I220@PURE_QUANTA.Q_CAP(CHIPS)':
 'A': CDS_PINID='A';
NODE_NAME     J2 1
 '@SCM_LIB.SCM(SCH_1):PAGE29_I221@PURE_QUANTA.CONN9_GSB3111315HR(CHIPS)':
 'VBUS': CDS_PINID='VBUS';
NET_NAME
'PCH_BEEP_LED'
 '@SCM_LIB.SCM(SCH_1):PCH_BEEP_LED':
 C_SIGNAL='@scm_lib.scm(sch_1):pch_beep_led';
NODE_NAME     U8 2
 '@SCM_LIB.SCM(SCH_1):PAGE49_I11@PURE_QUANTA.74LVC1G126SE7(CHIPS)':
 'A': CDS_PINID='A';
NODE_NAME     R811 1
 '@SCM_LIB.SCM(SCH_1):PAGE10_I565@PURE_QUANTA.Q_RES(CHIPS)':
 'A': CDS_PINID='A';
NODE_NAME     R847 1
 '@SCM_LIB.SCM(SCH_1):PAGE10_I569@PURE_QUANTA.Q_RES(CHIPS)':
 'A': CDS_PINID='A';
NET_NAME
'PCH_BEEP_R_LED'
 '@SCM_LIB.SCM(SCH_1):PCH_BEEP_R_LED':
 C_SIGNAL='@scm_lib.scm(sch_1):pch_beep_r_led';
NODE_NAME     GF1 B69
 '@SCM_LIB.SCM(SCH_1):PAGE10_I553@PURE_QUANTA.FCONN168_ME1016810202011_SCM(CHIPS)':
 'PCIE_HPM_TXN_3': CDS_PINID='PCIE_HPM_TXN_3';
NODE_NAME     R811 2
 '@SCM_LIB.SCM(SCH_1):PAGE10_I565@PURE_QUANTA.Q_RES(CHIPS)':
 'B': CDS_PINID='B';
NET_NAME
'PD_BIOS_MUX_EN_N'
 '@SCM_LIB.SCM(SCH_1):PD_BIOS_MUX_EN_N':
 C_SIGNAL='@scm_lib.scm(sch_1):pd_bios_mux_en_n';
NODE_NAME     U30 15
 '@SCM_LIB.SCM(SCH_1):PAGE44_I271@PURE_QUANTA.IDTQS3VH257PAG(CHIPS)':
 'E*': CDS_PINID='\e*\';
NODE_NAME     U21 15
 '@SCM_LIB.SCM(SCH_1):PAGE44_I296@PURE_QUANTA.IDTQS3VH257PAG(CHIPS)':
 'E*': CDS_PINID='\e*\';
NODE_NAME     R467 1
 '@SCM_LIB.SCM(SCH_1):PAGE44_I313@PURE_QUANTA.Q_RES(CHIPS)':
 'A': CDS_PINID='A';
NODE_NAME     R870 2
 '@SCM_LIB.SCM(SCH_1):PAGE44_I315@PURE_QUANTA.Q_RES(CHIPS)':
 'B': CDS_PINID='B';
NODE_NAME     R405 2
 '@SCM_LIB.SCM(SCH_1):PAGE13_I430@PURE_QUANTA.Q_RES(CHIPS)':
 'B': CDS_PINID='B';
NET_NAME
'PD_BIOS_MUX_EN_R_N'
 '@SCM_LIB.SCM(SCH_1):PD_BIOS_MUX_EN_R_N':
 C_SIGNAL='@scm_lib.scm(sch_1):pd_bios_mux_en_r_n';
NODE_NAME     U5 D26
 '@SCM_LIB.SCM(SCH_1):PAGE13_I363@PURE_QUANTA.AST2600A3GP(CHIPS)':
 'RGMII4TXD2||NDTR3||GPIOE0': CDS_PINID='\rgmii4txd2||ndtr3||gpioe0\';
NODE_NAME     R405 1
 '@SCM_LIB.SCM(SCH_1):PAGE13_I430@PURE_QUANTA.Q_RES(CHIPS)':
 'A': CDS_PINID='A';
NET_NAME
'PD_CLK_125M_PHY_BMC_RGMII'
 '@SCM_LIB.SCM(SCH_1):PD_CLK_125M_PHY_BMC_RGMII':
 C_SIGNAL='@scm_lib.scm(sch_1):pd_clk_125m_phy_bmc_rgmii';
NODE_NAME     R273 1
 '@SCM_LIB.SCM(SCH_1):PAGE13_I340@PURE_QUANTA.Q_RES(CHIPS)':
 'A': CDS_PINID='A';
NODE_NAME     U5 A10
 '@SCM_LIB.SCM(SCH_1):PAGE13_I363@PURE_QUANTA.AST2600A3GP(CHIPS)':
 'RGMIICK': CDS_PINID='RGMIICK';
NET_NAME
'PD_FRU_WC_N'
 '@SCM_LIB.SCM(SCH_1):PD_FRU_WC_N':
 C_SIGNAL='@scm_lib.scm(sch_1):pd_fru_wc_n';
NODE_NAME     U19 7
 '@SCM_LIB.SCM(SCH_1):PAGE26_I15@PURE_QUANTA.M24128BWDW6TP(CHIPS)':
 'WC#': CDS_PINID='\wc#\';
NODE_NAME     R15 1
 '@SCM_LIB.SCM(SCH_1):PAGE26_I32@PURE_QUANTA.Q_RES(CHIPS)':
 'A': CDS_PINID='A';
NET_NAME
'PD_M_BMC_DDR4_PAR'
 '@SCM_LIB.SCM(SCH_1):PD_M_BMC_DDR4_PAR':
 C_SIGNAL='@scm_lib.scm(sch_1):pd_m_bmc_ddr4_par';
NODE_NAME     R4 1
 '@SCM_LIB.SCM(SCH_1):PAGE20_I141@PURE_QUANTA.Q_RES(CHIPS)':
 'A': CDS_PINID='A';
NODE_NAME     U1 T3
 '@SCM_LIB.SCM(SCH_1):PAGE20_I196@PURE_QUANTA.K4A8G165WCBCTD(CHIPS)':
 'PAR': CDS_PINID='PAR';
NET_NAME
'PD_M_BMC_DDR4_TEN'
 '@SCM_LIB.SCM(SCH_1):PD_M_BMC_DDR4_TEN':
 C_SIGNAL='@scm_lib.scm(sch_1):pd_m_bmc_ddr4_ten';
NODE_NAME     R5 1
 '@SCM_LIB.SCM(SCH_1):PAGE20_I142@PURE_QUANTA.Q_RES(CHIPS)':
 'A': CDS_PINID='A';
NODE_NAME     U1 N9
 '@SCM_LIB.SCM(SCH_1):PAGE20_I196@PURE_QUANTA.K4A8G165WCBCTD(CHIPS)':
 'TEN': CDS_PINID='TEN';
NET_NAME
'PD_M_BMC_DDR4_ZQ'
 '@SCM_LIB.SCM(SCH_1):PD_M_BMC_DDR4_ZQ':
 C_SIGNAL='@scm_lib.scm(sch_1):pd_m_bmc_ddr4_zq';
NODE_NAME     R6 1
 '@SCM_LIB.SCM(SCH_1):PAGE20_I143@PURE_QUANTA.Q_RES(CHIPS)':
 'A': CDS_PINID='A';
NODE_NAME     U1 F9
 '@SCM_LIB.SCM(SCH_1):PAGE20_I196@PURE_QUANTA.K4A8G165WCBCTD(CHIPS)':
 'ZQ': CDS_PINID='ZQ';
NET_NAME
'PD_SP_ENTEST'
 '@SCM_LIB.SCM(SCH_1):PD_SP_ENTEST':
 C_SIGNAL='@scm_lib.scm(sch_1):pd_sp_entest';
NODE_NAME     R210 2
 '@SCM_LIB.SCM(SCH_1):PAGE15_I47@PURE_QUANTA.Q_RES(CHIPS)':
 'B': CDS_PINID='B';
NODE_NAME     U5 C10
 '@SCM_LIB.SCM(SCH_1):PAGE15_I350@PURE_QUANTA.AST2600A3GP(CHIPS)':
 'ENTEST': CDS_PINID='ENTEST';
NET_NAME
'PECI_BMC'
 '@SCM_LIB.SCM(SCH_1):PECI_BMC':
 C_SIGNAL='@scm_lib.scm(sch_1):peci_bmc';
NODE_NAME     GF1 B27
 '@SCM_LIB.SCM(SCH_1):PAGE10_I553@PURE_QUANTA.FCONN168_ME1016810202011_SCM(CHIPS)':
 'PECI_BMC': CDS_PINID='PECI_BMC';
NODE_NAME     R209 1
 '@SCM_LIB.SCM(SCH_1):PAGE15_I19@PURE_QUANTA.Q_RES(CHIPS)':
 'A': CDS_PINID='A';
NODE_NAME     R216 2
 '@SCM_LIB.SCM(SCH_1):PAGE15_I389@PURE_QUANTA.Q_RES(CHIPS)':
 'B': CDS_PINID='B';
NET_NAME
'PECI_BMC_R'
 '@SCM_LIB.SCM(SCH_1):PECI_BMC_R':
 C_SIGNAL='@scm_lib.scm(sch_1):peci_bmc_r';
NODE_NAME     U5 AF16
 '@SCM_LIB.SCM(SCH_1):PAGE15_I350@PURE_QUANTA.AST2600A3GP(CHIPS)':
 'PECI': CDS_PINID='PECI';
NODE_NAME     R216 1
 '@SCM_LIB.SCM(SCH_1):PAGE15_I389@PURE_QUANTA.Q_RES(CHIPS)':
 'A': CDS_PINID='A';
NET_NAME
'PGPPA_BMC_AUX'
 '@SCM_LIB.SCM(SCH_1):PGPPA_BMC_AUX':
 C_SIGNAL='@scm_lib.scm(sch_1):pgppa_bmc_aux',
 CDS_GLOBAL_NET='TRUE';
NODE_NAME     R117 1
 '@SCM_LIB.SCM(SCH_1):PAGE12_I2@PURE_QUANTA.Q_RES(CHIPS)':
 'A': CDS_PINID='A';
NODE_NAME     R116 1
 '@SCM_LIB.SCM(SCH_1):PAGE12_I3@PURE_QUANTA.Q_RES(CHIPS)':
 'A': CDS_PINID='A';
NODE_NAME     R115 1
 '@SCM_LIB.SCM(SCH_1):PAGE12_I4@PURE_QUANTA.Q_RES(CHIPS)':
 'A': CDS_PINID='A';
NODE_NAME     R797 1
 '@SCM_LIB.SCM(SCH_1):PAGE15_I261@PURE_QUANTA.Q_RES(CHIPS)':
 'A': CDS_PINID='A';
NODE_NAME     U5 W15
 '@SCM_LIB.SCM(SCH_1):PAGE16_I188@PURE_QUANTA.AST2600A3GP(CHIPS)':
 'LPVDD': CDS_PINID='LPVDD';
NODE_NAME     L17 2
 '@SCM_LIB.SCM(SCH_1):PAGE17_I176@PURE_QUANTA.Q_INDUCTOR(CHIPS)':
 '2': CDS_PINID='\2\';
NODE_NAME     C96 1
 '@SCM_LIB.SCM(SCH_1):PAGE17_I178@PURE_QUANTA.Q_CAP(CHIPS)':
 'A': CDS_PINID='A';
NODE_NAME     C224 1
 '@SCM_LIB.SCM(SCH_1):PAGE17_I180@PURE_QUANTA.Q_CAP(CHIPS)':
 'A': CDS_PINID='A';
NET_NAME
'PGPPA_BMC_AUX_L'
 '@SCM_LIB.SCM(SCH_1):PGPPA_BMC_AUX_L':
 C_SIGNAL='@scm_lib.scm(sch_1):pgppa_bmc_aux_l';
NODE_NAME     L17 1
 '@SCM_LIB.SCM(SCH_1):PAGE17_I176@PURE_QUANTA.Q_INDUCTOR(CHIPS)':
 '1': CDS_PINID='\1\';
NODE_NAME     Q5 1
 '@SCM_LIB.SCM(SCH_1):PAGE17_I274@PURE_QUANTA.MOSFET_NCH_4D1S(CHIPS)':
 '1': CDS_PINID='\1\';
NODE_NAME     Q5 2
 '@SCM_LIB.SCM(SCH_1):PAGE17_I274@PURE_QUANTA.MOSFET_NCH_4D1S(CHIPS)':
 '2': CDS_PINID='\2\';
NODE_NAME     Q5 5
 '@SCM_LIB.SCM(SCH_1):PAGE17_I274@PURE_QUANTA.MOSFET_NCH_4D1S(CHIPS)':
 '5': CDS_PINID='\5\';
NODE_NAME     Q5 6
 '@SCM_LIB.SCM(SCH_1):PAGE17_I274@PURE_QUANTA.MOSFET_NCH_4D1S(CHIPS)':
 '6': CDS_PINID='\6\';
NODE_NAME     R645 2
 '@SCM_LIB.SCM(SCH_1):PAGE17_I278@PURE_QUANTA.Q_RES(CHIPS)':
 'B': CDS_PINID='B';
NODE_NAME     R646 1
 '@SCM_LIB.SCM(SCH_1):PAGE17_I279@PURE_QUANTA.Q_RES(CHIPS)':
 'A': CDS_PINID='A';
NODE_NAME     Q4 D
 '@SCM_LIB.SCM(SCH_1):PAGE17_I289@PURE_QUANTA.MOSFET_PCH_GDS(CHIPS)':
 'D': CDS_PINID='D';
NET_NAME
'PGPPA_BMC_AUX_SENSOR'
 '@SCM_LIB.SCM(SCH_1):PGPPA_BMC_AUX_SENSOR':
 C_SIGNAL='@scm_lib.scm(sch_1):pgppa_bmc_aux_sensor';
NODE_NAME     C314 1
 '@SCM_LIB.SCM(SCH_1):PAGE15_I259@PURE_QUANTA.Q_CAP(CHIPS)':
 'A': CDS_PINID='A';
NODE_NAME     R797 2
 '@SCM_LIB.SCM(SCH_1):PAGE15_I261@PURE_QUANTA.Q_RES(CHIPS)':
 'B': CDS_PINID='B';
NODE_NAME     R798 1
 '@SCM_LIB.SCM(SCH_1):PAGE15_I262@PURE_QUANTA.Q_RES(CHIPS)':
 'A': CDS_PINID='A';
NODE_NAME     U5 AB19
 '@SCM_LIB.SCM(SCH_1):PAGE15_I350@PURE_QUANTA.AST2600A3GP(CHIPS)':
 'ADC5||GPIT5': CDS_PINID='\adc5||gpit5\';
NET_NAME
'PU_25M_BMC_CLK_EN'
 '@SCM_LIB.SCM(SCH_1):PU_25M_BMC_CLK_EN':
 C_SIGNAL='@scm_lib.scm(sch_1):pu_25m_bmc_clk_en';
NODE_NAME     R212 2
 '@SCM_LIB.SCM(SCH_1):PAGE15_I21@PURE_QUANTA.Q_RES(CHIPS)':
 'B': CDS_PINID='B';
NODE_NAME     OSC1 1
 '@SCM_LIB.SCM(SCH_1):PAGE15_I39@PURE_QUANTA.OSC4_7X25000018(CHIPS)':
 'OE': CDS_PINID='OE';
NET_NAME
'PU_25M_FPGA_CLK_EN'
 '@SCM_LIB.SCM(SCH_1):PU_25M_FPGA_CLK_EN':
 C_SIGNAL='@scm_lib.scm(sch_1):pu_25m_fpga_clk_en';
NODE_NAME     R806 2
 '@SCM_LIB.SCM(SCH_1):PAGE34_I119@PURE_QUANTA.Q_RES(CHIPS)':
 'B': CDS_PINID='B';
NODE_NAME     OSC2 1
 '@SCM_LIB.SCM(SCH_1):PAGE34_I127@PURE_QUANTA.OSC4_7X25000018(CHIPS)':
 'OE': CDS_PINID='OE';
NET_NAME
'PU_BMC_FWSPIABR_N'
 '@SCM_LIB.SCM(SCH_1):PU_BMC_FWSPIABR_N':
 C_SIGNAL='@scm_lib.scm(sch_1):pu_bmc_fwspiabr_n';
NODE_NAME     R239 2
 '@SCM_LIB.SCM(SCH_1):PAGE13_I185@PURE_QUANTA.Q_RES(CHIPS)':
 'B': CDS_PINID='B';
NODE_NAME     R401 1
 '@SCM_LIB.SCM(SCH_1):PAGE13_I374@PURE_QUANTA.Q_RES(CHIPS)':
 'A': CDS_PINID='A';
NET_NAME
'PU_BMC_FWSPIABR_N_R'
 '@SCM_LIB.SCM(SCH_1):PU_BMC_FWSPIABR_N_R':
 C_SIGNAL='@scm_lib.scm(sch_1):pu_bmc_fwspiabr_n_r';
NODE_NAME     U5 AC12
 '@SCM_LIB.SCM(SCH_1):PAGE13_I363@PURE_QUANTA.AST2600A3GP(CHIPS)':
 'GPIOY6||FWSPIABR': CDS_PINID='\gpioy6||fwspiabr\';
NODE_NAME     R401 2
 '@SCM_LIB.SCM(SCH_1):PAGE13_I374@PURE_QUANTA.Q_RES(CHIPS)':
 'B': CDS_PINID='B';
NET_NAME
'PU_FPGA_CONFIG_DONE'
 '@SCM_LIB.SCM(SCH_1):PU_FPGA_CONFIG_DONE':
 C_SIGNAL='@scm_lib.scm(sch_1):pu_fpga_config_done';
NODE_NAME     U25 C13
 '@SCM_LIB.SCM(SCH_1):PAGE34_I1@PURE_QUANTA.LCMXO3LF2100C5BG256C(CHIPS)':
 'PT24D||DONE': CDS_PINID='\pt24d||done\';
NODE_NAME     R808 1
 '@SCM_LIB.SCM(SCH_1):PAGE34_I117@PURE_QUANTA.Q_RES(CHIPS)':
 'A': CDS_PINID='A';
NET_NAME
'PU_FPGA_NCONFIG'
 '@SCM_LIB.SCM(SCH_1):PU_FPGA_NCONFIG':
 C_SIGNAL='@scm_lib.scm(sch_1):pu_fpga_nconfig';
NODE_NAME     R809 1
 '@SCM_LIB.SCM(SCH_1):PAGE34_I115@PURE_QUANTA.Q_RES(CHIPS)':
 'A': CDS_PINID='A';
NODE_NAME     U25 M10
 '@SCM_LIB.SCM(SCH_1):PAGE36_I1@PURE_QUANTA.LCMXO3LF2100C5BG256C(CHIPS)':
 'PB21C': CDS_PINID='PB21C';
NODE_NAME     R748 1
 '@SCM_LIB.SCM(SCH_1):PAGE36_I78@PURE_QUANTA.Q_RES(CHIPS)':
 'A': CDS_PINID='A';
NET_NAME
'PU_FPGA_NSTATUS'
 '@SCM_LIB.SCM(SCH_1):PU_FPGA_NSTATUS':
 C_SIGNAL='@scm_lib.scm(sch_1):pu_fpga_nstatus';
NODE_NAME     U25 A13
 '@SCM_LIB.SCM(SCH_1):PAGE34_I1@PURE_QUANTA.LCMXO3LF2100C5BG256C(CHIPS)':
 'PT24C||INITN': CDS_PINID='\pt24c||initn\';
NODE_NAME     R810 1
 '@SCM_LIB.SCM(SCH_1):PAGE34_I116@PURE_QUANTA.Q_RES(CHIPS)':
 'A': CDS_PINID='A';
NET_NAME
'PU_FWSPIWP_N'
 '@SCM_LIB.SCM(SCH_1):PU_FWSPIWP_N':
 C_SIGNAL='@scm_lib.scm(sch_1):pu_fwspiwp_n';
NODE_NAME     R240 2
 '@SCM_LIB.SCM(SCH_1):PAGE13_I187@PURE_QUANTA.Q_RES(CHIPS)':
 'B': CDS_PINID='B';
NODE_NAME     R402 1
 '@SCM_LIB.SCM(SCH_1):PAGE13_I373@PURE_QUANTA.Q_RES(CHIPS)':
 'A': CDS_PINID='A';
NET_NAME
'PU_FWSPIWP_N_R'
 '@SCM_LIB.SCM(SCH_1):PU_FWSPIWP_N_R':
 C_SIGNAL='@scm_lib.scm(sch_1):pu_fwspiwp_n_r';
NODE_NAME     U5 AB12
 '@SCM_LIB.SCM(SCH_1):PAGE13_I363@PURE_QUANTA.AST2600A3GP(CHIPS)':
 'GPIOY7||FWSPIWP#': CDS_PINID='\gpioy7||fwspiwp#\';
NODE_NAME     R402 2
 '@SCM_LIB.SCM(SCH_1):PAGE13_I373@PURE_QUANTA.Q_RES(CHIPS)':
 'B': CDS_PINID='B';
NET_NAME
'PU_J13_P1'
 '@SCM_LIB.SCM(SCH_1):PU_J13_P1':
 C_SIGNAL='@scm_lib.scm(sch_1):pu_j13_p1';
NODE_NAME     J13 1
 '@SCM_LIB.SCM(SCH_1):PAGE31_I61@PURE_QUANTA.SCONN3_212H9103GBR1(CHIPS)':
 '1': CDS_PINID='\1\';
NODE_NAME     R630 2
 '@SCM_LIB.SCM(SCH_1):PAGE31_I79@PURE_QUANTA.Q_RES(CHIPS)':
 'B': CDS_PINID='B';
NET_NAME
'PU_J1_P1'
 '@SCM_LIB.SCM(SCH_1):PU_J1_P1':
 C_SIGNAL='@scm_lib.scm(sch_1):pu_j1_p1';
NODE_NAME     J1 1
 '@SCM_LIB.SCM(SCH_1):PAGE25_I169@PURE_QUANTA.SCONN3_212H9103GBR1(CHIPS)':
 '1': CDS_PINID='\1\';
NODE_NAME     R592 2
 '@SCM_LIB.SCM(SCH_1):PAGE25_I171@PURE_QUANTA.Q_RES(CHIPS)':
 'B': CDS_PINID='B';
NET_NAME
'PU_PB25A'
 '@SCM_LIB.SCM(SCH_1):PU_PB25A':
 C_SIGNAL='@scm_lib.scm(sch_1):pu_pb25a';
NODE_NAME     U25 R12
 '@SCM_LIB.SCM(SCH_1):PAGE36_I1@PURE_QUANTA.LCMXO3LF2100C5BG256C(CHIPS)':
 'PB25A||SN': CDS_PINID='\pb25a||sn\';
NODE_NAME     R288 2
 '@SCM_LIB.SCM(SCH_1):PAGE36_I50@PURE_QUANTA.Q_RES(CHIPS)':
 'B': CDS_PINID='B';
NET_NAME
'PU_PT20D'
 '@SCM_LIB.SCM(SCH_1):PU_PT20D':
 C_SIGNAL='@scm_lib.scm(sch_1):pu_pt20d';
NODE_NAME     U25 B10
 '@SCM_LIB.SCM(SCH_1):PAGE34_I1@PURE_QUANTA.LCMXO3LF2100C5BG256C(CHIPS)':
 'PT20D||PROGRAMN': CDS_PINID='\pt20d||programn\';
NODE_NAME     R297 1
 '@SCM_LIB.SCM(SCH_1):PAGE34_I137@PURE_QUANTA.Q_RES(CHIPS)':
 'A': CDS_PINID='A';
NET_NAME
'PU_SPI1ABR'
 '@SCM_LIB.SCM(SCH_1):PU_SPI1ABR':
 C_SIGNAL='@scm_lib.scm(sch_1):pu_spi1abr';
NODE_NAME     R241 2
 '@SCM_LIB.SCM(SCH_1):PAGE13_I186@PURE_QUANTA.Q_RES(CHIPS)':
 'B': CDS_PINID='B';
NODE_NAME     U5 AD10
 '@SCM_LIB.SCM(SCH_1):PAGE13_I363@PURE_QUANTA.AST2600A3GP(CHIPS)':
 'GPIOZ1||SPI1ABR': CDS_PINID='\gpioz1||spi1abr\';
NET_NAME
'PU_SPI1WP_N'
 '@SCM_LIB.SCM(SCH_1):PU_SPI1WP_N':
 C_SIGNAL='@scm_lib.scm(sch_1):pu_spi1wp_n';
NODE_NAME     R683 2
 '@SCM_LIB.SCM(SCH_1):PAGE13_I188@PURE_QUANTA.Q_RES(CHIPS)':
 'B': CDS_PINID='B';
NODE_NAME     U5 AE10
 '@SCM_LIB.SCM(SCH_1):PAGE13_I363@PURE_QUANTA.AST2600A3GP(CHIPS)':
 'GPIOZ2||SPI1WP#': CDS_PINID='\gpioz2||spi1wp#\';
NET_NAME
'PVCC1_AUX'
 '@SCM_LIB.SCM(SCH_1):PVCC1_AUX':
 C_SIGNAL='@scm_lib.scm(sch_1):pvcc1_aux',
 CDS_GLOBAL_NET='TRUE';
NODE_NAME     PR539 1
 '@SCM_LIB.SCM(SCH_1):PAGE55_I8@PURE_QUANTA.Q_RES(CHIPS)':
 'A': CDS_PINID='A';
NODE_NAME     PR274 2
 '@SCM_LIB.SCM(SCH_1):PAGE55_I45@PURE_QUANTA.Q_RES(CHIPS)':
 'B': CDS_PINID='B';
NODE_NAME     PR275 2
 '@SCM_LIB.SCM(SCH_1):PAGE55_I48@PURE_QUANTA.Q_RES(CHIPS)':
 'B': CDS_PINID='B';
NET_NAME
'PVCC2_AUX'
 '@SCM_LIB.SCM(SCH_1):PVCC2_AUX':
 C_SIGNAL='@scm_lib.scm(sch_1):pvcc2_aux',
 CDS_GLOBAL_NET='TRUE';
NODE_NAME     PR541 1
 '@SCM_LIB.SCM(SCH_1):PAGE56_I8@PURE_QUANTA.Q_RES(CHIPS)':
 'A': CDS_PINID='A';
NODE_NAME     PR193 2
 '@SCM_LIB.SCM(SCH_1):PAGE56_I47@PURE_QUANTA.Q_RES(CHIPS)':
 'B': CDS_PINID='B';
NODE_NAME     PR205 2
 '@SCM_LIB.SCM(SCH_1):PAGE56_I48@PURE_QUANTA.Q_RES(CHIPS)':
 'B': CDS_PINID='B';
NET_NAME
'PVCCA_AUX_PLD'
 '@SCM_LIB.SCM(SCH_1):PVCCA_AUX_PLD':
 C_SIGNAL='@scm_lib.scm(sch_1):pvcca_aux_pld',
 CDS_GLOBAL_NET='TRUE';
NODE_NAME     U25 A1
 '@SCM_LIB.SCM(SCH_1):PAGE40_I1@PURE_QUANTA.LCMXO3LF2100C5BG256C(CHIPS)':
 'VCC_A1': CDS_PINID='VCC_A1';
NODE_NAME     U25 A16
 '@SCM_LIB.SCM(SCH_1):PAGE40_I1@PURE_QUANTA.LCMXO3LF2100C5BG256C(CHIPS)':
 'VCC_A16': CDS_PINID='VCC_A16';
NODE_NAME     U25 G7
 '@SCM_LIB.SCM(SCH_1):PAGE40_I1@PURE_QUANTA.LCMXO3LF2100C5BG256C(CHIPS)':
 'VCC_G7': CDS_PINID='VCC_G7';
NODE_NAME     U25 G10
 '@SCM_LIB.SCM(SCH_1):PAGE40_I1@PURE_QUANTA.LCMXO3LF2100C5BG256C(CHIPS)':
 'VCC_G10': CDS_PINID='VCC_G10';
NODE_NAME     U25 K7
 '@SCM_LIB.SCM(SCH_1):PAGE40_I1@PURE_QUANTA.LCMXO3LF2100C5BG256C(CHIPS)':
 'VCC_K7': CDS_PINID='VCC_K7';
NODE_NAME     U25 K10
 '@SCM_LIB.SCM(SCH_1):PAGE40_I1@PURE_QUANTA.LCMXO3LF2100C5BG256C(CHIPS)':
 'VCC_K10': CDS_PINID='VCC_K10';
NODE_NAME     U25 T1
 '@SCM_LIB.SCM(SCH_1):PAGE40_I1@PURE_QUANTA.LCMXO3LF2100C5BG256C(CHIPS)':
 'VCC_T1': CDS_PINID='VCC_T1';
NODE_NAME     U25 T16
 '@SCM_LIB.SCM(SCH_1):PAGE40_I1@PURE_QUANTA.LCMXO3LF2100C5BG256C(CHIPS)':
 'VCC_T16': CDS_PINID='VCC_T16';
NODE_NAME     L19 2
 '@SCM_LIB.SCM(SCH_1):PAGE41_I107@PURE_QUANTA.Q_INDUCTOR(CHIPS)':
 '2': CDS_PINID='\2\';
NODE_NAME     C176 1
 '@SCM_LIB.SCM(SCH_1):PAGE41_I108@PURE_QUANTA.Q_CAP(CHIPS)':
 'A': CDS_PINID='A';
NODE_NAME     C193 1
 '@SCM_LIB.SCM(SCH_1):PAGE41_I109@PURE_QUANTA.Q_CAP(CHIPS)':
 'A': CDS_PINID='A';
NODE_NAME     C250 1
 '@SCM_LIB.SCM(SCH_1):PAGE41_I115@PURE_QUANTA.Q_CAP(CHIPS)':
 'A': CDS_PINID='A';
NODE_NAME     C190 1
 '@SCM_LIB.SCM(SCH_1):PAGE41_I116@PURE_QUANTA.Q_CAP(CHIPS)':
 'A': CDS_PINID='A';
NODE_NAME     C263 1
 '@SCM_LIB.SCM(SCH_1):PAGE41_I117@PURE_QUANTA.Q_CAP(CHIPS)':
 'A': CDS_PINID='A';
NODE_NAME     C269 1
 '@SCM_LIB.SCM(SCH_1):PAGE41_I118@PURE_QUANTA.Q_CAP(CHIPS)':
 'A': CDS_PINID='A';
NODE_NAME     C266 1
 '@SCM_LIB.SCM(SCH_1):PAGE41_I119@PURE_QUANTA.Q_CAP(CHIPS)':
 'A': CDS_PINID='A';
NODE_NAME     C163 1
 '@SCM_LIB.SCM(SCH_1):PAGE41_I122@PURE_QUANTA.Q_CAP(CHIPS)':
 'A': CDS_PINID='A';
NODE_NAME     C286 1
 '@SCM_LIB.SCM(SCH_1):PAGE41_I123@PURE_QUANTA.Q_CAP(CHIPS)':
 'A': CDS_PINID='A';
NET_NAME
'PVCCIO_AUX_PLD'
 '@SCM_LIB.SCM(SCH_1):PVCCIO_AUX_PLD':
 C_SIGNAL='@scm_lib.scm(sch_1):pvccio_aux_pld',
 CDS_GLOBAL_NET='TRUE';
NODE_NAME     R809 2
 '@SCM_LIB.SCM(SCH_1):PAGE34_I115@PURE_QUANTA.Q_RES(CHIPS)':
 'B': CDS_PINID='B';
NODE_NAME     R810 2
 '@SCM_LIB.SCM(SCH_1):PAGE34_I116@PURE_QUANTA.Q_RES(CHIPS)':
 'B': CDS_PINID='B';
NODE_NAME     R808 2
 '@SCM_LIB.SCM(SCH_1):PAGE34_I117@PURE_QUANTA.Q_RES(CHIPS)':
 'B': CDS_PINID='B';
NODE_NAME     R183 2
 '@SCM_LIB.SCM(SCH_1):PAGE34_I139@PURE_QUANTA.Q_RES(CHIPS)':
 'B': CDS_PINID='B';
NODE_NAME     C256 1
 '@SCM_LIB.SCM(SCH_1):PAGE34_I140@PURE_QUANTA.Q_CAP(CHIPS)':
 'A': CDS_PINID='A';
NODE_NAME     C257 1
 '@SCM_LIB.SCM(SCH_1):PAGE34_I144@PURE_QUANTA.Q_CAP(CHIPS)':
 'A': CDS_PINID='A';
NET_NAME
'PVCCIO_PECI_BMC'
 '@SCM_LIB.SCM(SCH_1):PVCCIO_PECI_BMC':
 C_SIGNAL='@scm_lib.scm(sch_1):pvccio_peci_bmc';
NODE_NAME     GF1 B28
 '@SCM_LIB.SCM(SCH_1):PAGE10_I553@PURE_QUANTA.FCONN168_ME1016810202011_SCM(CHIPS)':
 'PVCCIO_PECI': CDS_PINID='PVCCIO_PECI';
NODE_NAME     C42 1
 '@SCM_LIB.SCM(SCH_1):PAGE15_I117@PURE_QUANTA.Q_CAP(CHIPS)':
 'A': CDS_PINID='A';
NODE_NAME     C43 1
 '@SCM_LIB.SCM(SCH_1):PAGE15_I119@PURE_QUANTA.Q_CAP(CHIPS)':
 'A': CDS_PINID='A';
NODE_NAME     U5 AA18
 '@SCM_LIB.SCM(SCH_1):PAGE15_I350@PURE_QUANTA.AST2600A3GP(CHIPS)':
 'PECIVDD': CDS_PINID='PECIVDD';
NET_NAME
'PWRGD_CPUPWRGD_LVC1'
 '@SCM_LIB.SCM(SCH_1):PWRGD_CPUPWRGD_LVC1':
 C_SIGNAL='@scm_lib.scm(sch_1):pwrgd_cpupwrgd_lvc1';
NODE_NAME     U5 W26
 '@SCM_LIB.SCM(SCH_1):PAGE15_I350@PURE_QUANTA.AST2600A3GP(CHIPS)':
 'GPIOR6||TACH14': CDS_PINID='\gpior6||tach14\';
NODE_NAME     U25 C11
 '@SCM_LIB.SCM(SCH_1):PAGE34_I1@PURE_QUANTA.LCMXO3LF2100C5BG256C(CHIPS)':
 'PT21B': CDS_PINID='PT21B';
NET_NAME
'PWRGD_DSW_PWROK'
 '@SCM_LIB.SCM(SCH_1):PWRGD_DSW_PWROK':
 C_SIGNAL='@scm_lib.scm(sch_1):pwrgd_dsw_pwrok';
NODE_NAME     R643 1
 '@SCM_LIB.SCM(SCH_1):PAGE13_I344@PURE_QUANTA.Q_RES(CHIPS)':
 'A': CDS_PINID='A';
NODE_NAME     R703 1
 '@SCM_LIB.SCM(SCH_1):PAGE28_I127@PURE_QUANTA.Q_RES(CHIPS)':
 'A': CDS_PINID='A';
NODE_NAME     R578 1
 '@SCM_LIB.SCM(SCH_1):PAGE36_I8@PURE_QUANTA.Q_RES(CHIPS)':
 'A': CDS_PINID='A';
NODE_NAME     R627 2
 '@SCM_LIB.SCM(SCH_1):PAGE42_I7@PURE_QUANTA.Q_RES(CHIPS)':
 'B': CDS_PINID='B';
NET_NAME
'PWRGD_DSW_PWROK_R1'
 '@SCM_LIB.SCM(SCH_1):PWRGD_DSW_PWROK_R1':
 C_SIGNAL='@scm_lib.scm(sch_1):pwrgd_dsw_pwrok_r1';
NODE_NAME     R643 2
 '@SCM_LIB.SCM(SCH_1):PAGE13_I344@PURE_QUANTA.Q_RES(CHIPS)':
 'B': CDS_PINID='B';
NODE_NAME     U5 AA9
 '@SCM_LIB.SCM(SCH_1):PAGE13_I363@PURE_QUANTA.AST2600A3GP(CHIPS)':
 'GPIOX1||SPI2CS1#': CDS_PINID='\gpiox1||spi2cs1#\';
NET_NAME
'PWRGD_DSW_PWROK_R2'
 '@SCM_LIB.SCM(SCH_1):PWRGD_DSW_PWROK_R2':
 C_SIGNAL='@scm_lib.scm(sch_1):pwrgd_dsw_pwrok_r2';
NODE_NAME     U25 R3
 '@SCM_LIB.SCM(SCH_1):PAGE36_I1@PURE_QUANTA.LCMXO3LF2100C5BG256C(CHIPS)':
 'PB3D': CDS_PINID='PB3D';
NODE_NAME     R578 2
 '@SCM_LIB.SCM(SCH_1):PAGE36_I8@PURE_QUANTA.Q_RES(CHIPS)':
 'B': CDS_PINID='B';
NET_NAME
'PWRGD_DSW_PWROK_R3'
 '@SCM_LIB.SCM(SCH_1):PWRGD_DSW_PWROK_R3':
 C_SIGNAL='@scm_lib.scm(sch_1):pwrgd_dsw_pwrok_r3';
NODE_NAME     R703 2
 '@SCM_LIB.SCM(SCH_1):PAGE28_I127@PURE_QUANTA.Q_RES(CHIPS)':
 'B': CDS_PINID='B';
NODE_NAME     R719 2
 '@SCM_LIB.SCM(SCH_1):PAGE28_I128@PURE_QUANTA.Q_RES(CHIPS)':
 'B': CDS_PINID='B';
NODE_NAME     U40 17
 '@SCM_LIB.SCM(SCH_1):PAGE28_I141@PURE_QUANTA.PCA9555PW(CHIPS)':
 'P14': CDS_PINID='P14';
NET_NAME
'PWRGD_EN_P3V3_R'
 '@SCM_LIB.SCM(SCH_1):PWRGD_EN_P3V3_R':
 C_SIGNAL='@scm_lib.scm(sch_1):pwrgd_en_p3v3_r';
NODE_NAME     PU1 5
 '@SCM_LIB.SCM(SCH_1):PAGE52_I82@PURE_QUANTA.MPQ8626GDZ(CHIPS)':
 'EN': CDS_PINID='EN';
NODE_NAME     R381 2
 '@SCM_LIB.SCM(SCH_1):PAGE52_I97@PURE_QUANTA.Q_RES(CHIPS)':
 'B': CDS_PINID='B';
NODE_NAME     R871 2
 '@SCM_LIB.SCM(SCH_1):PAGE52_I137@PURE_QUANTA.Q_RES(CHIPS)':
 'B': CDS_PINID='B';
NET_NAME
'PWRGD_P1V0_AUX'
 '@SCM_LIB.SCM(SCH_1):PWRGD_P1V0_AUX':
 C_SIGNAL='@scm_lib.scm(sch_1):pwrgd_p1v0_aux';
NODE_NAME     R49 1
 '@SCM_LIB.SCM(SCH_1):PAGE22_I72@PURE_QUANTA.Q_RES(CHIPS)':
 'A': CDS_PINID='A';
NODE_NAME     R379 2
 '@SCM_LIB.SCM(SCH_1):PAGE36_I36@PURE_QUANTA.Q_RES(CHIPS)':
 'B': CDS_PINID='B';
NODE_NAME     R277 2
 '@SCM_LIB.SCM(SCH_1):PAGE56_I54@PURE_QUANTA.Q_RES(CHIPS)':
 'B': CDS_PINID='B';
NET_NAME
'PWRGD_P1V0_AUX_DELAY'
 '@SCM_LIB.SCM(SCH_1):PWRGD_P1V0_AUX_DELAY':
 C_SIGNAL='@scm_lib.scm(sch_1):pwrgd_p1v0_aux_delay';
NODE_NAME     R711 2
 '@SCM_LIB.SCM(SCH_1):PAGE22_I49@PURE_QUANTA.Q_RES(CHIPS)':
 'B': CDS_PINID='B';
NODE_NAME     R451 1
 '@SCM_LIB.SCM(SCH_1):PAGE22_I74@PURE_QUANTA.Q_RES(CHIPS)':
 'A': CDS_PINID='A';
NODE_NAME     U6 1
 '@SCM_LIB.SCM(SCH_1):PAGE22_I87@PURE_QUANTA.74LVC2G07DW7(CHIPS)':
 '1A': CDS_PINID='\1a\';
NODE_NAME     Q13 2
 '@SCM_LIB.SCM(SCH_1):PAGE50_I218@PURE_QUANTA.MOSFET_NCH_DUAL(CHIPS)':
 'G1': CDS_PINID='G1';
NODE_NAME     R395 2
 '@SCM_LIB.SCM(SCH_1):PAGE13_I448@PURE_QUANTA.Q_RES(CHIPS)':
 'B': CDS_PINID='B';
NET_NAME
'PWRGD_P1V0_AUX_DELAY_BUF'
 '@SCM_LIB.SCM(SCH_1):PWRGD_P1V0_AUX_DELAY_BUF':
 C_SIGNAL='@scm_lib.scm(sch_1):pwrgd_p1v0_aux_delay_buf';
NODE_NAME     R192 1
 '@SCM_LIB.SCM(SCH_1):PAGE22_I41@PURE_QUANTA.Q_RES(CHIPS)':
 'A': CDS_PINID='A';
NODE_NAME     U6 6
 '@SCM_LIB.SCM(SCH_1):PAGE22_I87@PURE_QUANTA.74LVC2G07DW7(CHIPS)':
 '1Y': CDS_PINID='\1y\';
NET_NAME
'PWRGD_P1V0_AUX_DELAY_R'
 '@SCM_LIB.SCM(SCH_1):PWRGD_P1V0_AUX_DELAY_R':
 C_SIGNAL='@scm_lib.scm(sch_1):pwrgd_p1v0_aux_delay_r';
NODE_NAME     U28 4
 '@SCM_LIB.SCM(SCH_1):PAGE13_I435@PURE_QUANTA.74LVC1G66GV(CHIPS)':
 'E': CDS_PINID='E';
NODE_NAME     R395 1
 '@SCM_LIB.SCM(SCH_1):PAGE13_I448@PURE_QUANTA.Q_RES(CHIPS)':
 'A': CDS_PINID='A';
NET_NAME
'PWRGD_P1V0_AUX_DELAY_R1'
 '@SCM_LIB.SCM(SCH_1):PWRGD_P1V0_AUX_DELAY_R1':
 C_SIGNAL='@scm_lib.scm(sch_1):pwrgd_p1v0_aux_delay_r1';
NODE_NAME     R451 2
 '@SCM_LIB.SCM(SCH_1):PAGE22_I74@PURE_QUANTA.Q_RES(CHIPS)':
 'B': CDS_PINID='B';
NODE_NAME     R751 2
 '@SCM_LIB.SCM(SCH_1):PAGE22_I83@PURE_QUANTA.Q_RES(CHIPS)':
 'B': CDS_PINID='B';
NODE_NAME     U43 1
 '@SCM_LIB.SCM(SCH_1):PAGE22_I90@PURE_QUANTA.TPS3808G18DBVR(CHIPS)':
 '#RESET': CDS_PINID='\#reset\';
NET_NAME
'PWRGD_P1V0_AUX_R'
 '@SCM_LIB.SCM(SCH_1):PWRGD_P1V0_AUX_R':
 C_SIGNAL='@scm_lib.scm(sch_1):pwrgd_p1v0_aux_r';
NODE_NAME     PU42 13
 '@SCM_LIB.SCM(SCH_1):PAGE56_I15@PURE_QUANTA.NB695GDZ(CHIPS)':
 'PG': CDS_PINID='PG';
NODE_NAME     PR500 2
 '@SCM_LIB.SCM(SCH_1):PAGE56_I18@PURE_QUANTA.Q_RES(CHIPS)':
 'B': CDS_PINID='B';
NODE_NAME     C156 1
 '@SCM_LIB.SCM(SCH_1):PAGE56_I51@PURE_QUANTA.Q_CAP(CHIPS)':
 'A': CDS_PINID='A';
NODE_NAME     R277 1
 '@SCM_LIB.SCM(SCH_1):PAGE56_I54@PURE_QUANTA.Q_RES(CHIPS)':
 'A': CDS_PINID='A';
NET_NAME
'PWRGD_P1V0_AUX_R1'
 '@SCM_LIB.SCM(SCH_1):PWRGD_P1V0_AUX_R1':
 C_SIGNAL='@scm_lib.scm(sch_1):pwrgd_p1v0_aux_r1';
NODE_NAME     U25 P9
 '@SCM_LIB.SCM(SCH_1):PAGE36_I1@PURE_QUANTA.LCMXO3LF2100C5BG256C(CHIPS)':
 'PB16B||PCLKC2_1': CDS_PINID='\pb16b||pclkc2_1\';
NODE_NAME     R379 1
 '@SCM_LIB.SCM(SCH_1):PAGE36_I36@PURE_QUANTA.Q_RES(CHIPS)':
 'A': CDS_PINID='A';
NET_NAME
'PWRGD_P1V0_AUX_R2'
 '@SCM_LIB.SCM(SCH_1):PWRGD_P1V0_AUX_R2':
 C_SIGNAL='@scm_lib.scm(sch_1):pwrgd_p1v0_aux_r2';
NODE_NAME     R49 2
 '@SCM_LIB.SCM(SCH_1):PAGE22_I72@PURE_QUANTA.Q_RES(CHIPS)':
 'B': CDS_PINID='B';
NODE_NAME     U43 3
 '@SCM_LIB.SCM(SCH_1):PAGE22_I90@PURE_QUANTA.TPS3808G18DBVR(CHIPS)':
 '#MR': CDS_PINID='\#mr\';
NET_NAME
'PWRGD_P1V2_AUX'
 '@SCM_LIB.SCM(SCH_1):PWRGD_P1V2_AUX':
 C_SIGNAL='@scm_lib.scm(sch_1):pwrgd_p1v2_aux';
NODE_NAME     R323 2
 '@SCM_LIB.SCM(SCH_1):PAGE36_I34@PURE_QUANTA.Q_RES(CHIPS)':
 'B': CDS_PINID='B';
NODE_NAME     R276 2
 '@SCM_LIB.SCM(SCH_1):PAGE55_I50@PURE_QUANTA.Q_RES(CHIPS)':
 'B': CDS_PINID='B';
NODE_NAME     U53 2
 '@SCM_LIB.SCM(SCH_1):PAGE56_I66@PURE_QUANTA.74LVC1G08GW(CHIPS)':
 'A': CDS_PINID='A';
NET_NAME
'PWRGD_P1V2_AUX_R'
 '@SCM_LIB.SCM(SCH_1):PWRGD_P1V2_AUX_R':
 C_SIGNAL='@scm_lib.scm(sch_1):pwrgd_p1v2_aux_r';
NODE_NAME     PU41 13
 '@SCM_LIB.SCM(SCH_1):PAGE55_I15@PURE_QUANTA.NB695GDZ(CHIPS)':
 'PG': CDS_PINID='PG';
NODE_NAME     PR498 2
 '@SCM_LIB.SCM(SCH_1):PAGE55_I18@PURE_QUANTA.Q_RES(CHIPS)':
 'B': CDS_PINID='B';
NODE_NAME     R276 1
 '@SCM_LIB.SCM(SCH_1):PAGE55_I50@PURE_QUANTA.Q_RES(CHIPS)':
 'A': CDS_PINID='A';
NODE_NAME     C155 1
 '@SCM_LIB.SCM(SCH_1):PAGE55_I52@PURE_QUANTA.Q_CAP(CHIPS)':
 'A': CDS_PINID='A';
NODE_NAME     R877 1
 '@SCM_LIB.SCM(SCH_1):PAGE55_I70@PURE_QUANTA.Q_RES(CHIPS)':
 'A': CDS_PINID='A';
NET_NAME
'PWRGD_P1V2_AUX_R1'
 '@SCM_LIB.SCM(SCH_1):PWRGD_P1V2_AUX_R1':
 C_SIGNAL='@scm_lib.scm(sch_1):pwrgd_p1v2_aux_r1';
NODE_NAME     U25 T9
 '@SCM_LIB.SCM(SCH_1):PAGE36_I1@PURE_QUANTA.LCMXO3LF2100C5BG256C(CHIPS)':
 'PB16A||PCLKT2_1': CDS_PINID='\pb16a||pclkt2_1\';
NODE_NAME     R323 1
 '@SCM_LIB.SCM(SCH_1):PAGE36_I34@PURE_QUANTA.Q_RES(CHIPS)':
 'A': CDS_PINID='A';
NET_NAME
'PWRGD_P1V2_AUX_R2'
 '@SCM_LIB.SCM(SCH_1):PWRGD_P1V2_AUX_R2':
 C_SIGNAL='@scm_lib.scm(sch_1):pwrgd_p1v2_aux_r2';
NODE_NAME     R877 2
 '@SCM_LIB.SCM(SCH_1):PAGE55_I70@PURE_QUANTA.Q_RES(CHIPS)':
 'B': CDS_PINID='B';
NODE_NAME     R878 1
 '@SCM_LIB.SCM(SCH_1):PAGE56_I72@PURE_QUANTA.Q_RES(CHIPS)':
 'A': CDS_PINID='A';
NET_NAME
'PWRGD_P1V8_AUX'
 '@SCM_LIB.SCM(SCH_1):PWRGD_P1V8_AUX':
 C_SIGNAL='@scm_lib.scm(sch_1):pwrgd_p1v8_aux';
NODE_NAME     R321 2
 '@SCM_LIB.SCM(SCH_1):PAGE36_I33@PURE_QUANTA.Q_RES(CHIPS)':
 'B': CDS_PINID='B';
NODE_NAME     R275 1
 '@SCM_LIB.SCM(SCH_1):PAGE54_I99@PURE_QUANTA.Q_RES(CHIPS)':
 'A': CDS_PINID='A';
NODE_NAME     R764 1
 '@SCM_LIB.SCM(SCH_1):PAGE55_I41@PURE_QUANTA.Q_RES(CHIPS)':
 'A': CDS_PINID='A';
NODE_NAME     U42 2
 '@SCM_LIB.SCM(SCH_1):PAGE52_I104@PURE_QUANTA.MC74VHC1G32DTT1G(CHIPS)':
 'IN_A': CDS_PINID='IN_A';
NODE_NAME     R529 1
 '@SCM_LIB.SCM(SCH_1):PAGE52_I127@PURE_QUANTA.Q_RES(CHIPS)':
 'A': CDS_PINID='A';
NET_NAME
'PWRGD_P1V8_AUX_R'
 '@SCM_LIB.SCM(SCH_1):PWRGD_P1V8_AUX_R':
 C_SIGNAL='@scm_lib.scm(sch_1):pwrgd_p1v8_aux_r';
NODE_NAME     U41 5
 '@SCM_LIB.SCM(SCH_1):PAGE54_I96@PURE_QUANTA.RT9059GQW(CHIPS)':
 'PGOOD': CDS_PINID='PGOOD';
NODE_NAME     R275 2
 '@SCM_LIB.SCM(SCH_1):PAGE54_I99@PURE_QUANTA.Q_RES(CHIPS)':
 'B': CDS_PINID='B';
NODE_NAME     C154 1
 '@SCM_LIB.SCM(SCH_1):PAGE54_I100@PURE_QUANTA.Q_CAP(CHIPS)':
 'A': CDS_PINID='A';
NODE_NAME     R406 2
 '@SCM_LIB.SCM(SCH_1):PAGE54_I108@PURE_QUANTA.Q_RES(CHIPS)':
 'B': CDS_PINID='B';
NODE_NAME     R874 2
 '@SCM_LIB.SCM(SCH_1):PAGE54_I139@PURE_QUANTA.Q_RES(CHIPS)':
 'B': CDS_PINID='B';
NET_NAME
'PWRGD_P1V8_AUX_R1'
 '@SCM_LIB.SCM(SCH_1):PWRGD_P1V8_AUX_R1':
 C_SIGNAL='@scm_lib.scm(sch_1):pwrgd_p1v8_aux_r1';
NODE_NAME     U25 M8
 '@SCM_LIB.SCM(SCH_1):PAGE36_I1@PURE_QUANTA.LCMXO3LF2100C5BG256C(CHIPS)':
 'PB16C': CDS_PINID='PB16C';
NODE_NAME     R321 1
 '@SCM_LIB.SCM(SCH_1):PAGE36_I33@PURE_QUANTA.Q_RES(CHIPS)':
 'A': CDS_PINID='A';
NET_NAME
'PWRGD_P1V8_AUX_R2'
 '@SCM_LIB.SCM(SCH_1):PWRGD_P1V8_AUX_R2':
 C_SIGNAL='@scm_lib.scm(sch_1):pwrgd_p1v8_aux_r2';
NODE_NAME     U18 2
 '@SCM_LIB.SCM(SCH_1):PAGE52_I114@PURE_QUANTA.74LVC1G08GW(CHIPS)':
 'A': CDS_PINID='A';
NODE_NAME     C305 1
 '@SCM_LIB.SCM(SCH_1):PAGE52_I125@PURE_QUANTA.Q_CAP(CHIPS)':
 'A': CDS_PINID='A';
NODE_NAME     R529 2
 '@SCM_LIB.SCM(SCH_1):PAGE52_I127@PURE_QUANTA.Q_RES(CHIPS)':
 'B': CDS_PINID='B';
NET_NAME
'PWRGD_P1V8_AUX_R3'
 '@SCM_LIB.SCM(SCH_1):PWRGD_P1V8_AUX_R3':
 C_SIGNAL='@scm_lib.scm(sch_1):pwrgd_p1v8_aux_r3';
NODE_NAME     R869 1
 '@SCM_LIB.SCM(SCH_1):PAGE52_I139@PURE_QUANTA.Q_RES(CHIPS)':
 'A': CDS_PINID='A';
NODE_NAME     R874 1
 '@SCM_LIB.SCM(SCH_1):PAGE54_I139@PURE_QUANTA.Q_RES(CHIPS)':
 'A': CDS_PINID='A';
NET_NAME
'PWRGD_P2V5_AUX'
 '@SCM_LIB.SCM(SCH_1):PWRGD_P2V5_AUX':
 C_SIGNAL='@scm_lib.scm(sch_1):pwrgd_p2v5_aux';
NODE_NAME     R320 2
 '@SCM_LIB.SCM(SCH_1):PAGE35_I95@PURE_QUANTA.Q_RES(CHIPS)':
 'B': CDS_PINID='B';
NODE_NAME     R35 1
 '@SCM_LIB.SCM(SCH_1):PAGE53_I58@PURE_QUANTA.Q_RES(CHIPS)':
 'A': CDS_PINID='A';
NODE_NAME     R873 2
 '@SCM_LIB.SCM(SCH_1):PAGE53_I72@PURE_QUANTA.Q_RES(CHIPS)':
 'B': CDS_PINID='B';
NET_NAME
'PWRGD_P2V5_AUX_R'
 '@SCM_LIB.SCM(SCH_1):PWRGD_P2V5_AUX_R':
 C_SIGNAL='@scm_lib.scm(sch_1):pwrgd_p2v5_aux_r';
NODE_NAME     R35 2
 '@SCM_LIB.SCM(SCH_1):PAGE53_I58@PURE_QUANTA.Q_RES(CHIPS)':
 'B': CDS_PINID='B';
NODE_NAME     U39 5
 '@SCM_LIB.SCM(SCH_1):PAGE53_I60@PURE_QUANTA.RT9059GQW(CHIPS)':
 'PGOOD': CDS_PINID='PGOOD';
NODE_NAME     C153 1
 '@SCM_LIB.SCM(SCH_1):PAGE53_I64@PURE_QUANTA.Q_CAP(CHIPS)':
 'A': CDS_PINID='A';
NODE_NAME     R403 2
 '@SCM_LIB.SCM(SCH_1):PAGE53_I68@PURE_QUANTA.Q_RES(CHIPS)':
 'B': CDS_PINID='B';
NET_NAME
'PWRGD_P2V5_AUX_R1'
 '@SCM_LIB.SCM(SCH_1):PWRGD_P2V5_AUX_R1':
 C_SIGNAL='@scm_lib.scm(sch_1):pwrgd_p2v5_aux_r1';
NODE_NAME     U25 N14
 '@SCM_LIB.SCM(SCH_1):PAGE35_I1@PURE_QUANTA.LCMXO3LF2100C5BG256C(CHIPS)':
 'PR14B': CDS_PINID='PR14B';
NODE_NAME     R320 1
 '@SCM_LIB.SCM(SCH_1):PAGE35_I95@PURE_QUANTA.Q_RES(CHIPS)':
 'A': CDS_PINID='A';
NET_NAME
'PWRGD_P2V5_AUX_R3'
 '@SCM_LIB.SCM(SCH_1):PWRGD_P2V5_AUX_R3':
 C_SIGNAL='@scm_lib.scm(sch_1):pwrgd_p2v5_aux_r3';
NODE_NAME     R875 1
 '@SCM_LIB.SCM(SCH_1):PAGE54_I137@PURE_QUANTA.Q_RES(CHIPS)':
 'A': CDS_PINID='A';
NODE_NAME     R873 1
 '@SCM_LIB.SCM(SCH_1):PAGE53_I72@PURE_QUANTA.Q_RES(CHIPS)':
 'A': CDS_PINID='A';
NET_NAME
'PWRGD_P3V3_AUX'
 '@SCM_LIB.SCM(SCH_1):PWRGD_P3V3_AUX':
 C_SIGNAL='@scm_lib.scm(sch_1):pwrgd_p3v3_aux';
NODE_NAME     R318 2
 '@SCM_LIB.SCM(SCH_1):PAGE35_I98@PURE_QUANTA.Q_RES(CHIPS)':
 'B': CDS_PINID='B';
NODE_NAME     R293 2
 '@SCM_LIB.SCM(SCH_1):PAGE52_I95@PURE_QUANTA.Q_RES(CHIPS)':
 'B': CDS_PINID='B';
NODE_NAME     R382 1
 '@SCM_LIB.SCM(SCH_1):PAGE53_I65@PURE_QUANTA.Q_RES(CHIPS)':
 'A': CDS_PINID='A';
NET_NAME
'PWRGD_P3V3_AUX_R'
 '@SCM_LIB.SCM(SCH_1):PWRGD_P3V3_AUX_R':
 C_SIGNAL='@scm_lib.scm(sch_1):pwrgd_p3v3_aux_r';
NODE_NAME     PR242 2
 '@SCM_LIB.SCM(SCH_1):PAGE52_I13@PURE_QUANTA.Q_RES(CHIPS)':
 'B': CDS_PINID='B';
NODE_NAME     PU1 9
 '@SCM_LIB.SCM(SCH_1):PAGE52_I82@PURE_QUANTA.MPQ8626GDZ(CHIPS)':
 'PGOOD': CDS_PINID='PGOOD';
NODE_NAME     C151 1
 '@SCM_LIB.SCM(SCH_1):PAGE52_I93@PURE_QUANTA.Q_CAP(CHIPS)':
 'A': CDS_PINID='A';
NODE_NAME     R293 1
 '@SCM_LIB.SCM(SCH_1):PAGE52_I95@PURE_QUANTA.Q_RES(CHIPS)':
 'A': CDS_PINID='A';
NET_NAME
'PWRGD_P3V3_AUX_R1'
 '@SCM_LIB.SCM(SCH_1):PWRGD_P3V3_AUX_R1':
 C_SIGNAL='@scm_lib.scm(sch_1):pwrgd_p3v3_aux_r1';
NODE_NAME     U25 N16
 '@SCM_LIB.SCM(SCH_1):PAGE35_I1@PURE_QUANTA.LCMXO3LF2100C5BG256C(CHIPS)':
 'PR14A': CDS_PINID='PR14A';
NODE_NAME     R318 1
 '@SCM_LIB.SCM(SCH_1):PAGE35_I98@PURE_QUANTA.Q_RES(CHIPS)':
 'A': CDS_PINID='A';
NET_NAME
'PWRGD_P3V3_AUX_R2'
 '@SCM_LIB.SCM(SCH_1):PWRGD_P3V3_AUX_R2':
 C_SIGNAL='@scm_lib.scm(sch_1):pwrgd_p3v3_aux_r2';
NODE_NAME     U39 6
 '@SCM_LIB.SCM(SCH_1):PAGE53_I60@PURE_QUANTA.RT9059GQW(CHIPS)':
 'EN': CDS_PINID='EN';
NODE_NAME     R382 2
 '@SCM_LIB.SCM(SCH_1):PAGE53_I65@PURE_QUANTA.Q_RES(CHIPS)':
 'B': CDS_PINID='B';
NET_NAME
'PWRGD_P3V3_RGM'
 '@SCM_LIB.SCM(SCH_1):PWRGD_P3V3_RGM':
 C_SIGNAL='@scm_lib.scm(sch_1):pwrgd_p3v3_rgm';
NODE_NAME     R322 2
 '@SCM_LIB.SCM(SCH_1):PAGE36_I35@PURE_QUANTA.Q_RES(CHIPS)':
 'B': CDS_PINID='B';
NODE_NAME     R99 2
 '@SCM_LIB.SCM(SCH_1):PAGE52_I96@PURE_QUANTA.Q_RES(CHIPS)':
 'B': CDS_PINID='B';
NODE_NAME     U52 2
 '@SCM_LIB.SCM(SCH_1):PAGE55_I63@PURE_QUANTA.74LVC1G08GW(CHIPS)':
 'A': CDS_PINID='A';
NODE_NAME     R530 1
 '@SCM_LIB.SCM(SCH_1):PAGE54_I132@PURE_QUANTA.Q_RES(CHIPS)':
 'A': CDS_PINID='A';
NET_NAME
'PWRGD_P3V3_RGM_R'
 '@SCM_LIB.SCM(SCH_1):PWRGD_P3V3_RGM_R':
 C_SIGNAL='@scm_lib.scm(sch_1):pwrgd_p3v3_rgm_r';
NODE_NAME     C252 1
 '@SCM_LIB.SCM(SCH_1):PAGE52_I73@PURE_QUANTA.Q_CAP(CHIPS)':
 'A': CDS_PINID='A';
NODE_NAME     R99 1
 '@SCM_LIB.SCM(SCH_1):PAGE52_I96@PURE_QUANTA.Q_RES(CHIPS)':
 'A': CDS_PINID='A';
NODE_NAME     R872 1
 '@SCM_LIB.SCM(SCH_1):PAGE52_I141@PURE_QUANTA.Q_RES(CHIPS)':
 'A': CDS_PINID='A';
NODE_NAME     R709 2
 '@SCM_LIB.SCM(SCH_1):PAGE52_I145@PURE_QUANTA.Q_RES(CHIPS)':
 'B': CDS_PINID='B';
NET_NAME
'PWRGD_P3V3_RGM_R1'
 '@SCM_LIB.SCM(SCH_1):PWRGD_P3V3_RGM_R1':
 C_SIGNAL='@scm_lib.scm(sch_1):pwrgd_p3v3_rgm_r1';
NODE_NAME     U25 N9
 '@SCM_LIB.SCM(SCH_1):PAGE36_I1@PURE_QUANTA.LCMXO3LF2100C5BG256C(CHIPS)':
 'PB16D': CDS_PINID='PB16D';
NODE_NAME     R322 1
 '@SCM_LIB.SCM(SCH_1):PAGE36_I35@PURE_QUANTA.Q_RES(CHIPS)':
 'A': CDS_PINID='A';
NET_NAME
'PWRGD_P3V3_RGM_R2'
 '@SCM_LIB.SCM(SCH_1):PWRGD_P3V3_RGM_R2':
 C_SIGNAL='@scm_lib.scm(sch_1):pwrgd_p3v3_rgm_r2';
NODE_NAME     U49 2
 '@SCM_LIB.SCM(SCH_1):PAGE54_I116@PURE_QUANTA.MC74VHC1G32DTT1G(CHIPS)':
 'IN_A': CDS_PINID='IN_A';
NODE_NAME     C310 1
 '@SCM_LIB.SCM(SCH_1):PAGE54_I130@PURE_QUANTA.Q_CAP(CHIPS)':
 'A': CDS_PINID='A';
NODE_NAME     R530 2
 '@SCM_LIB.SCM(SCH_1):PAGE54_I132@PURE_QUANTA.Q_RES(CHIPS)':
 'B': CDS_PINID='B';
NET_NAME
'PWRGD_P3V3_RGM_R3'
 '@SCM_LIB.SCM(SCH_1):PWRGD_P3V3_RGM_R3':
 C_SIGNAL='@scm_lib.scm(sch_1):pwrgd_p3v3_rgm_r3';
NODE_NAME     R872 2
 '@SCM_LIB.SCM(SCH_1):PAGE52_I141@PURE_QUANTA.Q_RES(CHIPS)':
 'B': CDS_PINID='B';
NODE_NAME     R876 1
 '@SCM_LIB.SCM(SCH_1):PAGE55_I68@PURE_QUANTA.Q_RES(CHIPS)':
 'A': CDS_PINID='A';
NET_NAME
'PWRGD_P5V_AUX'
 '@SCM_LIB.SCM(SCH_1):PWRGD_P5V_AUX':
 C_SIGNAL='@scm_lib.scm(sch_1):pwrgd_p5v_aux';
NODE_NAME     R292 2
 '@SCM_LIB.SCM(SCH_1):PAGE51_I51@PURE_QUANTA.Q_RES(CHIPS)':
 'B': CDS_PINID='B';
NODE_NAME     U49 1
 '@SCM_LIB.SCM(SCH_1):PAGE54_I116@PURE_QUANTA.MC74VHC1G32DTT1G(CHIPS)':
 'IN_B': CDS_PINID='IN_B';
NODE_NAME     U53 1
 '@SCM_LIB.SCM(SCH_1):PAGE56_I66@PURE_QUANTA.74LVC1G08GW(CHIPS)':
 'B': CDS_PINID='B';
NODE_NAME     U52 1
 '@SCM_LIB.SCM(SCH_1):PAGE55_I63@PURE_QUANTA.74LVC1G08GW(CHIPS)':
 'B': CDS_PINID='B';
NODE_NAME     U42 1
 '@SCM_LIB.SCM(SCH_1):PAGE52_I104@PURE_QUANTA.MC74VHC1G32DTT1G(CHIPS)':
 'IN_B': CDS_PINID='IN_B';
NODE_NAME     U18 1
 '@SCM_LIB.SCM(SCH_1):PAGE52_I114@PURE_QUANTA.74LVC1G08GW(CHIPS)':
 'B': CDS_PINID='B';
NODE_NAME     D23 1
 '@SCM_LIB.SCM(SCH_1):PAGE35_I150@PURE_QUANTA.Q_DIODE(CHIPS)':
 '1': CDS_PINID='\1\';
NET_NAME
'PWRGD_P5V_AUX_R'
 '@SCM_LIB.SCM(SCH_1):PWRGD_P5V_AUX_R':
 C_SIGNAL='@scm_lib.scm(sch_1):pwrgd_p5v_aux_r';
NODE_NAME     PR241 2
 '@SCM_LIB.SCM(SCH_1):PAGE51_I21@PURE_QUANTA.Q_RES(CHIPS)':
 'B': CDS_PINID='B';
NODE_NAME     PU38 9
 '@SCM_LIB.SCM(SCH_1):PAGE51_I42@PURE_QUANTA.MPQ8633AGLEC807Z(CHIPS)':
 'PGOOD': CDS_PINID='PGOOD';
NODE_NAME     PR245 1
 '@SCM_LIB.SCM(SCH_1):PAGE51_I43@PURE_QUANTA.Q_RES(CHIPS)':
 'A': CDS_PINID='A';
NODE_NAME     C150 1
 '@SCM_LIB.SCM(SCH_1):PAGE51_I49@PURE_QUANTA.Q_CAP(CHIPS)':
 'A': CDS_PINID='A';
NODE_NAME     R292 1
 '@SCM_LIB.SCM(SCH_1):PAGE51_I51@PURE_QUANTA.Q_RES(CHIPS)':
 'A': CDS_PINID='A';
NODE_NAME     R868 1
 '@SCM_LIB.SCM(SCH_1):PAGE51_I54@PURE_QUANTA.Q_RES(CHIPS)':
 'A': CDS_PINID='A';
NET_NAME
'PWRGD_P5V_AUX_R1'
 '@SCM_LIB.SCM(SCH_1):PWRGD_P5V_AUX_R1':
 C_SIGNAL='@scm_lib.scm(sch_1):pwrgd_p5v_aux_r1';
NODE_NAME     U25 M15
 '@SCM_LIB.SCM(SCH_1):PAGE35_I1@PURE_QUANTA.LCMXO3LF2100C5BG256C(CHIPS)':
 'PR13B': CDS_PINID='PR13B';
NODE_NAME     D23 2
 '@SCM_LIB.SCM(SCH_1):PAGE35_I150@PURE_QUANTA.Q_DIODE(CHIPS)':
 '2': CDS_PINID='\2\';
NODE_NAME     R886 2
 '@SCM_LIB.SCM(SCH_1):PAGE35_I151@PURE_QUANTA.Q_RES(CHIPS)':
 'B': CDS_PINID='B';
NET_NAME
'PWRGD_PCH_PWROK'
 '@SCM_LIB.SCM(SCH_1):PWRGD_PCH_PWROK':
 C_SIGNAL='@scm_lib.scm(sch_1):pwrgd_pch_pwrok';
NODE_NAME     U5 T23
 '@SCM_LIB.SCM(SCH_1):PAGE15_I350@PURE_QUANTA.AST2600A3GP(CHIPS)':
 'GPIOR5||TACH13': CDS_PINID='\gpior5||tach13\';
NODE_NAME     U25 E7
 '@SCM_LIB.SCM(SCH_1):PAGE34_I1@PURE_QUANTA.LCMXO3LF2100C5BG256C(CHIPS)':
 'PT12B': CDS_PINID='PT12B';
NET_NAME
'PWRGD_PSU_AC_PWROK'
 '@SCM_LIB.SCM(SCH_1):PWRGD_PSU_AC_PWROK':
 C_SIGNAL='@scm_lib.scm(sch_1):pwrgd_psu_ac_pwrok';
NODE_NAME     R243 1
 '@SCM_LIB.SCM(SCH_1):PAGE10_I293@PURE_QUANTA.Q_RES(CHIPS)':
 'A': CDS_PINID='A';
NODE_NAME     R66 2
 '@SCM_LIB.SCM(SCH_1):PAGE11_I181@PURE_QUANTA.Q_RES(CHIPS)':
 'B': CDS_PINID='B';
NODE_NAME     R836 1
 '@SCM_LIB.SCM(SCH_1):PAGE13_I225@PURE_QUANTA.Q_RES(CHIPS)':
 'A': CDS_PINID='A';
NODE_NAME     R711 1
 '@SCM_LIB.SCM(SCH_1):PAGE22_I49@PURE_QUANTA.Q_RES(CHIPS)':
 'A': CDS_PINID='A';
NODE_NAME     R719 1
 '@SCM_LIB.SCM(SCH_1):PAGE28_I128@PURE_QUANTA.Q_RES(CHIPS)':
 'A': CDS_PINID='A';
NODE_NAME     R837 1
 '@SCM_LIB.SCM(SCH_1):PAGE34_I158@PURE_QUANTA.Q_RES(CHIPS)':
 'A': CDS_PINID='A';
NET_NAME
'PWRGD_PSU_AC_PWROK_BMC'
 '@SCM_LIB.SCM(SCH_1):PWRGD_PSU_AC_PWROK_BMC':
 C_SIGNAL='@scm_lib.scm(sch_1):pwrgd_psu_ac_pwrok_bmc';
NODE_NAME     R836 2
 '@SCM_LIB.SCM(SCH_1):PAGE13_I225@PURE_QUANTA.Q_RES(CHIPS)':
 'B': CDS_PINID='B';
NODE_NAME     U5 A12
 '@SCM_LIB.SCM(SCH_1):PAGE13_I363@PURE_QUANTA.AST2600A3GP(CHIPS)':
 'GPIOM2||NDSR1': CDS_PINID='\gpiom2||ndsr1\';
NET_NAME
'PWRGD_PSU_AC_PWROK_PLD'
 '@SCM_LIB.SCM(SCH_1):PWRGD_PSU_AC_PWROK_PLD':
 C_SIGNAL='@scm_lib.scm(sch_1):pwrgd_psu_ac_pwrok_pld';
NODE_NAME     U25 C5
 '@SCM_LIB.SCM(SCH_1):PAGE34_I1@PURE_QUANTA.LCMXO3LF2100C5BG256C(CHIPS)':
 'PT10B': CDS_PINID='PT10B';
NODE_NAME     R837 2
 '@SCM_LIB.SCM(SCH_1):PAGE34_I158@PURE_QUANTA.Q_RES(CHIPS)':
 'B': CDS_PINID='B';
NET_NAME
'PWRGD_PSU_AC_PWROK_R'
 '@SCM_LIB.SCM(SCH_1):PWRGD_PSU_AC_PWROK_R':
 C_SIGNAL='@scm_lib.scm(sch_1):pwrgd_psu_ac_pwrok_r';
NODE_NAME     R243 2
 '@SCM_LIB.SCM(SCH_1):PAGE10_I293@PURE_QUANTA.Q_RES(CHIPS)':
 'B': CDS_PINID='B';
NODE_NAME     GF1 A44
 '@SCM_LIB.SCM(SCH_1):PAGE10_I553@PURE_QUANTA.FCONN168_ME1016810202011_SCM(CHIPS)':
 'HPM_STBY_RDY': CDS_PINID='HPM_STBY_RDY';
NET_NAME
'PWRGD_SYS_PWROK'
 '@SCM_LIB.SCM(SCH_1):PWRGD_SYS_PWROK':
 C_SIGNAL='@scm_lib.scm(sch_1):pwrgd_sys_pwrok';
NODE_NAME     GF1 A48
 '@SCM_LIB.SCM(SCH_1):PAGE10_I553@PURE_QUANTA.FCONN168_ME1016810202011_SCM(CHIPS)':
 'SYS_PWROK': CDS_PINID='SYS_PWROK';
NODE_NAME     R40 2
 '@SCM_LIB.SCM(SCH_1):PAGE11_I171@PURE_QUANTA.Q_RES(CHIPS)':
 'B': CDS_PINID='B';
NODE_NAME     R840 1
 '@SCM_LIB.SCM(SCH_1):PAGE13_I295@PURE_QUANTA.Q_RES(CHIPS)':
 'A': CDS_PINID='A';
NODE_NAME     R701 1
 '@SCM_LIB.SCM(SCH_1):PAGE28_I125@PURE_QUANTA.Q_RES(CHIPS)':
 'A': CDS_PINID='A';
NODE_NAME     R841 2
 '@SCM_LIB.SCM(SCH_1):PAGE35_I142@PURE_QUANTA.Q_RES(CHIPS)':
 'B': CDS_PINID='B';
NET_NAME
'PWRGD_SYS_PWROK_BMC'
 '@SCM_LIB.SCM(SCH_1):PWRGD_SYS_PWROK_BMC':
 C_SIGNAL='@scm_lib.scm(sch_1):pwrgd_sys_pwrok_bmc';
NODE_NAME     R840 2
 '@SCM_LIB.SCM(SCH_1):PAGE13_I295@PURE_QUANTA.Q_RES(CHIPS)':
 'B': CDS_PINID='B';
NODE_NAME     U5 B12
 '@SCM_LIB.SCM(SCH_1):PAGE13_I363@PURE_QUANTA.AST2600A3GP(CHIPS)':
 'GPIOM4||NDTR1': CDS_PINID='\gpiom4||ndtr1\';
NET_NAME
'PWRGD_SYS_PWROK_PLD'
 '@SCM_LIB.SCM(SCH_1):PWRGD_SYS_PWROK_PLD':
 C_SIGNAL='@scm_lib.scm(sch_1):pwrgd_sys_pwrok_pld';
NODE_NAME     U25 K15
 '@SCM_LIB.SCM(SCH_1):PAGE35_I1@PURE_QUANTA.LCMXO3LF2100C5BG256C(CHIPS)':
 'PR10B': CDS_PINID='PR10B';
NODE_NAME     R841 1
 '@SCM_LIB.SCM(SCH_1):PAGE35_I142@PURE_QUANTA.Q_RES(CHIPS)':
 'A': CDS_PINID='A';
NET_NAME
'PWRGD_SYS_PWROK_R1'
 '@SCM_LIB.SCM(SCH_1):PWRGD_SYS_PWROK_R1':
 C_SIGNAL='@scm_lib.scm(sch_1):pwrgd_sys_pwrok_r1';
NODE_NAME     R701 2
 '@SCM_LIB.SCM(SCH_1):PAGE28_I125@PURE_QUANTA.Q_RES(CHIPS)':
 'B': CDS_PINID='B';
NODE_NAME     U40 15
 '@SCM_LIB.SCM(SCH_1):PAGE28_I141@PURE_QUANTA.PCA9555PW(CHIPS)':
 'P12': CDS_PINID='P12';
NET_NAME
'PWR_BTN_BMC_N'
 '@SCM_LIB.SCM(SCH_1):PWR_BTN_BMC_N':
 C_SIGNAL='@scm_lib.scm(sch_1):pwr_btn_bmc_n';
NODE_NAME     R81 2
 '@SCM_LIB.SCM(SCH_1):PAGE11_I245@PURE_QUANTA.Q_RES(CHIPS)':
 'B': CDS_PINID='B';
NODE_NAME     U31 4
 '@SCM_LIB.SCM(SCH_1):PAGE50_I151@PURE_QUANTA.74LVC1G07GW(CHIPS)':
 'Y': CDS_PINID='Y';
NODE_NAME     U15 2
 '@SCM_LIB.SCM(SCH_1):PAGE15_I393@PURE_QUANTA.74LVC1G08GW(CHIPS)':
 'A': CDS_PINID='A';
NODE_NAME     R225 2
 '@SCM_LIB.SCM(SCH_1):PAGE15_I405@PURE_QUANTA.Q_RES(CHIPS)':
 'B': CDS_PINID='B';
NET_NAME
'PWR_LED'
 '@SCM_LIB.SCM(SCH_1):PWR_LED':
 C_SIGNAL='@scm_lib.scm(sch_1):pwr_led';
NODE_NAME     R316 2
 '@SCM_LIB.SCM(SCH_1):PAGE15_I318@PURE_QUANTA.Q_RES(CHIPS)':
 'B': CDS_PINID='B';
NODE_NAME     R317 2
 '@SCM_LIB.SCM(SCH_1):PAGE35_I99@PURE_QUANTA.Q_RES(CHIPS)':
 'B': CDS_PINID='B';
NODE_NAME     R839 1
 '@SCM_LIB.SCM(SCH_1):PAGE49_I22@PURE_QUANTA.Q_RES(CHIPS)':
 'A': CDS_PINID='A';
NODE_NAME     Q12 2
 '@SCM_LIB.SCM(SCH_1):PAGE49_I24@PURE_QUANTA.MOSFET_DUAL_6P(CHIPS)':
 'G1': CDS_PINID='G1';
NET_NAME
'PWR_LED_BUF_N'
 '@SCM_LIB.SCM(SCH_1):PWR_LED_BUF_N':
 C_SIGNAL='@scm_lib.scm(sch_1):pwr_led_buf_n';
NODE_NAME     Q12 6
 '@SCM_LIB.SCM(SCH_1):PAGE49_I24@PURE_QUANTA.MOSFET_DUAL_6P(CHIPS)':
 'D1': CDS_PINID='D1';
NODE_NAME     R812 1
 '@SCM_LIB.SCM(SCH_1):PAGE49_I34@PURE_QUANTA.Q_RES(CHIPS)':
 'A': CDS_PINID='A';
NET_NAME
'PWR_LED_BUF_N_R'
 '@SCM_LIB.SCM(SCH_1):PWR_LED_BUF_N_R':
 C_SIGNAL='@scm_lib.scm(sch_1):pwr_led_buf_n_r';
NODE_NAME     R812 2
 '@SCM_LIB.SCM(SCH_1):PAGE49_I34@PURE_QUANTA.Q_RES(CHIPS)':
 'B': CDS_PINID='B';
NODE_NAME     R814 2
 '@SCM_LIB.SCM(SCH_1):PAGE49_I36@PURE_QUANTA.Q_RES(CHIPS)':
 'B': CDS_PINID='B';
NODE_NAME     C326 1
 '@SCM_LIB.SCM(SCH_1):PAGE49_I38@PURE_QUANTA.Q_CAP(CHIPS)':
 'A': CDS_PINID='A';
NODE_NAME     D14 C
 '@SCM_LIB.SCM(SCH_1):PAGE49_I94@PURE_QUANTA.Q_LED(CHIPS)':
 'C': CDS_PINID='C';
NET_NAME
'PWR_LED_CPLD'
 '@SCM_LIB.SCM(SCH_1):PWR_LED_CPLD':
 C_SIGNAL='@scm_lib.scm(sch_1):pwr_led_cpld';
NODE_NAME     U25 M14
 '@SCM_LIB.SCM(SCH_1):PAGE35_I1@PURE_QUANTA.LCMXO3LF2100C5BG256C(CHIPS)':
 'PR13A': CDS_PINID='PR13A';
NODE_NAME     R317 1
 '@SCM_LIB.SCM(SCH_1):PAGE35_I99@PURE_QUANTA.Q_RES(CHIPS)':
 'A': CDS_PINID='A';
NET_NAME
'PWR_LED_P5V_AUX'
 '@SCM_LIB.SCM(SCH_1):PWR_LED_P5V_AUX':
 C_SIGNAL='@scm_lib.scm(sch_1):pwr_led_p5v_aux';
NODE_NAME     C321 1
 '@SCM_LIB.SCM(SCH_1):PAGE49_I43@PURE_QUANTA.Q_CAP(CHIPS)':
 'A': CDS_PINID='A';
NODE_NAME     R568 1
 '@SCM_LIB.SCM(SCH_1):PAGE49_I59@PURE_QUANTA.Q_RES(CHIPS)':
 'A': CDS_PINID='A';
NODE_NAME     D14 A
 '@SCM_LIB.SCM(SCH_1):PAGE49_I94@PURE_QUANTA.Q_LED(CHIPS)':
 'A': CDS_PINID='A';
NET_NAME
'Q7_D'
 '@SCM_LIB.SCM(SCH_1):Q7_D':
 C_SIGNAL='@scm_lib.scm(sch_1):q7_d';
NODE_NAME     R42 2
 '@SCM_LIB.SCM(SCH_1):PAGE27_I222@PURE_QUANTA.Q_RES(CHIPS)':
 'B': CDS_PINID='B';
NODE_NAME     Q7 D
 '@SCM_LIB.SCM(SCH_1):PAGE27_I243@PURE_QUANTA.2N7002A7(CHIPS)':
 'D': CDS_PINID='D';
NET_NAME
'QSPI_2_PLD_CLK'
 '@SCM_LIB.SCM(SCH_1):QSPI_2_PLD_CLK':
 C_SIGNAL='@scm_lib.scm(sch_1):qspi_2_pld_clk';
NODE_NAME     GF1 B43
 '@SCM_LIB.SCM(SCH_1):PAGE10_I553@PURE_QUANTA.FCONN168_ME1016810202011_SCM(CHIPS)':
 'QSPI1_CLK': CDS_PINID='QSPI1_CLK';
NODE_NAME     R678 2
 '@SCM_LIB.SCM(SCH_1):PAGE13_I239@PURE_QUANTA.Q_RES(CHIPS)':
 'B': CDS_PINID='B';
NET_NAME
'QSPI_2_PLD_IO0'
 '@SCM_LIB.SCM(SCH_1):QSPI_2_PLD_IO0':
 C_SIGNAL='@scm_lib.scm(sch_1):qspi_2_pld_io0';
NODE_NAME     GF1 B45
 '@SCM_LIB.SCM(SCH_1):PAGE10_I553@PURE_QUANTA.FCONN168_ME1016810202011_SCM(CHIPS)':
 'QSPI1_D0': CDS_PINID='QSPI1_D0';
NODE_NAME     R679 2
 '@SCM_LIB.SCM(SCH_1):PAGE13_I247@PURE_QUANTA.Q_RES(CHIPS)':
 'B': CDS_PINID='B';
NET_NAME
'QSPI_2_PLD_IO1'
 '@SCM_LIB.SCM(SCH_1):QSPI_2_PLD_IO1':
 C_SIGNAL='@scm_lib.scm(sch_1):qspi_2_pld_io1';
NODE_NAME     GF1 B46
 '@SCM_LIB.SCM(SCH_1):PAGE10_I553@PURE_QUANTA.FCONN168_ME1016810202011_SCM(CHIPS)':
 'QSPI1_D1': CDS_PINID='QSPI1_D1';
NODE_NAME     R680 2
 '@SCM_LIB.SCM(SCH_1):PAGE13_I248@PURE_QUANTA.Q_RES(CHIPS)':
 'B': CDS_PINID='B';
NET_NAME
'QSPI_2_PLD_IO2'
 '@SCM_LIB.SCM(SCH_1):QSPI_2_PLD_IO2':
 C_SIGNAL='@scm_lib.scm(sch_1):qspi_2_pld_io2';
NODE_NAME     GF1 B47
 '@SCM_LIB.SCM(SCH_1):PAGE10_I553@PURE_QUANTA.FCONN168_ME1016810202011_SCM(CHIPS)':
 'QSPI1_D2': CDS_PINID='QSPI1_D2';
NODE_NAME     R681 2
 '@SCM_LIB.SCM(SCH_1):PAGE13_I245@PURE_QUANTA.Q_RES(CHIPS)':
 'B': CDS_PINID='B';
NET_NAME
'QSPI_2_PLD_IO3'
 '@SCM_LIB.SCM(SCH_1):QSPI_2_PLD_IO3':
 C_SIGNAL='@scm_lib.scm(sch_1):qspi_2_pld_io3';
NODE_NAME     GF1 B48
 '@SCM_LIB.SCM(SCH_1):PAGE10_I553@PURE_QUANTA.FCONN168_ME1016810202011_SCM(CHIPS)':
 'QSPI1_D3': CDS_PINID='QSPI1_D3';
NODE_NAME     R682 2
 '@SCM_LIB.SCM(SCH_1):PAGE13_I246@PURE_QUANTA.Q_RES(CHIPS)':
 'B': CDS_PINID='B';
NET_NAME
'RD_N'
 '@SCM_LIB.SCM(SCH_1):RD_N':
 C_SIGNAL='@scm_lib.scm(sch_1):rd_n';
NODE_NAME     U54 6
 '@SCM_LIB.SCM(SCH_1):PAGE25_I138@PURE_QUANTA.74LVC1G74DP(CHIPS)':
 'RD_N': CDS_PINID='RD_N';
NODE_NAME     R548 2
 '@SCM_LIB.SCM(SCH_1):PAGE25_I172@PURE_QUANTA.Q_RES(CHIPS)':
 'B': CDS_PINID='B';
NET_NAME
'REAR_AC_PWR_BMC_BTN_N'
 '@SCM_LIB.SCM(SCH_1):REAR_AC_PWR_BMC_BTN_N':
 C_SIGNAL='@scm_lib.scm(sch_1):rear_ac_pwr_bmc_btn_n';
NODE_NAME     U57 2
 '@SCM_LIB.SCM(SCH_1):PAGE50_I278@PURE_QUANTA.74LVC1G07GW(CHIPS)':
 'A': CDS_PINID='A';
NODE_NAME     R883 2
 '@SCM_LIB.SCM(SCH_1):PAGE50_I284@PURE_QUANTA.Q_RES(CHIPS)':
 'B': CDS_PINID='B';
NODE_NAME     C335 1
 '@SCM_LIB.SCM(SCH_1):PAGE50_I285@PURE_QUANTA.Q_CAP(CHIPS)':
 'A': CDS_PINID='A';
NODE_NAME     R882 2
 '@SCM_LIB.SCM(SCH_1):PAGE50_I286@PURE_QUANTA.Q_RES(CHIPS)':
 'B': CDS_PINID='B';
NET_NAME
'REAR_AC_PWR_BTN'
 '@SCM_LIB.SCM(SCH_1):REAR_AC_PWR_BTN':
 C_SIGNAL='@scm_lib.scm(sch_1):rear_ac_pwr_btn';
NODE_NAME     R470 1
 '@SCM_LIB.SCM(SCH_1):PAGE50_I241@PURE_QUANTA.Q_RES(CHIPS)':
 'A': CDS_PINID='A';
NODE_NAME     R471 1
 '@SCM_LIB.SCM(SCH_1):PAGE50_I242@PURE_QUANTA.Q_RES(CHIPS)':
 'A': CDS_PINID='A';
NODE_NAME     D10 A
 '@SCM_LIB.SCM(SCH_1):PAGE50_I244@PURE_QUANTA.DIODE_BIDIRECTIONAL(CHIPS)':
 'A': CDS_PINID='A';
NODE_NAME     C181 1
 '@SCM_LIB.SCM(SCH_1):PAGE50_I246@PURE_QUANTA.Q_CAP(CHIPS)':
 'A': CDS_PINID='A';
NODE_NAME     R882 1
 '@SCM_LIB.SCM(SCH_1):PAGE50_I286@PURE_QUANTA.Q_RES(CHIPS)':
 'A': CDS_PINID='A';
NODE_NAME     SW8 2
 '@SCM_LIB.SCM(SCH_1):PAGE50_I293@PURE_QUANTA.SW_PUSHBUTTON4P_12_G34_H2(CHIPS)':
 '2': CDS_PINID='\2\';
NET_NAME
'REAR_AC_PWR_BTN_N'
 '@SCM_LIB.SCM(SCH_1):REAR_AC_PWR_BTN_N':
 C_SIGNAL='@scm_lib.scm(sch_1):rear_ac_pwr_btn_n';
NODE_NAME     U16 2
 '@SCM_LIB.SCM(SCH_1):PAGE50_I227@PURE_QUANTA.74LVC1G07GW(CHIPS)':
 'A': CDS_PINID='A';
NODE_NAME     R391 2
 '@SCM_LIB.SCM(SCH_1):PAGE50_I235@PURE_QUANTA.Q_RES(CHIPS)':
 'B': CDS_PINID='B';
NODE_NAME     C28 1
 '@SCM_LIB.SCM(SCH_1):PAGE50_I236@PURE_QUANTA.Q_CAP(CHIPS)':
 'A': CDS_PINID='A';
NODE_NAME     R470 2
 '@SCM_LIB.SCM(SCH_1):PAGE50_I241@PURE_QUANTA.Q_RES(CHIPS)':
 'B': CDS_PINID='B';
NET_NAME
'REAR_ID_RST_BTN_N'
 '@SCM_LIB.SCM(SCH_1):REAR_ID_RST_BTN_N':
 C_SIGNAL='@scm_lib.scm(sch_1):rear_id_rst_btn_n';
NODE_NAME     U32 2
 '@SCM_LIB.SCM(SCH_1):PAGE50_I49@PURE_QUANTA.74LVC1G17GW(CHIPS)':
 'A': CDS_PINID='A';
NODE_NAME     C199 1
 '@SCM_LIB.SCM(SCH_1):PAGE50_I55@PURE_QUANTA.Q_CAP(CHIPS)':
 'A': CDS_PINID='A';
NODE_NAME     R504 2
 '@SCM_LIB.SCM(SCH_1):PAGE50_I82@PURE_QUANTA.Q_RES(CHIPS)':
 'B': CDS_PINID='B';
NODE_NAME     R733 1
 '@SCM_LIB.SCM(SCH_1):PAGE50_I154@PURE_QUANTA.Q_RES(CHIPS)':
 'A': CDS_PINID='A';
NODE_NAME     SW7 2
 '@SCM_LIB.SCM(SCH_1):PAGE50_I204@PURE_QUANTA.SW_PUSHBUTTON4P_12_G34_H2(CHIPS)':
 '2': CDS_PINID='\2\';
NET_NAME
'REAR_PWR_BTN_N'
 '@SCM_LIB.SCM(SCH_1):REAR_PWR_BTN_N':
 C_SIGNAL='@scm_lib.scm(sch_1):rear_pwr_btn_n';
NODE_NAME     C198 1
 '@SCM_LIB.SCM(SCH_1):PAGE50_I44@PURE_QUANTA.Q_CAP(CHIPS)':
 'A': CDS_PINID='A';
NODE_NAME     R768 2
 '@SCM_LIB.SCM(SCH_1):PAGE50_I89@PURE_QUANTA.Q_RES(CHIPS)':
 'B': CDS_PINID='B';
NODE_NAME     U31 2
 '@SCM_LIB.SCM(SCH_1):PAGE50_I151@PURE_QUANTA.74LVC1G07GW(CHIPS)':
 'A': CDS_PINID='A';
NODE_NAME     R734 1
 '@SCM_LIB.SCM(SCH_1):PAGE50_I152@PURE_QUANTA.Q_RES(CHIPS)':
 'A': CDS_PINID='A';
NODE_NAME     SW6 2
 '@SCM_LIB.SCM(SCH_1):PAGE50_I292@PURE_QUANTA.SW_PUSHBUTTON4P_12_G34_H2(CHIPS)':
 '2': CDS_PINID='\2\';
NET_NAME
'RMII_CSRDV'
 '@SCM_LIB.SCM(SCH_1):RMII_CSRDV':
 C_SIGNAL='@scm_lib.scm(sch_1):rmii_csrdv';
NODE_NAME     GF1 B19
 '@SCM_LIB.SCM(SCH_1):PAGE10_I553@PURE_QUANTA.FCONN168_ME1016810202011_SCM(CHIPS)':
 'NCSI_CRS_DV': CDS_PINID='NCSI_CRS_DV';
NODE_NAME     R161 2
 '@SCM_LIB.SCM(SCH_1):PAGE11_I218@PURE_QUANTA.Q_RES(CHIPS)':
 'B': CDS_PINID='B';
NODE_NAME     U5 B25
 '@SCM_LIB.SCM(SCH_1):PAGE13_I363@PURE_QUANTA.AST2600A3GP(CHIPS)':
 'RGMII4RXD2||RMII4CRSDV||NDTR4||GPIOE6': CDS_PINID='\rgmii4rxd2||rmii4crsdv||ndtr4||gpioe6\';
NET_NAME
'RMII_OCP_RCLKI'
 '@SCM_LIB.SCM(SCH_1):RMII_OCP_RCLKI':
 C_SIGNAL='@scm_lib.scm(sch_1):rmii_ocp_rclki';
NODE_NAME     GF1 B18
 '@SCM_LIB.SCM(SCH_1):PAGE10_I553@PURE_QUANTA.FCONN168_ME1016810202011_SCM(CHIPS)':
 'NCSI_CLK': CDS_PINID='NCSI_CLK';
NODE_NAME     U28 1
 '@SCM_LIB.SCM(SCH_1):PAGE13_I435@PURE_QUANTA.74LVC1G66GV(CHIPS)':
 'Y': CDS_PINID='Y';
NET_NAME
'RMII_OCP_RCLKI_ISO'
 '@SCM_LIB.SCM(SCH_1):RMII_OCP_RCLKI_ISO':
 C_SIGNAL='@scm_lib.scm(sch_1):rmii_ocp_rclki_iso';
NODE_NAME     U28 2
 '@SCM_LIB.SCM(SCH_1):PAGE13_I435@PURE_QUANTA.74LVC1G66GV(CHIPS)':
 'Z': CDS_PINID='Z';
NODE_NAME     R392 1
 '@SCM_LIB.SCM(SCH_1):PAGE13_I447@PURE_QUANTA.Q_RES(CHIPS)':
 'A': CDS_PINID='A';
NET_NAME
'RMII_OCP_RCLKI_R_ISO'
 '@SCM_LIB.SCM(SCH_1):RMII_OCP_RCLKI_R_ISO':
 C_SIGNAL='@scm_lib.scm(sch_1):rmii_ocp_rclki_r_iso';
NODE_NAME     U5 C25
 '@SCM_LIB.SCM(SCH_1):PAGE13_I363@PURE_QUANTA.AST2600A3GP(CHIPS)':
 'RGMII4RXCK||RMII4RCLKI||NCTS4||GPIOE2': CDS_PINID='\rgmii4rxck||rmii4rclki||ncts4||gpioe2\';
NODE_NAME     R392 2
 '@SCM_LIB.SCM(SCH_1):PAGE13_I447@PURE_QUANTA.Q_RES(CHIPS)':
 'B': CDS_PINID='B';
NET_NAME
'RMII_RXD0'
 '@SCM_LIB.SCM(SCH_1):RMII_RXD0':
 C_SIGNAL='@scm_lib.scm(sch_1):rmii_rxd0';
NODE_NAME     GF1 B24
 '@SCM_LIB.SCM(SCH_1):PAGE10_I553@PURE_QUANTA.FCONN168_ME1016810202011_SCM(CHIPS)':
 'NCSI_RXD0': CDS_PINID='NCSI_RXD0';
NODE_NAME     U5 C24
 '@SCM_LIB.SCM(SCH_1):PAGE13_I363@PURE_QUANTA.AST2600A3GP(CHIPS)':
 'RGMII4RXD0||RMII4RXD0||NDSR4||GPIOE4': CDS_PINID='\rgmii4rxd0||rmii4rxd0||ndsr4||gpioe4\';
NET_NAME
'RMII_RXD1'
 '@SCM_LIB.SCM(SCH_1):RMII_RXD1':
 C_SIGNAL='@scm_lib.scm(sch_1):rmii_rxd1';
NODE_NAME     GF1 B25
 '@SCM_LIB.SCM(SCH_1):PAGE10_I553@PURE_QUANTA.FCONN168_ME1016810202011_SCM(CHIPS)':
 'NCSI_RXD1': CDS_PINID='NCSI_RXD1';
NODE_NAME     U5 B26
 '@SCM_LIB.SCM(SCH_1):PAGE13_I363@PURE_QUANTA.AST2600A3GP(CHIPS)':
 'RGMII4RXD1||RMII4RXD1||NRI4||GPIOE5': CDS_PINID='\rgmii4rxd1||rmii4rxd1||nri4||gpioe5\';
NET_NAME
'RMII_RXER'
 '@SCM_LIB.SCM(SCH_1):RMII_RXER':
 C_SIGNAL='@scm_lib.scm(sch_1):rmii_rxer';
NODE_NAME     GF1 B23
 '@SCM_LIB.SCM(SCH_1):PAGE10_I553@PURE_QUANTA.FCONN168_ME1016810202011_SCM(CHIPS)':
 'NCSI_RXER': CDS_PINID='NCSI_RXER';
NODE_NAME     R101 2
 '@SCM_LIB.SCM(SCH_1):PAGE11_I214@PURE_QUANTA.Q_RES(CHIPS)':
 'B': CDS_PINID='B';
NODE_NAME     U5 B24
 '@SCM_LIB.SCM(SCH_1):PAGE13_I363@PURE_QUANTA.AST2600A3GP(CHIPS)':
 'RGMII4RXD3||RMII4RXER||NRTS4||GPIOE7': CDS_PINID='\rgmii4rxd3||rmii4rxer||nrts4||gpioe7\';
NET_NAME
'RMII_TXD0'
 '@SCM_LIB.SCM(SCH_1):RMII_TXD0':
 C_SIGNAL='@scm_lib.scm(sch_1):rmii_txd0';
NODE_NAME     GF1 B21
 '@SCM_LIB.SCM(SCH_1):PAGE10_I553@PURE_QUANTA.FCONN168_ME1016810202011_SCM(CHIPS)':
 'NCSI_TXD0': CDS_PINID='NCSI_TXD0';
NODE_NAME     R172 2
 '@SCM_LIB.SCM(SCH_1):PAGE13_I452@PURE_QUANTA.Q_RES(CHIPS)':
 'B': CDS_PINID='B';
NET_NAME
'RMII_TXD0_R'
 '@SCM_LIB.SCM(SCH_1):RMII_TXD0_R':
 C_SIGNAL='@scm_lib.scm(sch_1):rmii_txd0_r';
NODE_NAME     U5 E24
 '@SCM_LIB.SCM(SCH_1):PAGE13_I363@PURE_QUANTA.AST2600A3GP(CHIPS)':
 'RGMII4TXD0||RMII4TXD0||NDSR3||GPIOD6': CDS_PINID='\rgmii4txd0||rmii4txd0||ndsr3||gpiod6\';
NODE_NAME     R172 1
 '@SCM_LIB.SCM(SCH_1):PAGE13_I452@PURE_QUANTA.Q_RES(CHIPS)':
 'A': CDS_PINID='A';
NET_NAME
'RMII_TXD1'
 '@SCM_LIB.SCM(SCH_1):RMII_TXD1':
 C_SIGNAL='@scm_lib.scm(sch_1):rmii_txd1';
NODE_NAME     GF1 B22
 '@SCM_LIB.SCM(SCH_1):PAGE10_I553@PURE_QUANTA.FCONN168_ME1016810202011_SCM(CHIPS)':
 'NCSI_TXD1': CDS_PINID='NCSI_TXD1';
NODE_NAME     R173 2
 '@SCM_LIB.SCM(SCH_1):PAGE13_I453@PURE_QUANTA.Q_RES(CHIPS)':
 'B': CDS_PINID='B';
NET_NAME
'RMII_TXD1_R'
 '@SCM_LIB.SCM(SCH_1):RMII_TXD1_R':
 C_SIGNAL='@scm_lib.scm(sch_1):rmii_txd1_r';
NODE_NAME     U5 E25
 '@SCM_LIB.SCM(SCH_1):PAGE13_I363@PURE_QUANTA.AST2600A3GP(CHIPS)':
 'RGMII4TXD1||RMII4TXD1||NRI3||GPIOD7': CDS_PINID='\rgmii4txd1||rmii4txd1||nri3||gpiod7\';
NODE_NAME     R173 1
 '@SCM_LIB.SCM(SCH_1):PAGE13_I453@PURE_QUANTA.Q_RES(CHIPS)':
 'A': CDS_PINID='A';
NET_NAME
'RMII_TXEN'
 '@SCM_LIB.SCM(SCH_1):RMII_TXEN':
 C_SIGNAL='@scm_lib.scm(sch_1):rmii_txen';
NODE_NAME     GF1 B20
 '@SCM_LIB.SCM(SCH_1):PAGE10_I553@PURE_QUANTA.FCONN168_ME1016810202011_SCM(CHIPS)':
 'NCSI_TXEN': CDS_PINID='NCSI_TXEN';
NODE_NAME     R103 2
 '@SCM_LIB.SCM(SCH_1):PAGE11_I219@PURE_QUANTA.Q_RES(CHIPS)':
 'B': CDS_PINID='B';
NODE_NAME     R171 2
 '@SCM_LIB.SCM(SCH_1):PAGE13_I451@PURE_QUANTA.Q_RES(CHIPS)':
 'B': CDS_PINID='B';
NET_NAME
'RMII_TXEN_R'
 '@SCM_LIB.SCM(SCH_1):RMII_TXEN_R':
 C_SIGNAL='@scm_lib.scm(sch_1):rmii_txen_r';
NODE_NAME     U5 E23
 '@SCM_LIB.SCM(SCH_1):PAGE13_I363@PURE_QUANTA.AST2600A3GP(CHIPS)':
 'RGMII4TXCTL||RMII4TXEN||NDCD3||GPIOD5': CDS_PINID='\rgmii4txctl||rmii4txen||ndcd3||gpiod5\';
NODE_NAME     R171 1
 '@SCM_LIB.SCM(SCH_1):PAGE13_I451@PURE_QUANTA.Q_RES(CHIPS)':
 'A': CDS_PINID='A';
NET_NAME
'RST_BMC_EXTRST_R1_N'
 '@SCM_LIB.SCM(SCH_1):RST_BMC_EXTRST_R1_N':
 C_SIGNAL='@scm_lib.scm(sch_1):rst_bmc_extrst_r1_n';
NODE_NAME     R290 2
 '@SCM_LIB.SCM(SCH_1):PAGE22_I8@PURE_QUANTA.Q_RES(CHIPS)':
 'B': CDS_PINID='B';
NODE_NAME     R291 2
 '@SCM_LIB.SCM(SCH_1):PAGE22_I9@PURE_QUANTA.Q_RES(CHIPS)':
 'B': CDS_PINID='B';
NODE_NAME     U12 D
 '@SCM_LIB.SCM(SCH_1):PAGE22_I14@PURE_QUANTA.MOSFET_N(CHIPS)':
 'DRAIN': CDS_PINID='DRAIN';
NODE_NAME     U13 4
 '@SCM_LIB.SCM(SCH_1):PAGE22_I89@PURE_QUANTA.MC74VHC1G07DFT2G(CHIPS)':
 'OUT_Y': CDS_PINID='OUT_Y';
NET_NAME
'RST_BMC_EXTRST_R2_N'
 '@SCM_LIB.SCM(SCH_1):RST_BMC_EXTRST_R2_N':
 C_SIGNAL='@scm_lib.scm(sch_1):rst_bmc_extrst_r2_n';
NODE_NAME     Q1 C
 '@SCM_LIB.SCM(SCH_1):PAGE22_I2@PURE_QUANTA.MMBT39047F(CHIPS)':
 '3': CDS_PINID='\3\';
NODE_NAME     R287 2
 '@SCM_LIB.SCM(SCH_1):PAGE22_I5@PURE_QUANTA.Q_RES(CHIPS)':
 'B': CDS_PINID='B';
NODE_NAME     R636 2
 '@SCM_LIB.SCM(SCH_1):PAGE22_I10@PURE_QUANTA.Q_RES(CHIPS)':
 'B': CDS_PINID='B';
NODE_NAME     R106 2
 '@SCM_LIB.SCM(SCH_1):PAGE22_I12@PURE_QUANTA.Q_RES(CHIPS)':
 'B': CDS_PINID='B';
NODE_NAME     R110 2
 '@SCM_LIB.SCM(SCH_1):PAGE46_I116@PURE_QUANTA.Q_RES(CHIPS)':
 'B': CDS_PINID='B';
NET_NAME
'RST_BMC_EXTRST_R3_N'
 '@SCM_LIB.SCM(SCH_1):RST_BMC_EXTRST_R3_N':
 C_SIGNAL='@scm_lib.scm(sch_1):rst_bmc_extrst_r3_n';
NODE_NAME     J10 2
 '@SCM_LIB.SCM(SCH_1):PAGE46_I113@PURE_QUANTA.SCONN11_9192031111LF(CHIPS)':
 '2': CDS_PINID='\2\';
NODE_NAME     R110 1
 '@SCM_LIB.SCM(SCH_1):PAGE46_I116@PURE_QUANTA.Q_RES(CHIPS)':
 'A': CDS_PINID='A';
NET_NAME
'RST_BMC_HW'
 '@SCM_LIB.SCM(SCH_1):RST_BMC_HW':
 C_SIGNAL='@scm_lib.scm(sch_1):rst_bmc_hw';
NODE_NAME     R638 2
 '@SCM_LIB.SCM(SCH_1):PAGE35_I143@PURE_QUANTA.Q_RES(CHIPS)':
 'B': CDS_PINID='B';
NODE_NAME     R282 2
 '@SCM_LIB.SCM(SCH_1):PAGE22_I100@PURE_QUANTA.Q_RES(CHIPS)':
 'B': CDS_PINID='B';
NODE_NAME     R887 2
 '@SCM_LIB.SCM(SCH_1):PAGE22_I106@PURE_QUANTA.Q_RES(CHIPS)':
 'B': CDS_PINID='B';
NET_NAME
'RST_BMC_HW_OUT'
 '@SCM_LIB.SCM(SCH_1):RST_BMC_HW_OUT':
 C_SIGNAL='@scm_lib.scm(sch_1):rst_bmc_hw_out';
NODE_NAME     D17 1
 '@SCM_LIB.SCM(SCH_1):PAGE22_I28@PURE_QUANTA.Q_DIODE(CHIPS)':
 '1': CDS_PINID='\1\';
NODE_NAME     R633 2
 '@SCM_LIB.SCM(SCH_1):PAGE22_I81@PURE_QUANTA.Q_RES(CHIPS)':
 'B': CDS_PINID='B';
NODE_NAME     U58 4
 '@SCM_LIB.SCM(SCH_1):PAGE22_I94@PURE_QUANTA.MC74VHC1G32DTT1G(CHIPS)':
 'OUT_Y': CDS_PINID='OUT_Y';
NET_NAME
'RST_BMC_HW_R'
 '@SCM_LIB.SCM(SCH_1):RST_BMC_HW_R':
 C_SIGNAL='@scm_lib.scm(sch_1):rst_bmc_hw_r';
NODE_NAME     U25 J15
 '@SCM_LIB.SCM(SCH_1):PAGE35_I1@PURE_QUANTA.LCMXO3LF2100C5BG256C(CHIPS)':
 'PR9A': CDS_PINID='PR9A';
NODE_NAME     R638 1
 '@SCM_LIB.SCM(SCH_1):PAGE35_I143@PURE_QUANTA.Q_RES(CHIPS)':
 'A': CDS_PINID='A';
NET_NAME
'RST_BMC_HW_R1'
 '@SCM_LIB.SCM(SCH_1):RST_BMC_HW_R1':
 C_SIGNAL='@scm_lib.scm(sch_1):rst_bmc_hw_r1';
NODE_NAME     U58 2
 '@SCM_LIB.SCM(SCH_1):PAGE22_I94@PURE_QUANTA.MC74VHC1G32DTT1G(CHIPS)':
 'IN_A': CDS_PINID='IN_A';
NODE_NAME     R282 1
 '@SCM_LIB.SCM(SCH_1):PAGE22_I100@PURE_QUANTA.Q_RES(CHIPS)':
 'A': CDS_PINID='A';
NET_NAME
'RST_BMC_LPC_ESPI_N'
 '@SCM_LIB.SCM(SCH_1):RST_BMC_LPC_ESPI_N':
 C_SIGNAL='@scm_lib.scm(sch_1):rst_bmc_lpc_espi_n';
NODE_NAME     GF1 B4
 '@SCM_LIB.SCM(SCH_1):PAGE10_I553@PURE_QUANTA.FCONN168_ME1016810202011_SCM(CHIPS)':
 'ESPI_RESET_N': CDS_PINID='ESPI_RESET_N';
NODE_NAME     R117 2
 '@SCM_LIB.SCM(SCH_1):PAGE12_I2@PURE_QUANTA.Q_RES(CHIPS)':
 'B': CDS_PINID='B';
NODE_NAME     R120 1
 '@SCM_LIB.SCM(SCH_1):PAGE12_I33@PURE_QUANTA.Q_RES(CHIPS)':
 'A': CDS_PINID='A';
NODE_NAME     R312 1
 '@SCM_LIB.SCM(SCH_1):PAGE12_I456@PURE_QUANTA.Q_RES(CHIPS)':
 'A': CDS_PINID='A';
NET_NAME
'RST_BMC_RSTBTN_OUT_N'
 '@SCM_LIB.SCM(SCH_1):RST_BMC_RSTBTN_OUT_N':
 C_SIGNAL='@scm_lib.scm(sch_1):rst_bmc_rstbtn_out_n';
NODE_NAME     R566 2
 '@SCM_LIB.SCM(SCH_1):PAGE15_I128@PURE_QUANTA.Q_RES(CHIPS)':
 'B': CDS_PINID='B';
NODE_NAME     R717 2
 '@SCM_LIB.SCM(SCH_1):PAGE15_I174@PURE_QUANTA.Q_RES(CHIPS)':
 'B': CDS_PINID='B';
NODE_NAME     U25 C7
 '@SCM_LIB.SCM(SCH_1):PAGE34_I1@PURE_QUANTA.LCMXO3LF2100C5BG256C(CHIPS)':
 'PT13B': CDS_PINID='PT13B';
NET_NAME
'RST_BMC_RSTBTN_OUT_R_N'
 '@SCM_LIB.SCM(SCH_1):RST_BMC_RSTBTN_OUT_R_N':
 C_SIGNAL='@scm_lib.scm(sch_1):rst_bmc_rstbtn_out_r_n';
NODE_NAME     R566 1
 '@SCM_LIB.SCM(SCH_1):PAGE15_I128@PURE_QUANTA.Q_RES(CHIPS)':
 'A': CDS_PINID='A';
NODE_NAME     U5 AA24
 '@SCM_LIB.SCM(SCH_1):PAGE15_I350@PURE_QUANTA.AST2600A3GP(CHIPS)':
 'GPIOP3||PWM11||THRUOUT1': CDS_PINID='\gpiop3||pwm11||thruout1\';
NET_NAME
'RST_BMC_SELF_HW'
 '@SCM_LIB.SCM(SCH_1):RST_BMC_SELF_HW':
 C_SIGNAL='@scm_lib.scm(sch_1):rst_bmc_self_hw';
NODE_NAME     R494 2
 '@SCM_LIB.SCM(SCH_1):PAGE13_I335@PURE_QUANTA.Q_RES(CHIPS)':
 'B': CDS_PINID='B';
NODE_NAME     R271 1
 '@SCM_LIB.SCM(SCH_1):PAGE35_I88@PURE_QUANTA.Q_RES(CHIPS)':
 'A': CDS_PINID='A';
NODE_NAME     R450 1
 '@SCM_LIB.SCM(SCH_1):PAGE22_I101@PURE_QUANTA.Q_RES(CHIPS)':
 'A': CDS_PINID='A';
NODE_NAME     R888 2
 '@SCM_LIB.SCM(SCH_1):PAGE22_I102@PURE_QUANTA.Q_RES(CHIPS)':
 'B': CDS_PINID='B';
NET_NAME
'RST_BMC_SELF_HW_D'
 '@SCM_LIB.SCM(SCH_1):RST_BMC_SELF_HW_D':
 C_SIGNAL='@scm_lib.scm(sch_1):rst_bmc_self_hw_d';
NODE_NAME     C161 1
 '@SCM_LIB.SCM(SCH_1):PAGE22_I23@PURE_QUANTA.Q_CAP(CHIPS)':
 'A': CDS_PINID='A';
NODE_NAME     D17 2
 '@SCM_LIB.SCM(SCH_1):PAGE22_I28@PURE_QUANTA.Q_DIODE(CHIPS)':
 '2': CDS_PINID='\2\';
NODE_NAME     R313 1
 '@SCM_LIB.SCM(SCH_1):PAGE22_I30@PURE_QUANTA.Q_RES(CHIPS)':
 'A': CDS_PINID='A';
NET_NAME
'RST_BMC_SELF_HW_D_C'
 '@SCM_LIB.SCM(SCH_1):RST_BMC_SELF_HW_D_C':
 C_SIGNAL='@scm_lib.scm(sch_1):rst_bmc_self_hw_d_c';
NODE_NAME     U12 G
 '@SCM_LIB.SCM(SCH_1):PAGE22_I14@PURE_QUANTA.MOSFET_N(CHIPS)':
 'GATE': CDS_PINID='GATE';
NODE_NAME     C161 2
 '@SCM_LIB.SCM(SCH_1):PAGE22_I23@PURE_QUANTA.Q_CAP(CHIPS)':
 'B': CDS_PINID='B';
NODE_NAME     R314 1
 '@SCM_LIB.SCM(SCH_1):PAGE22_I26@PURE_QUANTA.Q_RES(CHIPS)':
 'A': CDS_PINID='A';
NODE_NAME     C173 1
 '@SCM_LIB.SCM(SCH_1):PAGE22_I107@PURE_QUANTA.Q_CAP(CHIPS)':
 'A': CDS_PINID='A';
NET_NAME
'RST_BMC_SELF_HW_R1'
 '@SCM_LIB.SCM(SCH_1):RST_BMC_SELF_HW_R1':
 C_SIGNAL='@scm_lib.scm(sch_1):rst_bmc_self_hw_r1';
NODE_NAME     R494 1
 '@SCM_LIB.SCM(SCH_1):PAGE13_I335@PURE_QUANTA.Q_RES(CHIPS)':
 'A': CDS_PINID='A';
NODE_NAME     U5 AF11
 '@SCM_LIB.SCM(SCH_1):PAGE13_I363@PURE_QUANTA.AST2600A3GP(CHIPS)':
 'GPIOY0||SALT5||WDTRST1#': CDS_PINID='\gpioy0||salt5||wdtrst1#\';
NET_NAME
'RST_BMC_SELF_HW_R2'
 '@SCM_LIB.SCM(SCH_1):RST_BMC_SELF_HW_R2':
 C_SIGNAL='@scm_lib.scm(sch_1):rst_bmc_self_hw_r2';
NODE_NAME     U25 G13
 '@SCM_LIB.SCM(SCH_1):PAGE35_I1@PURE_QUANTA.LCMXO3LF2100C5BG256C(CHIPS)':
 'PR4D': CDS_PINID='PR4D';
NODE_NAME     R271 2
 '@SCM_LIB.SCM(SCH_1):PAGE35_I88@PURE_QUANTA.Q_RES(CHIPS)':
 'B': CDS_PINID='B';
NODE_NAME     R641 2
 '@SCM_LIB.SCM(SCH_1):PAGE42_I53@PURE_QUANTA.Q_RES(CHIPS)':
 'B': CDS_PINID='B';
NET_NAME
'RST_BMC_SELF_HW_R3'
 '@SCM_LIB.SCM(SCH_1):RST_BMC_SELF_HW_R3':
 C_SIGNAL='@scm_lib.scm(sch_1):rst_bmc_self_hw_r3';
NODE_NAME     U58 1
 '@SCM_LIB.SCM(SCH_1):PAGE22_I94@PURE_QUANTA.MC74VHC1G32DTT1G(CHIPS)':
 'IN_B': CDS_PINID='IN_B';
NODE_NAME     R450 2
 '@SCM_LIB.SCM(SCH_1):PAGE22_I101@PURE_QUANTA.Q_RES(CHIPS)':
 'B': CDS_PINID='B';
NET_NAME
'RST_BMC_SRST_BUF_R1_N'
 '@SCM_LIB.SCM(SCH_1):RST_BMC_SRST_BUF_R1_N':
 C_SIGNAL='@scm_lib.scm(sch_1):rst_bmc_srst_buf_r1_n';
NODE_NAME     R315 2
 '@SCM_LIB.SCM(SCH_1):PAGE22_I71@PURE_QUANTA.Q_RES(CHIPS)':
 'B': CDS_PINID='B';
NODE_NAME     U13 2
 '@SCM_LIB.SCM(SCH_1):PAGE22_I89@PURE_QUANTA.MC74VHC1G07DFT2G(CHIPS)':
 'IN_A': CDS_PINID='IN_A';
NET_NAME
'RST_BMC_SRST_BUF_R_N'
 '@SCM_LIB.SCM(SCH_1):RST_BMC_SRST_BUF_R_N':
 C_SIGNAL='@scm_lib.scm(sch_1):rst_bmc_srst_buf_r_n';
NODE_NAME     R192 2
 '@SCM_LIB.SCM(SCH_1):PAGE22_I41@PURE_QUANTA.Q_RES(CHIPS)':
 'B': CDS_PINID='B';
NODE_NAME     C223 1
 '@SCM_LIB.SCM(SCH_1):PAGE22_I46@PURE_QUANTA.Q_CAP(CHIPS)':
 'A': CDS_PINID='A';
NODE_NAME     R108 2
 '@SCM_LIB.SCM(SCH_1):PAGE22_I65@PURE_QUANTA.Q_RES(CHIPS)':
 'B': CDS_PINID='B';
NODE_NAME     R124 2
 '@SCM_LIB.SCM(SCH_1):PAGE22_I67@PURE_QUANTA.Q_RES(CHIPS)':
 'B': CDS_PINID='B';
NODE_NAME     R125 1
 '@SCM_LIB.SCM(SCH_1):PAGE22_I69@PURE_QUANTA.Q_RES(CHIPS)':
 'A': CDS_PINID='A';
NODE_NAME     R315 1
 '@SCM_LIB.SCM(SCH_1):PAGE22_I71@PURE_QUANTA.Q_RES(CHIPS)':
 'A': CDS_PINID='A';
NET_NAME
'RST_BMC_SRST_N'
 '@SCM_LIB.SCM(SCH_1):RST_BMC_SRST_N':
 C_SIGNAL='@scm_lib.scm(sch_1):rst_bmc_srst_n';
NODE_NAME     R491 2
 '@SCM_LIB.SCM(SCH_1):PAGE15_I346@PURE_QUANTA.Q_RES(CHIPS)':
 'B': CDS_PINID='B';
NODE_NAME     U5 E10
 '@SCM_LIB.SCM(SCH_1):PAGE15_I350@PURE_QUANTA.AST2600A3GP(CHIPS)':
 'SRST#': CDS_PINID='\srst#\';
NODE_NAME     R106 1
 '@SCM_LIB.SCM(SCH_1):PAGE22_I12@PURE_QUANTA.Q_RES(CHIPS)':
 'A': CDS_PINID='A';
NODE_NAME     R125 2
 '@SCM_LIB.SCM(SCH_1):PAGE22_I69@PURE_QUANTA.Q_RES(CHIPS)':
 'B': CDS_PINID='B';
NET_NAME
'RST_ESPI_LPC_BMC_N'
 '@SCM_LIB.SCM(SCH_1):RST_ESPI_LPC_BMC_N':
 C_SIGNAL='@scm_lib.scm(sch_1):rst_espi_lpc_bmc_n';
NODE_NAME     R120 2
 '@SCM_LIB.SCM(SCH_1):PAGE12_I33@PURE_QUANTA.Q_RES(CHIPS)':
 'B': CDS_PINID='B';
NODE_NAME     U5 AD8
 '@SCM_LIB.SCM(SCH_1):PAGE12_I436@PURE_QUANTA.AST2600A3GP(CHIPS)':
 'GPIOW7||LPCRST#||ESPIRST#': CDS_PINID='\gpiow7||lpcrst#||espirst#\';
NET_NAME
'RST_EXTRST_N'
 '@SCM_LIB.SCM(SCH_1):RST_EXTRST_N':
 C_SIGNAL='@scm_lib.scm(sch_1):rst_extrst_n';
NODE_NAME     R623 2
 '@SCM_LIB.SCM(SCH_1):PAGE15_I152@PURE_QUANTA.Q_RES(CHIPS)':
 'B': CDS_PINID='B';
NODE_NAME     U5 B10
 '@SCM_LIB.SCM(SCH_1):PAGE15_I350@PURE_QUANTA.AST2600A3GP(CHIPS)':
 'EXTRST#': CDS_PINID='\extrst#\';
NODE_NAME     R636 1
 '@SCM_LIB.SCM(SCH_1):PAGE22_I10@PURE_QUANTA.Q_RES(CHIPS)':
 'A': CDS_PINID='A';
NODE_NAME     R447 2
 '@SCM_LIB.SCM(SCH_1):PAGE34_I168@PURE_QUANTA.Q_RES(CHIPS)':
 'B': CDS_PINID='B';
NET_NAME
'RST_EXTRST_R_N'
 '@SCM_LIB.SCM(SCH_1):RST_EXTRST_R_N':
 C_SIGNAL='@scm_lib.scm(sch_1):rst_extrst_r_n';
NODE_NAME     U25 A11
 '@SCM_LIB.SCM(SCH_1):PAGE34_I1@PURE_QUANTA.LCMXO3LF2100C5BG256C(CHIPS)':
 'PT21A': CDS_PINID='PT21A';
NODE_NAME     R447 1
 '@SCM_LIB.SCM(SCH_1):PAGE34_I168@PURE_QUANTA.Q_RES(CHIPS)':
 'A': CDS_PINID='A';
NET_NAME
'RST_MB_STBY_N'
 '@SCM_LIB.SCM(SCH_1):RST_MB_STBY_N':
 C_SIGNAL='@scm_lib.scm(sch_1):rst_mb_stby_n';
NODE_NAME     GF1 A46
 '@SCM_LIB.SCM(SCH_1):PAGE10_I553@PURE_QUANTA.FCONN168_ME1016810202011_SCM(CHIPS)':
 'HPM_STBY_RST_N': CDS_PINID='HPM_STBY_RST_N';
NODE_NAME     R263 1
 '@SCM_LIB.SCM(SCH_1):PAGE35_I141@PURE_QUANTA.Q_RES(CHIPS)':
 'A': CDS_PINID='A';
NET_NAME
'RST_MB_STBY_R_N'
 '@SCM_LIB.SCM(SCH_1):RST_MB_STBY_R_N':
 C_SIGNAL='@scm_lib.scm(sch_1):rst_mb_stby_r_n';
NODE_NAME     U25 H11
 '@SCM_LIB.SCM(SCH_1):PAGE35_I1@PURE_QUANTA.LCMXO3LF2100C5BG256C(CHIPS)':
 'PR9C': CDS_PINID='PR9C';
NODE_NAME     R263 2
 '@SCM_LIB.SCM(SCH_1):PAGE35_I141@PURE_QUANTA.Q_RES(CHIPS)':
 'B': CDS_PINID='B';
NET_NAME
'RST_PCA9548_SENSOR_N'
 '@SCM_LIB.SCM(SCH_1):RST_PCA9548_SENSOR_N':
 C_SIGNAL='@scm_lib.scm(sch_1):rst_pca9548_sensor_n';
NODE_NAME     U25 B4
 '@SCM_LIB.SCM(SCH_1):PAGE34_I1@PURE_QUANTA.LCMXO3LF2100C5BG256C(CHIPS)':
 'PT11D': CDS_PINID='PT11D';
NODE_NAME     R169 2
 '@SCM_LIB.SCM(SCH_1):PAGE11_I256@PURE_QUANTA.Q_RES(CHIPS)':
 'B': CDS_PINID='B';
NODE_NAME     R70 2
 '@SCM_LIB.SCM(SCH_1):PAGE13_I419@PURE_QUANTA.Q_RES(CHIPS)':
 'B': CDS_PINID='B';
NET_NAME
'RST_PCA9548_SENSOR_R_N'
 '@SCM_LIB.SCM(SCH_1):RST_PCA9548_SENSOR_R_N':
 C_SIGNAL='@scm_lib.scm(sch_1):rst_pca9548_sensor_r_n';
NODE_NAME     U5 P23
 '@SCM_LIB.SCM(SCH_1):PAGE13_I363@PURE_QUANTA.AST2600A3GP(CHIPS)':
 'GPIOS6||TXD11': CDS_PINID='\gpios6||txd11\';
NODE_NAME     R70 1
 '@SCM_LIB.SCM(SCH_1):PAGE13_I419@PURE_QUANTA.Q_RES(CHIPS)':
 'A': CDS_PINID='A';
NET_NAME
'RST_PFR_OVR_RTC_R'
 '@SCM_LIB.SCM(SCH_1):RST_PFR_OVR_RTC_R':
 C_SIGNAL='@scm_lib.scm(sch_1):rst_pfr_ovr_rtc_r';
NODE_NAME     U5 M25
 '@SCM_LIB.SCM(SCH_1):PAGE12_I436@PURE_QUANTA.AST2600A3GP(CHIPS)':
 'GPIOA1||SDA11||MDIO3': CDS_PINID='\gpioa1||sda11||mdio3\';
NODE_NAME     U25 T7
 '@SCM_LIB.SCM(SCH_1):PAGE36_I1@PURE_QUANTA.LCMXO3LF2100C5BG256C(CHIPS)':
 'PB11A||PCLKT2_0': CDS_PINID='\pb11a||pclkt2_0\';
NET_NAME
'RST_PLTRST_N'
 '@SCM_LIB.SCM(SCH_1):RST_PLTRST_N':
 C_SIGNAL='@scm_lib.scm(sch_1):rst_pltrst_n';
NODE_NAME     GF1 A51
 '@SCM_LIB.SCM(SCH_1):PAGE10_I553@PURE_QUANTA.FCONN168_ME1016810202011_SCM(CHIPS)':
 'RST_PLTRST_BUF_N': CDS_PINID='RST_PLTRST_BUF_N';
NODE_NAME     R34 2
 '@SCM_LIB.SCM(SCH_1):PAGE11_I194@PURE_QUANTA.Q_RES(CHIPS)':
 'B': CDS_PINID='B';
NODE_NAME     R118 2
 '@SCM_LIB.SCM(SCH_1):PAGE12_I53@PURE_QUANTA.Q_RES(CHIPS)':
 'B': CDS_PINID='B';
NODE_NAME     R168 1
 '@SCM_LIB.SCM(SCH_1):PAGE12_I268@PURE_QUANTA.Q_RES(CHIPS)':
 'A': CDS_PINID='A';
NODE_NAME     U5 A7
 '@SCM_LIB.SCM(SCH_1):PAGE12_I436@PURE_QUANTA.AST2600A3GP(CHIPS)':
 'PERST#': CDS_PINID='\perst#\';
NODE_NAME     R702 1
 '@SCM_LIB.SCM(SCH_1):PAGE28_I126@PURE_QUANTA.Q_RES(CHIPS)':
 'A': CDS_PINID='A';
NODE_NAME     R503 2
 '@SCM_LIB.SCM(SCH_1):PAGE46_I60@PURE_QUANTA.Q_RES(CHIPS)':
 'B': CDS_PINID='B';
NODE_NAME     R718 1
 '@SCM_LIB.SCM(SCH_1):PAGE34_I157@PURE_QUANTA.Q_RES(CHIPS)':
 'A': CDS_PINID='A';
NET_NAME
'RST_PLTRST_R1_N'
 '@SCM_LIB.SCM(SCH_1):RST_PLTRST_R1_N':
 C_SIGNAL='@scm_lib.scm(sch_1):rst_pltrst_r1_n';
NODE_NAME     U25 A4
 '@SCM_LIB.SCM(SCH_1):PAGE34_I1@PURE_QUANTA.LCMXO3LF2100C5BG256C(CHIPS)':
 'PT10A': CDS_PINID='PT10A';
NODE_NAME     R718 2
 '@SCM_LIB.SCM(SCH_1):PAGE34_I157@PURE_QUANTA.Q_RES(CHIPS)':
 'B': CDS_PINID='B';
NET_NAME
'RST_PLTRST_R2_N'
 '@SCM_LIB.SCM(SCH_1):RST_PLTRST_R2_N':
 C_SIGNAL='@scm_lib.scm(sch_1):rst_pltrst_r2_n';
NODE_NAME     R702 2
 '@SCM_LIB.SCM(SCH_1):PAGE28_I126@PURE_QUANTA.Q_RES(CHIPS)':
 'B': CDS_PINID='B';
NODE_NAME     U40 16
 '@SCM_LIB.SCM(SCH_1):PAGE28_I141@PURE_QUANTA.PCA9555PW(CHIPS)':
 'P13': CDS_PINID='P13';
NET_NAME
'RST_PLTRST_R_N'
 '@SCM_LIB.SCM(SCH_1):RST_PLTRST_R_N':
 C_SIGNAL='@scm_lib.scm(sch_1):rst_pltrst_r_n';
NODE_NAME     R168 2
 '@SCM_LIB.SCM(SCH_1):PAGE12_I268@PURE_QUANTA.Q_RES(CHIPS)':
 'B': CDS_PINID='B';
NODE_NAME     U5 H24
 '@SCM_LIB.SCM(SCH_1):PAGE13_I363@PURE_QUANTA.AST2600A3GP(CHIPS)':
 'RGMII3TXCK||RMII3RCLKO||GPIOC0': CDS_PINID='\rgmii3txck||rmii3rclko||gpioc0\';
NET_NAME
'RST_PLTRST_TPM_N'
 '@SCM_LIB.SCM(SCH_1):RST_PLTRST_TPM_N':
 C_SIGNAL='@scm_lib.scm(sch_1):rst_pltrst_tpm_n';
NODE_NAME     J5 2
 '@SCM_LIB.SCM(SCH_1):PAGE46_I56@PURE_QUANTA.SCONN11_9192031111LF(CHIPS)':
 '2': CDS_PINID='\2\';
NODE_NAME     R503 1
 '@SCM_LIB.SCM(SCH_1):PAGE46_I60@PURE_QUANTA.Q_RES(CHIPS)':
 'A': CDS_PINID='A';
NET_NAME
'RST_ROT_CPU_N'
 '@SCM_LIB.SCM(SCH_1):RST_ROT_CPU_N':
 C_SIGNAL='@scm_lib.scm(sch_1):rst_rot_cpu_n';
NODE_NAME     GF1 A53
 '@SCM_LIB.SCM(SCH_1):PAGE10_I553@PURE_QUANTA.FCONN168_ME1016810202011_SCM(CHIPS)':
 'ROT_CPU_RST_N': CDS_PINID='ROT_CPU_RST_N';
NODE_NAME     R828 2
 '@SCM_LIB.SCM(SCH_1):PAGE11_I241@PURE_QUANTA.Q_RES(CHIPS)':
 'B': CDS_PINID='B';
NODE_NAME     R60 2
 '@SCM_LIB.SCM(SCH_1):PAGE13_I382@PURE_QUANTA.Q_RES(CHIPS)':
 'B': CDS_PINID='B';
NODE_NAME     R748 2
 '@SCM_LIB.SCM(SCH_1):PAGE36_I78@PURE_QUANTA.Q_RES(CHIPS)':
 'B': CDS_PINID='B';
NODE_NAME     R825 1
 '@SCM_LIB.SCM(SCH_1):PAGE35_I138@PURE_QUANTA.Q_RES(CHIPS)':
 'A': CDS_PINID='A';
NET_NAME
'RST_ROT_CPU_R1_N'
 '@SCM_LIB.SCM(SCH_1):RST_ROT_CPU_R1_N':
 C_SIGNAL='@scm_lib.scm(sch_1):rst_rot_cpu_r1_n';
NODE_NAME     U5 G22
 '@SCM_LIB.SCM(SCH_1):PAGE13_I363@PURE_QUANTA.AST2600A3GP(CHIPS)':
 'RGMII3TXD2||GPIOC4': CDS_PINID='\rgmii3txd2||gpioc4\';
NODE_NAME     R60 1
 '@SCM_LIB.SCM(SCH_1):PAGE13_I382@PURE_QUANTA.Q_RES(CHIPS)':
 'A': CDS_PINID='A';
NET_NAME
'RST_ROT_CPU_R_N'
 '@SCM_LIB.SCM(SCH_1):RST_ROT_CPU_R_N':
 C_SIGNAL='@scm_lib.scm(sch_1):rst_rot_cpu_r_n';
NODE_NAME     U25 H12
 '@SCM_LIB.SCM(SCH_1):PAGE35_I1@PURE_QUANTA.LCMXO3LF2100C5BG256C(CHIPS)':
 'PR5D': CDS_PINID='PR5D';
NODE_NAME     R825 2
 '@SCM_LIB.SCM(SCH_1):PAGE35_I138@PURE_QUANTA.Q_RES(CHIPS)':
 'B': CDS_PINID='B';
NET_NAME
'RST_RSMRST_N'
 '@SCM_LIB.SCM(SCH_1):RST_RSMRST_N':
 C_SIGNAL='@scm_lib.scm(sch_1):rst_rsmrst_n';
NODE_NAME     R160 1
 '@SCM_LIB.SCM(SCH_1):PAGE13_I159@PURE_QUANTA.Q_RES(CHIPS)':
 'A': CDS_PINID='A';
NODE_NAME     U25 A5
 '@SCM_LIB.SCM(SCH_1):PAGE34_I1@PURE_QUANTA.LCMXO3LF2100C5BG256C(CHIPS)':
 'PT11A': CDS_PINID='PT11A';
NODE_NAME     R625 2
 '@SCM_LIB.SCM(SCH_1):PAGE34_I17@PURE_QUANTA.Q_RES(CHIPS)':
 'B': CDS_PINID='B';
NET_NAME
'RST_RSMRST_R_N'
 '@SCM_LIB.SCM(SCH_1):RST_RSMRST_R_N':
 C_SIGNAL='@scm_lib.scm(sch_1):rst_rsmrst_r_n';
NODE_NAME     R160 2
 '@SCM_LIB.SCM(SCH_1):PAGE13_I159@PURE_QUANTA.Q_RES(CHIPS)':
 'B': CDS_PINID='B';
NODE_NAME     U5 AF14
 '@SCM_LIB.SCM(SCH_1):PAGE13_I363@PURE_QUANTA.AST2600A3GP(CHIPS)':
 'GPIOV1||SIOS5#': CDS_PINID='\gpiov1||sios5#\';
NET_NAME
'RST_SGPIO_RESET_BMC_N'
 '@SCM_LIB.SCM(SCH_1):RST_SGPIO_RESET_BMC_N':
 C_SIGNAL='@scm_lib.scm(sch_1):rst_sgpio_reset_bmc_n';
NODE_NAME     U5 H23
 '@SCM_LIB.SCM(SCH_1):PAGE13_I363@PURE_QUANTA.AST2600A3GP(CHIPS)':
 'RGMII3TXD1||RMII3TXD1||GPIOC3': CDS_PINID='\rgmii3txd1||rmii3txd1||gpioc3\';
NODE_NAME     R688 1
 '@SCM_LIB.SCM(SCH_1):PAGE13_I383@PURE_QUANTA.Q_RES(CHIPS)':
 'A': CDS_PINID='A';
NET_NAME
'RST_SGPIO_RESET_N'
 '@SCM_LIB.SCM(SCH_1):RST_SGPIO_RESET_N':
 C_SIGNAL='@scm_lib.scm(sch_1):rst_sgpio_reset_n';
NODE_NAME     GF1 B39
 '@SCM_LIB.SCM(SCH_1):PAGE10_I553@PURE_QUANTA.FCONN168_ME1016810202011_SCM(CHIPS)':
 'SGPIO_RESET_N': CDS_PINID='SGPIO_RESET_N';
NODE_NAME     R69 2
 '@SCM_LIB.SCM(SCH_1):PAGE11_I227@PURE_QUANTA.Q_RES(CHIPS)':
 'B': CDS_PINID='B';
NODE_NAME     R688 2
 '@SCM_LIB.SCM(SCH_1):PAGE13_I383@PURE_QUANTA.Q_RES(CHIPS)':
 'B': CDS_PINID='B';
NODE_NAME     R691 2
 '@SCM_LIB.SCM(SCH_1):PAGE35_I148@PURE_QUANTA.Q_RES(CHIPS)':
 'B': CDS_PINID='B';
NET_NAME
'RST_SGPIO_RESET_R_N'
 '@SCM_LIB.SCM(SCH_1):RST_SGPIO_RESET_R_N':
 C_SIGNAL='@scm_lib.scm(sch_1):rst_sgpio_reset_r_n';
NODE_NAME     U25 E16
 '@SCM_LIB.SCM(SCH_1):PAGE35_I1@PURE_QUANTA.LCMXO3LF2100C5BG256C(CHIPS)':
 'PR3A': CDS_PINID='PR3A';
NODE_NAME     R691 1
 '@SCM_LIB.SCM(SCH_1):PAGE35_I148@PURE_QUANTA.Q_RES(CHIPS)':
 'A': CDS_PINID='A';
NET_NAME
'RST_SPI_BMC_FLASH_R1_N'
 '@SCM_LIB.SCM(SCH_1):RST_SPI_BMC_FLASH_R1_N':
 C_SIGNAL='@scm_lib.scm(sch_1):rst_spi_bmc_flash_r1_n';
NODE_NAME     J4 21
 '@SCM_LIB.SCM(SCH_1):PAGE21_I84@PURE_QUANTA.SCONN67_NASA0S6730TS67(CHIPS)':
 '21': CDS_PINID='\21\';
NODE_NAME     R562 1
 '@SCM_LIB.SCM(SCH_1):PAGE21_I180@PURE_QUANTA.Q_RES(CHIPS)':
 'A': CDS_PINID='A';
NET_NAME
'RST_SPI_BMC_FLASH_R2_N'
 '@SCM_LIB.SCM(SCH_1):RST_SPI_BMC_FLASH_R2_N':
 C_SIGNAL='@scm_lib.scm(sch_1):rst_spi_bmc_flash_r2_n';
NODE_NAME     J4 19
 '@SCM_LIB.SCM(SCH_1):PAGE21_I84@PURE_QUANTA.SCONN67_NASA0S6730TS67(CHIPS)':
 '19': CDS_PINID='\19\';
NODE_NAME     R561 1
 '@SCM_LIB.SCM(SCH_1):PAGE21_I181@PURE_QUANTA.Q_RES(CHIPS)':
 'A': CDS_PINID='A';
NODE_NAME     R90 2
 '@SCM_LIB.SCM(SCH_1):PAGE21_I182@PURE_QUANTA.Q_RES(CHIPS)':
 'B': CDS_PINID='B';
NET_NAME
'RST_SPI_FLASH_BUF_N'
 '@SCM_LIB.SCM(SCH_1):RST_SPI_FLASH_BUF_N':
 C_SIGNAL='@scm_lib.scm(sch_1):rst_spi_flash_buf_n';
NODE_NAME     R563 2
 '@SCM_LIB.SCM(SCH_1):PAGE25_I3@PURE_QUANTA.Q_RES(CHIPS)':
 'B': CDS_PINID='B';
NODE_NAME     R827 2
 '@SCM_LIB.SCM(SCH_1):PAGE25_I73@PURE_QUANTA.Q_RES(CHIPS)':
 'B': CDS_PINID='B';
NODE_NAME     R562 2
 '@SCM_LIB.SCM(SCH_1):PAGE21_I180@PURE_QUANTA.Q_RES(CHIPS)':
 'B': CDS_PINID='B';
NODE_NAME     R561 2
 '@SCM_LIB.SCM(SCH_1):PAGE21_I181@PURE_QUANTA.Q_RES(CHIPS)':
 'B': CDS_PINID='B';
NET_NAME
'RST_SPI_FLASH_BUF_R3_N'
 '@SCM_LIB.SCM(SCH_1):RST_SPI_FLASH_BUF_R3_N':
 C_SIGNAL='@scm_lib.scm(sch_1):rst_spi_flash_buf_r3_n';
NODE_NAME     U44 4
 '@SCM_LIB.SCM(SCH_1):PAGE25_I61@PURE_QUANTA.SN74LVC1G07DCKR(CHIPS)':
 'Y': CDS_PINID='Y';
NODE_NAME     R827 1
 '@SCM_LIB.SCM(SCH_1):PAGE25_I73@PURE_QUANTA.Q_RES(CHIPS)':
 'A': CDS_PINID='A';
NET_NAME
'RST_SPI_FLASH_N'
 '@SCM_LIB.SCM(SCH_1):RST_SPI_FLASH_N':
 C_SIGNAL='@scm_lib.scm(sch_1):rst_spi_flash_n';
NODE_NAME     U5 B7
 '@SCM_LIB.SCM(SCH_1):PAGE15_I350@PURE_QUANTA.AST2600A3GP(CHIPS)':
 'RSTIND#': CDS_PINID='\rstind#\';
NODE_NAME     R752 1
 '@SCM_LIB.SCM(SCH_1):PAGE25_I67@PURE_QUANTA.Q_RES(CHIPS)':
 'A': CDS_PINID='A';
NODE_NAME     R585 2
 '@SCM_LIB.SCM(SCH_1):PAGE15_I404@PURE_QUANTA.Q_RES(CHIPS)':
 'B': CDS_PINID='B';
NET_NAME
'RST_SPI_FLASH_R_N'
 '@SCM_LIB.SCM(SCH_1):RST_SPI_FLASH_R_N':
 C_SIGNAL='@scm_lib.scm(sch_1):rst_spi_flash_r_n';
NODE_NAME     U44 2
 '@SCM_LIB.SCM(SCH_1):PAGE25_I61@PURE_QUANTA.SN74LVC1G07DCKR(CHIPS)':
 'A': CDS_PINID='A';
NODE_NAME     R752 2
 '@SCM_LIB.SCM(SCH_1):PAGE25_I67@PURE_QUANTA.Q_RES(CHIPS)':
 'B': CDS_PINID='B';
NET_NAME
'RST_SPI_PCH_FLASH_R1_N'
 '@SCM_LIB.SCM(SCH_1):RST_SPI_PCH_FLASH_R1_N':
 C_SIGNAL='@scm_lib.scm(sch_1):rst_spi_pch_flash_r1_n';
NODE_NAME     R496 2
 '@SCM_LIB.SCM(SCH_1):PAGE45_I48@PURE_QUANTA.Q_RES(CHIPS)':
 'B': CDS_PINID='B';
NODE_NAME     J40 3
 '@SCM_LIB.SCM(SCH_1):PAGE45_I53@PURE_QUANTA.SCONN16_ACASPI006P06(CHIPS)':
 'NC0': CDS_PINID='NC0';
NODE_NAME     U17 3
 '@SCM_LIB.SCM(SCH_1):PAGE45_I54@PURE_QUANTA.MX25L51245GMI10G(CHIPS)':
 'RESET#': CDS_PINID='\reset#\';
NET_NAME
'RST_SRST_PLD_BMC_BUF_N'
 '@SCM_LIB.SCM(SCH_1):RST_SRST_PLD_BMC_BUF_N':
 C_SIGNAL='@scm_lib.scm(sch_1):rst_srst_pld_bmc_buf_n';
NODE_NAME     R108 1
 '@SCM_LIB.SCM(SCH_1):PAGE22_I65@PURE_QUANTA.Q_RES(CHIPS)':
 'A': CDS_PINID='A';
NODE_NAME     U6 4
 '@SCM_LIB.SCM(SCH_1):PAGE22_I87@PURE_QUANTA.74LVC2G07DW7(CHIPS)':
 '2Y': CDS_PINID='\2y\';
NET_NAME
'RST_SRST_PLD_BMC_R1_N'
 '@SCM_LIB.SCM(SCH_1):RST_SRST_PLD_BMC_R1_N':
 C_SIGNAL='@scm_lib.scm(sch_1):rst_srst_pld_bmc_r1_n';
NODE_NAME     R614 1
 '@SCM_LIB.SCM(SCH_1):PAGE22_I35@PURE_QUANTA.Q_RES(CHIPS)':
 'A': CDS_PINID='A';
NODE_NAME     U6 3
 '@SCM_LIB.SCM(SCH_1):PAGE22_I87@PURE_QUANTA.74LVC2G07DW7(CHIPS)':
 '2A': CDS_PINID='\2a\';
NODE_NAME     R388 2
 '@SCM_LIB.SCM(SCH_1):PAGE22_I92@PURE_QUANTA.Q_RES(CHIPS)':
 'B': CDS_PINID='B';
NET_NAME
'RST_SRST_PLD_BMC_R2_N'
 '@SCM_LIB.SCM(SCH_1):RST_SRST_PLD_BMC_R2_N':
 C_SIGNAL='@scm_lib.scm(sch_1):rst_srst_pld_bmc_r2_n';
NODE_NAME     U25 F8
 '@SCM_LIB.SCM(SCH_1):PAGE34_I1@PURE_QUANTA.LCMXO3LF2100C5BG256C(CHIPS)':
 'PT18A': CDS_PINID='PT18A';
NODE_NAME     R10 1
 '@SCM_LIB.SCM(SCH_1):PAGE34_I155@PURE_QUANTA.Q_RES(CHIPS)':
 'A': CDS_PINID='A';
NET_NAME
'RST_SRST_PLD_BMC_R_N'
 '@SCM_LIB.SCM(SCH_1):RST_SRST_PLD_BMC_R_N':
 C_SIGNAL='@scm_lib.scm(sch_1):rst_srst_pld_bmc_r_n';
NODE_NAME     GF1 OB11
 '@SCM_LIB.SCM(SCH_1):PAGE10_I553@PURE_QUANTA.FCONN168_ME1016810202011_SCM(CHIPS)':
 'SPI0_CLK': CDS_PINID='SPI0_CLK';
NODE_NAME     R10 2
 '@SCM_LIB.SCM(SCH_1):PAGE34_I155@PURE_QUANTA.Q_RES(CHIPS)':
 'B': CDS_PINID='B';
NODE_NAME     R388 1
 '@SCM_LIB.SCM(SCH_1):PAGE22_I92@PURE_QUANTA.Q_RES(CHIPS)':
 'A': CDS_PINID='A';
NET_NAME
'RST_WDTRST_PLD_N'
 '@SCM_LIB.SCM(SCH_1):RST_WDTRST_PLD_N':
 C_SIGNAL='@scm_lib.scm(sch_1):rst_wdtrst_pld_n';
NODE_NAME     R637 2
 '@SCM_LIB.SCM(SCH_1):PAGE13_I337@PURE_QUANTA.Q_RES(CHIPS)':
 'B': CDS_PINID='B';
NODE_NAME     R452 2
 '@SCM_LIB.SCM(SCH_1):PAGE13_I339@PURE_QUANTA.Q_RES(CHIPS)':
 'B': CDS_PINID='B';
NODE_NAME     R635 1
 '@SCM_LIB.SCM(SCH_1):PAGE36_I80@PURE_QUANTA.Q_RES(CHIPS)':
 'A': CDS_PINID='A';
NET_NAME
'RST_WDTRST_PLD_R1_N'
 '@SCM_LIB.SCM(SCH_1):RST_WDTRST_PLD_R1_N':
 C_SIGNAL='@scm_lib.scm(sch_1):rst_wdtrst_pld_r1_n';
NODE_NAME     R637 1
 '@SCM_LIB.SCM(SCH_1):PAGE13_I337@PURE_QUANTA.Q_RES(CHIPS)':
 'A': CDS_PINID='A';
NODE_NAME     U5 AD12
 '@SCM_LIB.SCM(SCH_1):PAGE13_I363@PURE_QUANTA.AST2600A3GP(CHIPS)':
 'GPIOY1||SALT6||WDTRST2#': CDS_PINID='\gpioy1||salt6||wdtrst2#\';
NET_NAME
'RST_WDTRST_PLD_R2_N'
 '@SCM_LIB.SCM(SCH_1):RST_WDTRST_PLD_R2_N':
 C_SIGNAL='@scm_lib.scm(sch_1):rst_wdtrst_pld_r2_n';
NODE_NAME     U25 T3
 '@SCM_LIB.SCM(SCH_1):PAGE36_I1@PURE_QUANTA.LCMXO3LF2100C5BG256C(CHIPS)':
 'PB6C': CDS_PINID='PB6C';
NODE_NAME     R635 2
 '@SCM_LIB.SCM(SCH_1):PAGE36_I80@PURE_QUANTA.Q_RES(CHIPS)':
 'B': CDS_PINID='B';
NET_NAME
'SGPIO_BMC_M1_CLK'
 '@SCM_LIB.SCM(SCH_1):SGPIO_BMC_M1_CLK':
 C_SIGNAL='@scm_lib.scm(sch_1):sgpio_bmc_m1_clk';
NODE_NAME     R148 2
 '@SCM_LIB.SCM(SCH_1):PAGE12_I379@PURE_QUANTA.Q_RES(CHIPS)':
 'B': CDS_PINID='B';
NODE_NAME     U5 A18
 '@SCM_LIB.SCM(SCH_1):PAGE12_I436@PURE_QUANTA.AST2600A3GP(CHIPS)':
 'GPIOH0||SGPM1CK': CDS_PINID='\gpioh0||sgpm1ck\';
NET_NAME
'SGPIO_BMC_M1_DI'
 '@SCM_LIB.SCM(SCH_1):SGPIO_BMC_M1_DI':
 C_SIGNAL='@scm_lib.scm(sch_1):sgpio_bmc_m1_di';
NODE_NAME     R433 2
 '@SCM_LIB.SCM(SCH_1):PAGE12_I382@PURE_QUANTA.Q_RES(CHIPS)':
 'B': CDS_PINID='B';
NODE_NAME     U5 A17
 '@SCM_LIB.SCM(SCH_1):PAGE12_I436@PURE_QUANTA.AST2600A3GP(CHIPS)':
 'GPIOH3||SGPM1I': CDS_PINID='\gpioh3||sgpm1i\';
NET_NAME
'SGPIO_BMC_M1_DO'
 '@SCM_LIB.SCM(SCH_1):SGPIO_BMC_M1_DO':
 C_SIGNAL='@scm_lib.scm(sch_1):sgpio_bmc_m1_do';
NODE_NAME     R151 2
 '@SCM_LIB.SCM(SCH_1):PAGE12_I381@PURE_QUANTA.Q_RES(CHIPS)':
 'B': CDS_PINID='B';
NODE_NAME     U5 C18
 '@SCM_LIB.SCM(SCH_1):PAGE12_I436@PURE_QUANTA.AST2600A3GP(CHIPS)':
 'GPIOH2||SGPM1O': CDS_PINID='\gpioh2||sgpm1o\';
NET_NAME
'SGPIO_BMC_M1_LD'
 '@SCM_LIB.SCM(SCH_1):SGPIO_BMC_M1_LD':
 C_SIGNAL='@scm_lib.scm(sch_1):sgpio_bmc_m1_ld';
NODE_NAME     R150 2
 '@SCM_LIB.SCM(SCH_1):PAGE12_I380@PURE_QUANTA.Q_RES(CHIPS)':
 'B': CDS_PINID='B';
NODE_NAME     U5 B18
 '@SCM_LIB.SCM(SCH_1):PAGE12_I436@PURE_QUANTA.AST2600A3GP(CHIPS)':
 'GPIOH1||SGPM1LD': CDS_PINID='\gpioh1||sgpm1ld\';
NET_NAME
'SGPIO_CLK_0'
 '@SCM_LIB.SCM(SCH_1):SGPIO_CLK_0':
 C_SIGNAL='@scm_lib.scm(sch_1):sgpio_clk_0';
NODE_NAME     GF1 B30
 '@SCM_LIB.SCM(SCH_1):PAGE10_I553@PURE_QUANTA.FCONN168_ME1016810202011_SCM(CHIPS)':
 'SGPIO_CLK': CDS_PINID='SGPIO_CLK';
NODE_NAME     R82 2
 '@SCM_LIB.SCM(SCH_1):PAGE11_I232@PURE_QUANTA.Q_RES(CHIPS)':
 'B': CDS_PINID='B';
NODE_NAME     R64 1
 '@SCM_LIB.SCM(SCH_1):PAGE11_I233@PURE_QUANTA.Q_RES(CHIPS)':
 'A': CDS_PINID='A';
NODE_NAME     R434 2
 '@SCM_LIB.SCM(SCH_1):PAGE34_I160@PURE_QUANTA.Q_RES(CHIPS)':
 'B': CDS_PINID='B';
NET_NAME
'SGPIO_CLK_1'
 '@SCM_LIB.SCM(SCH_1):SGPIO_CLK_1':
 C_SIGNAL='@scm_lib.scm(sch_1):sgpio_clk_1';
NODE_NAME     GF1 B35
 '@SCM_LIB.SCM(SCH_1):PAGE10_I553@PURE_QUANTA.FCONN168_ME1016810202011_SCM(CHIPS)':
 'RSVD2': CDS_PINID='RSVD2';
NODE_NAME     R76 2
 '@SCM_LIB.SCM(SCH_1):PAGE11_I230@PURE_QUANTA.Q_RES(CHIPS)':
 'B': CDS_PINID='B';
NODE_NAME     R63 1
 '@SCM_LIB.SCM(SCH_1):PAGE11_I231@PURE_QUANTA.Q_RES(CHIPS)':
 'A': CDS_PINID='A';
NODE_NAME     R148 1
 '@SCM_LIB.SCM(SCH_1):PAGE12_I379@PURE_QUANTA.Q_RES(CHIPS)':
 'A': CDS_PINID='A';
NET_NAME
'SGPIO_CLK_PLD_0'
 '@SCM_LIB.SCM(SCH_1):SGPIO_CLK_PLD_0':
 C_SIGNAL='@scm_lib.scm(sch_1):sgpio_clk_pld_0';
NODE_NAME     U25 A14
 '@SCM_LIB.SCM(SCH_1):PAGE34_I1@PURE_QUANTA.LCMXO3LF2100C5BG256C(CHIPS)':
 'PT22D': CDS_PINID='PT22D';
NODE_NAME     R434 1
 '@SCM_LIB.SCM(SCH_1):PAGE34_I160@PURE_QUANTA.Q_RES(CHIPS)':
 'A': CDS_PINID='A';
NET_NAME
'SGPIO_DI_0'
 '@SCM_LIB.SCM(SCH_1):SGPIO_DI_0':
 C_SIGNAL='@scm_lib.scm(sch_1):sgpio_di_0';
NODE_NAME     GF1 B31
 '@SCM_LIB.SCM(SCH_1):PAGE10_I553@PURE_QUANTA.FCONN168_ME1016810202011_SCM(CHIPS)':
 'SGPIO0_DI': CDS_PINID='SGPIO0_DI';
NODE_NAME     R78 2
 '@SCM_LIB.SCM(SCH_1):PAGE11_I129@PURE_QUANTA.Q_RES(CHIPS)':
 'B': CDS_PINID='B';
NODE_NAME     R437 2
 '@SCM_LIB.SCM(SCH_1):PAGE34_I163@PURE_QUANTA.Q_RES(CHIPS)':
 'B': CDS_PINID='B';
NET_NAME
'SGPIO_DI_1'
 '@SCM_LIB.SCM(SCH_1):SGPIO_DI_1':
 C_SIGNAL='@scm_lib.scm(sch_1):sgpio_di_1';
NODE_NAME     GF1 B36
 '@SCM_LIB.SCM(SCH_1):PAGE10_I553@PURE_QUANTA.FCONN168_ME1016810202011_SCM(CHIPS)':
 'SGPIO1_DI': CDS_PINID='SGPIO1_DI';
NODE_NAME     R74 2
 '@SCM_LIB.SCM(SCH_1):PAGE11_I117@PURE_QUANTA.Q_RES(CHIPS)':
 'B': CDS_PINID='B';
NODE_NAME     R433 1
 '@SCM_LIB.SCM(SCH_1):PAGE12_I382@PURE_QUANTA.Q_RES(CHIPS)':
 'A': CDS_PINID='A';
NET_NAME
'SGPIO_DO_0'
 '@SCM_LIB.SCM(SCH_1):SGPIO_DO_0':
 C_SIGNAL='@scm_lib.scm(sch_1):sgpio_do_0';
NODE_NAME     GF1 B29
 '@SCM_LIB.SCM(SCH_1):PAGE10_I553@PURE_QUANTA.FCONN168_ME1016810202011_SCM(CHIPS)':
 'SGPIO0_DO': CDS_PINID='SGPIO0_DO';
NODE_NAME     R79 2
 '@SCM_LIB.SCM(SCH_1):PAGE11_I130@PURE_QUANTA.Q_RES(CHIPS)':
 'B': CDS_PINID='B';
NODE_NAME     R435 2
 '@SCM_LIB.SCM(SCH_1):PAGE34_I161@PURE_QUANTA.Q_RES(CHIPS)':
 'B': CDS_PINID='B';
NET_NAME
'SGPIO_DO_1'
 '@SCM_LIB.SCM(SCH_1):SGPIO_DO_1':
 C_SIGNAL='@scm_lib.scm(sch_1):sgpio_do_1';
NODE_NAME     GF1 B34
 '@SCM_LIB.SCM(SCH_1):PAGE10_I553@PURE_QUANTA.FCONN168_ME1016810202011_SCM(CHIPS)':
 'SGPIO1_DO': CDS_PINID='SGPIO1_DO';
NODE_NAME     R75 2
 '@SCM_LIB.SCM(SCH_1):PAGE11_I110@PURE_QUANTA.Q_RES(CHIPS)':
 'B': CDS_PINID='B';
NODE_NAME     R151 1
 '@SCM_LIB.SCM(SCH_1):PAGE12_I381@PURE_QUANTA.Q_RES(CHIPS)':
 'A': CDS_PINID='A';
NET_NAME
'SGPIO_LD_0'
 '@SCM_LIB.SCM(SCH_1):SGPIO_LD_0':
 C_SIGNAL='@scm_lib.scm(sch_1):sgpio_ld_0';
NODE_NAME     GF1 B32
 '@SCM_LIB.SCM(SCH_1):PAGE10_I553@PURE_QUANTA.FCONN168_ME1016810202011_SCM(CHIPS)':
 'SGPIO0_LD': CDS_PINID='SGPIO0_LD';
NODE_NAME     R77 2
 '@SCM_LIB.SCM(SCH_1):PAGE11_I128@PURE_QUANTA.Q_RES(CHIPS)':
 'B': CDS_PINID='B';
NODE_NAME     R436 2
 '@SCM_LIB.SCM(SCH_1):PAGE34_I162@PURE_QUANTA.Q_RES(CHIPS)':
 'B': CDS_PINID='B';
NET_NAME
'SGPIO_LD_1'
 '@SCM_LIB.SCM(SCH_1):SGPIO_LD_1':
 C_SIGNAL='@scm_lib.scm(sch_1):sgpio_ld_1';
NODE_NAME     GF1 B37
 '@SCM_LIB.SCM(SCH_1):PAGE10_I553@PURE_QUANTA.FCONN168_ME1016810202011_SCM(CHIPS)':
 'SGPIO1_LD': CDS_PINID='SGPIO1_LD';
NODE_NAME     R73 2
 '@SCM_LIB.SCM(SCH_1):PAGE11_I118@PURE_QUANTA.Q_RES(CHIPS)':
 'B': CDS_PINID='B';
NODE_NAME     R150 1
 '@SCM_LIB.SCM(SCH_1):PAGE12_I380@PURE_QUANTA.Q_RES(CHIPS)':
 'A': CDS_PINID='A';
NET_NAME
'SGPIO_PLD_DI_0'
 '@SCM_LIB.SCM(SCH_1):SGPIO_PLD_DI_0':
 C_SIGNAL='@scm_lib.scm(sch_1):sgpio_pld_di_0';
NODE_NAME     U25 B14
 '@SCM_LIB.SCM(SCH_1):PAGE34_I1@PURE_QUANTA.LCMXO3LF2100C5BG256C(CHIPS)':
 'PT24A': CDS_PINID='PT24A';
NODE_NAME     R437 1
 '@SCM_LIB.SCM(SCH_1):PAGE34_I163@PURE_QUANTA.Q_RES(CHIPS)':
 'A': CDS_PINID='A';
NET_NAME
'SGPIO_PLD_DO_0'
 '@SCM_LIB.SCM(SCH_1):SGPIO_PLD_DO_0':
 C_SIGNAL='@scm_lib.scm(sch_1):sgpio_pld_do_0';
NODE_NAME     U25 C12
 '@SCM_LIB.SCM(SCH_1):PAGE34_I1@PURE_QUANTA.LCMXO3LF2100C5BG256C(CHIPS)':
 'PT23A': CDS_PINID='PT23A';
NODE_NAME     R435 1
 '@SCM_LIB.SCM(SCH_1):PAGE34_I161@PURE_QUANTA.Q_RES(CHIPS)':
 'A': CDS_PINID='A';
NET_NAME
'SGPIO_PLD_LD_0'
 '@SCM_LIB.SCM(SCH_1):SGPIO_PLD_LD_0':
 C_SIGNAL='@scm_lib.scm(sch_1):sgpio_pld_ld_0';
NODE_NAME     U25 B12
 '@SCM_LIB.SCM(SCH_1):PAGE34_I1@PURE_QUANTA.LCMXO3LF2100C5BG256C(CHIPS)':
 'PT23B': CDS_PINID='PT23B';
NODE_NAME     R436 1
 '@SCM_LIB.SCM(SCH_1):PAGE34_I162@PURE_QUANTA.Q_RES(CHIPS)':
 'A': CDS_PINID='A';
NET_NAME
'SMB_BMC_ALERT10_N'
 '@SCM_LIB.SCM(SCH_1):SMB_BMC_ALERT10_N':
 C_SIGNAL='@scm_lib.scm(sch_1):smb_bmc_alert10_n';
NODE_NAME     R449 1
 '@SCM_LIB.SCM(SCH_1):PAGE15_I321@PURE_QUANTA.Q_RES(CHIPS)':
 'A': CDS_PINID='A';
NODE_NAME     R843 2
 '@SCM_LIB.SCM(SCH_1):PAGE27_I177@PURE_QUANTA.Q_RES(CHIPS)':
 'B': CDS_PINID='B';
NODE_NAME     R457 1
 '@SCM_LIB.SCM(SCH_1):PAGE35_I5@PURE_QUANTA.Q_RES(CHIPS)':
 'A': CDS_PINID='A';
NET_NAME
'SMB_BMC_ALERT10_R1_N'
 '@SCM_LIB.SCM(SCH_1):SMB_BMC_ALERT10_R1_N':
 C_SIGNAL='@scm_lib.scm(sch_1):smb_bmc_alert10_r1_n';
NODE_NAME     U25 G12
 '@SCM_LIB.SCM(SCH_1):PAGE35_I1@PURE_QUANTA.LCMXO3LF2100C5BG256C(CHIPS)':
 'PR3D': CDS_PINID='PR3D';
NODE_NAME     R457 2
 '@SCM_LIB.SCM(SCH_1):PAGE35_I5@PURE_QUANTA.Q_RES(CHIPS)':
 'B': CDS_PINID='B';
NET_NAME
'SMB_BMC_ALERT10_R_N'
 '@SCM_LIB.SCM(SCH_1):SMB_BMC_ALERT10_R_N':
 C_SIGNAL='@scm_lib.scm(sch_1):smb_bmc_alert10_r_n';
NODE_NAME     R449 2
 '@SCM_LIB.SCM(SCH_1):PAGE15_I321@PURE_QUANTA.Q_RES(CHIPS)':
 'B': CDS_PINID='B';
NODE_NAME     U5 AA17
 '@SCM_LIB.SCM(SCH_1):PAGE15_I350@PURE_QUANTA.AST2600A3GP(CHIPS)':
 'ADC9||GPIU1||SALT10': CDS_PINID='\adc9||gpiu1||salt10\';
NET_NAME
'SMB_BMC_ALERT12_N'
 '@SCM_LIB.SCM(SCH_1):SMB_BMC_ALERT12_N':
 C_SIGNAL='@scm_lib.scm(sch_1):smb_bmc_alert12_n';
NODE_NAME     U5 AE16
 '@SCM_LIB.SCM(SCH_1):PAGE15_I350@PURE_QUANTA.AST2600A3GP(CHIPS)':
 'ADC11||GPIU3||SALT12': CDS_PINID='\adc11||gpiu3||salt12\';
NODE_NAME     R844 2
 '@SCM_LIB.SCM(SCH_1):PAGE27_I179@PURE_QUANTA.Q_RES(CHIPS)':
 'B': CDS_PINID='B';
NODE_NAME     U25 L14
 '@SCM_LIB.SCM(SCH_1):PAGE35_I1@PURE_QUANTA.LCMXO3LF2100C5BG256C(CHIPS)':
 'PR11B': CDS_PINID='PR11B';
NET_NAME
'SMB_BMC_ALERT15_N'
 '@SCM_LIB.SCM(SCH_1):SMB_BMC_ALERT15_N':
 C_SIGNAL='@scm_lib.scm(sch_1):smb_bmc_alert15_n';
NODE_NAME     U5 D21
 '@SCM_LIB.SCM(SCH_1):PAGE12_I436@PURE_QUANTA.AST2600A3GP(CHIPS)':
 'GPIOG6||TXD9||SD2CD#||SALT15': CDS_PINID='\gpiog6||txd9||sd2cd#||salt15\';
NODE_NAME     R851 2
 '@SCM_LIB.SCM(SCH_1):PAGE27_I184@PURE_QUANTA.Q_RES(CHIPS)':
 'B': CDS_PINID='B';
NET_NAME
'SMB_BMC_ALERT16_N'
 '@SCM_LIB.SCM(SCH_1):SMB_BMC_ALERT16_N':
 C_SIGNAL='@scm_lib.scm(sch_1):smb_bmc_alert16_n';
NODE_NAME     U5 AC17
 '@SCM_LIB.SCM(SCH_1):PAGE15_I350@PURE_QUANTA.AST2600A3GP(CHIPS)':
 'ADC15||GPIU7||SALT16': CDS_PINID='\adc15||gpiu7||salt16\';
NODE_NAME     R848 2
 '@SCM_LIB.SCM(SCH_1):PAGE27_I182@PURE_QUANTA.Q_RES(CHIPS)':
 'B': CDS_PINID='B';
NODE_NAME     R574 1
 '@SCM_LIB.SCM(SCH_1):PAGE35_I76@PURE_QUANTA.Q_RES(CHIPS)':
 'A': CDS_PINID='A';
NODE_NAME     R54 2
 '@SCM_LIB.SCM(SCH_1):PAGE26_I65@PURE_QUANTA.Q_RES(CHIPS)':
 'B': CDS_PINID='B';
NET_NAME
'SMB_BMC_ALERT16_R2_N'
 '@SCM_LIB.SCM(SCH_1):SMB_BMC_ALERT16_R2_N':
 C_SIGNAL='@scm_lib.scm(sch_1):smb_bmc_alert16_r2_n';
NODE_NAME     U25 R16
 '@SCM_LIB.SCM(SCH_1):PAGE35_I1@PURE_QUANTA.LCMXO3LF2100C5BG256C(CHIPS)':
 'PR14D': CDS_PINID='PR14D';
NODE_NAME     R574 2
 '@SCM_LIB.SCM(SCH_1):PAGE35_I76@PURE_QUANTA.Q_RES(CHIPS)':
 'B': CDS_PINID='B';
NET_NAME
'SMB_BMC_ALERT16_R_N'
 '@SCM_LIB.SCM(SCH_1):SMB_BMC_ALERT16_R_N':
 C_SIGNAL='@scm_lib.scm(sch_1):smb_bmc_alert16_r_n';
NODE_NAME     R54 1
 '@SCM_LIB.SCM(SCH_1):PAGE26_I65@PURE_QUANTA.Q_RES(CHIPS)':
 'A': CDS_PINID='A';
NODE_NAME     J14 6
 '@SCM_LIB.SCM(SCH_1):PAGE26_I71@PURE_QUANTA.CONN8_TSW10407FD(CHIPS)':
 '6': CDS_PINID='\6\';
NET_NAME
'SMB_BMC_ALERT3_N'
 '@SCM_LIB.SCM(SCH_1):SMB_BMC_ALERT3_N':
 C_SIGNAL='@scm_lib.scm(sch_1):smb_bmc_alert3_n';
NODE_NAME     R442 1
 '@SCM_LIB.SCM(SCH_1):PAGE13_I301@PURE_QUANTA.Q_RES(CHIPS)':
 'A': CDS_PINID='A';
NODE_NAME     R268 2
 '@SCM_LIB.SCM(SCH_1):PAGE27_I86@PURE_QUANTA.Q_RES(CHIPS)':
 'B': CDS_PINID='B';
NODE_NAME     R453 1
 '@SCM_LIB.SCM(SCH_1):PAGE35_I2@PURE_QUANTA.Q_RES(CHIPS)':
 'A': CDS_PINID='A';
NET_NAME
'SMB_BMC_ALERT3_R1_N'
 '@SCM_LIB.SCM(SCH_1):SMB_BMC_ALERT3_R1_N':
 C_SIGNAL='@scm_lib.scm(sch_1):smb_bmc_alert3_r1_n';
NODE_NAME     U25 C16
 '@SCM_LIB.SCM(SCH_1):PAGE35_I1@PURE_QUANTA.LCMXO3LF2100C5BG256C(CHIPS)':
 'PR2C': CDS_PINID='PR2C';
NODE_NAME     R453 2
 '@SCM_LIB.SCM(SCH_1):PAGE35_I2@PURE_QUANTA.Q_RES(CHIPS)':
 'B': CDS_PINID='B';
NET_NAME
'SMB_BMC_ALERT3_R_N'
 '@SCM_LIB.SCM(SCH_1):SMB_BMC_ALERT3_R_N':
 C_SIGNAL='@scm_lib.scm(sch_1):smb_bmc_alert3_r_n';
NODE_NAME     R442 2
 '@SCM_LIB.SCM(SCH_1):PAGE13_I301@PURE_QUANTA.Q_RES(CHIPS)':
 'B': CDS_PINID='B';
NODE_NAME     U5 H26
 '@SCM_LIB.SCM(SCH_1):PAGE13_I363@PURE_QUANTA.AST2600A3GP(CHIPS)':
 'GPIOB2||SALT3': CDS_PINID='\gpiob2||salt3\';
NET_NAME
'SMB_BMC_ALERT4_N'
 '@SCM_LIB.SCM(SCH_1):SMB_BMC_ALERT4_N':
 C_SIGNAL='@scm_lib.scm(sch_1):smb_bmc_alert4_n';
NODE_NAME     R443 1
 '@SCM_LIB.SCM(SCH_1):PAGE13_I300@PURE_QUANTA.Q_RES(CHIPS)':
 'A': CDS_PINID='A';
NODE_NAME     R269 2
 '@SCM_LIB.SCM(SCH_1):PAGE27_I84@PURE_QUANTA.Q_RES(CHIPS)':
 'B': CDS_PINID='B';
NODE_NAME     R454 1
 '@SCM_LIB.SCM(SCH_1):PAGE35_I3@PURE_QUANTA.Q_RES(CHIPS)':
 'A': CDS_PINID='A';
NET_NAME
'SMB_BMC_ALERT4_R1_N'
 '@SCM_LIB.SCM(SCH_1):SMB_BMC_ALERT4_R1_N':
 C_SIGNAL='@scm_lib.scm(sch_1):smb_bmc_alert4_r1_n';
NODE_NAME     U25 D15
 '@SCM_LIB.SCM(SCH_1):PAGE35_I1@PURE_QUANTA.LCMXO3LF2100C5BG256C(CHIPS)':
 'PR2D': CDS_PINID='PR2D';
NODE_NAME     R454 2
 '@SCM_LIB.SCM(SCH_1):PAGE35_I3@PURE_QUANTA.Q_RES(CHIPS)':
 'B': CDS_PINID='B';
NET_NAME
'SMB_BMC_ALERT4_R_N'
 '@SCM_LIB.SCM(SCH_1):SMB_BMC_ALERT4_R_N':
 C_SIGNAL='@scm_lib.scm(sch_1):smb_bmc_alert4_r_n';
NODE_NAME     R443 2
 '@SCM_LIB.SCM(SCH_1):PAGE13_I300@PURE_QUANTA.Q_RES(CHIPS)':
 'B': CDS_PINID='B';
NODE_NAME     U5 J25
 '@SCM_LIB.SCM(SCH_1):PAGE13_I363@PURE_QUANTA.AST2600A3GP(CHIPS)':
 'GPIOB3||SALT4': CDS_PINID='\gpiob3||salt4\';
NET_NAME
'SMB_BMC_ALERT9_N'
 '@SCM_LIB.SCM(SCH_1):SMB_BMC_ALERT9_N':
 C_SIGNAL='@scm_lib.scm(sch_1):smb_bmc_alert9_n';
NODE_NAME     R448 1
 '@SCM_LIB.SCM(SCH_1):PAGE15_I320@PURE_QUANTA.Q_RES(CHIPS)':
 'A': CDS_PINID='A';
NODE_NAME     R842 2
 '@SCM_LIB.SCM(SCH_1):PAGE27_I168@PURE_QUANTA.Q_RES(CHIPS)':
 'B': CDS_PINID='B';
NODE_NAME     R456 1
 '@SCM_LIB.SCM(SCH_1):PAGE35_I4@PURE_QUANTA.Q_RES(CHIPS)':
 'A': CDS_PINID='A';
NET_NAME
'SMB_BMC_ALERT9_R1_N'
 '@SCM_LIB.SCM(SCH_1):SMB_BMC_ALERT9_R1_N':
 C_SIGNAL='@scm_lib.scm(sch_1):smb_bmc_alert9_r1_n';
NODE_NAME     U25 F13
 '@SCM_LIB.SCM(SCH_1):PAGE35_I1@PURE_QUANTA.LCMXO3LF2100C5BG256C(CHIPS)':
 'PR3C': CDS_PINID='PR3C';
NODE_NAME     R456 2
 '@SCM_LIB.SCM(SCH_1):PAGE35_I4@PURE_QUANTA.Q_RES(CHIPS)':
 'B': CDS_PINID='B';
NET_NAME
'SMB_BMC_ALERT9_R_N'
 '@SCM_LIB.SCM(SCH_1):SMB_BMC_ALERT9_R_N':
 C_SIGNAL='@scm_lib.scm(sch_1):smb_bmc_alert9_r_n';
NODE_NAME     R448 2
 '@SCM_LIB.SCM(SCH_1):PAGE15_I320@PURE_QUANTA.Q_RES(CHIPS)':
 'B': CDS_PINID='B';
NODE_NAME     U5 AB16
 '@SCM_LIB.SCM(SCH_1):PAGE15_I350@PURE_QUANTA.AST2600A3GP(CHIPS)':
 'ADC8||GPIU0||SALT9': CDS_PINID='\adc8||gpiu0||salt9\';
NET_NAME
'SMB_BMC_MM10_R_SCL'
 '@SCM_LIB.SCM(SCH_1):SMB_BMC_MM10_R_SCL':
 C_SIGNAL='@scm_lib.scm(sch_1):smb_bmc_mm10_r_scl';
NODE_NAME     R583 1
 '@SCM_LIB.SCM(SCH_1):PAGE12_I319@PURE_QUANTA.Q_RES(CHIPS)':
 'A': CDS_PINID='A';
NODE_NAME     U5 E15
 '@SCM_LIB.SCM(SCH_1):PAGE12_I436@PURE_QUANTA.AST2600A3GP(CHIPS)':
 'GPIOL2||SCL10': CDS_PINID='\gpiol2||scl10\';
NET_NAME
'SMB_BMC_MM10_R_SDA'
 '@SCM_LIB.SCM(SCH_1):SMB_BMC_MM10_R_SDA':
 C_SIGNAL='@scm_lib.scm(sch_1):smb_bmc_mm10_r_sda';
NODE_NAME     R584 1
 '@SCM_LIB.SCM(SCH_1):PAGE12_I320@PURE_QUANTA.Q_RES(CHIPS)':
 'A': CDS_PINID='A';
NODE_NAME     U5 A13
 '@SCM_LIB.SCM(SCH_1):PAGE12_I436@PURE_QUANTA.AST2600A3GP(CHIPS)':
 'GPIOL3||SDA10': CDS_PINID='\gpiol3||sda10\';
NET_NAME
'SMB_BMC_MM10_SCL'
 '@SCM_LIB.SCM(SCH_1):SMB_BMC_MM10_SCL':
 C_SIGNAL='@scm_lib.scm(sch_1):smb_bmc_mm10_scl';
NODE_NAME     GF1 A31
 '@SCM_LIB.SCM(SCH_1):PAGE10_I553@PURE_QUANTA.FCONN168_ME1016810202011_SCM(CHIPS)':
 'I2C_10_SCL': CDS_PINID='I2C_10_SCL';
NODE_NAME     R583 2
 '@SCM_LIB.SCM(SCH_1):PAGE12_I319@PURE_QUANTA.Q_RES(CHIPS)':
 'B': CDS_PINID='B';
NODE_NAME     R262 2
 '@SCM_LIB.SCM(SCH_1):PAGE27_I93@PURE_QUANTA.Q_RES(CHIPS)':
 'B': CDS_PINID='B';
NET_NAME
'SMB_BMC_MM10_SDA'
 '@SCM_LIB.SCM(SCH_1):SMB_BMC_MM10_SDA':
 C_SIGNAL='@scm_lib.scm(sch_1):smb_bmc_mm10_sda';
NODE_NAME     GF1 A32
 '@SCM_LIB.SCM(SCH_1):PAGE10_I553@PURE_QUANTA.FCONN168_ME1016810202011_SCM(CHIPS)':
 'I2C_10_SDA': CDS_PINID='I2C_10_SDA';
NODE_NAME     R584 2
 '@SCM_LIB.SCM(SCH_1):PAGE12_I320@PURE_QUANTA.Q_RES(CHIPS)':
 'B': CDS_PINID='B';
NODE_NAME     R521 2
 '@SCM_LIB.SCM(SCH_1):PAGE27_I234@PURE_QUANTA.Q_RES(CHIPS)':
 'B': CDS_PINID='B';
NET_NAME
'SMB_BMC_MM12_R_SCL'
 '@SCM_LIB.SCM(SCH_1):SMB_BMC_MM12_R_SCL':
 C_SIGNAL='@scm_lib.scm(sch_1):smb_bmc_mm12_r_scl';
NODE_NAME     R137 1
 '@SCM_LIB.SCM(SCH_1):PAGE12_I385@PURE_QUANTA.Q_RES(CHIPS)':
 'A': CDS_PINID='A';
NODE_NAME     U5 L26
 '@SCM_LIB.SCM(SCH_1):PAGE12_I436@PURE_QUANTA.AST2600A3GP(CHIPS)':
 'GPIOA2||SCL12||MDC4': CDS_PINID='\gpioa2||scl12||mdc4\';
NET_NAME
'SMB_BMC_MM12_R_SDA'
 '@SCM_LIB.SCM(SCH_1):SMB_BMC_MM12_R_SDA':
 C_SIGNAL='@scm_lib.scm(sch_1):smb_bmc_mm12_r_sda';
NODE_NAME     R144 1
 '@SCM_LIB.SCM(SCH_1):PAGE12_I386@PURE_QUANTA.Q_RES(CHIPS)':
 'A': CDS_PINID='A';
NODE_NAME     U5 K24
 '@SCM_LIB.SCM(SCH_1):PAGE12_I436@PURE_QUANTA.AST2600A3GP(CHIPS)':
 'GPIOA3||SDA12||MDIO4': CDS_PINID='\gpioa3||sda12||mdio4\';
NET_NAME
'SMB_BMC_MM12_SCL'
 '@SCM_LIB.SCM(SCH_1):SMB_BMC_MM12_SCL':
 C_SIGNAL='@scm_lib.scm(sch_1):smb_bmc_mm12_scl';
NODE_NAME     GF1 A38
 '@SCM_LIB.SCM(SCH_1):PAGE10_I553@PURE_QUANTA.FCONN168_ME1016810202011_SCM(CHIPS)':
 'I2C_11_SCL': CDS_PINID='I2C_11_SCL';
NODE_NAME     R137 2
 '@SCM_LIB.SCM(SCH_1):PAGE12_I385@PURE_QUANTA.Q_RES(CHIPS)':
 'B': CDS_PINID='B';
NODE_NAME     R145 2
 '@SCM_LIB.SCM(SCH_1):PAGE27_I235@PURE_QUANTA.Q_RES(CHIPS)':
 'B': CDS_PINID='B';
NET_NAME
'SMB_BMC_MM12_SDA'
 '@SCM_LIB.SCM(SCH_1):SMB_BMC_MM12_SDA':
 C_SIGNAL='@scm_lib.scm(sch_1):smb_bmc_mm12_sda';
NODE_NAME     GF1 A39
 '@SCM_LIB.SCM(SCH_1):PAGE10_I553@PURE_QUANTA.FCONN168_ME1016810202011_SCM(CHIPS)':
 'I2C_11_SDA': CDS_PINID='I2C_11_SDA';
NODE_NAME     R144 2
 '@SCM_LIB.SCM(SCH_1):PAGE12_I386@PURE_QUANTA.Q_RES(CHIPS)':
 'B': CDS_PINID='B';
NODE_NAME     R149 2
 '@SCM_LIB.SCM(SCH_1):PAGE27_I236@PURE_QUANTA.Q_RES(CHIPS)':
 'B': CDS_PINID='B';
NET_NAME
'SMB_BMC_MM13_R_SCL'
 '@SCM_LIB.SCM(SCH_1):SMB_BMC_MM13_R_SCL':
 C_SIGNAL='@scm_lib.scm(sch_1):smb_bmc_mm13_r_scl';
NODE_NAME     R423 1
 '@SCM_LIB.SCM(SCH_1):PAGE12_I252@PURE_QUANTA.Q_RES(CHIPS)':
 'A': CDS_PINID='A';
NODE_NAME     R817 1
 '@SCM_LIB.SCM(SCH_1):PAGE12_I393@PURE_QUANTA.Q_RES(CHIPS)':
 'A': CDS_PINID='A';
NODE_NAME     U5 K26
 '@SCM_LIB.SCM(SCH_1):PAGE12_I436@PURE_QUANTA.AST2600A3GP(CHIPS)':
 'GPIOA4||MAC1LINK||SCL13||SGPM2CK||SGPS2CK': CDS_PINID='\gpioa4||mac1link||scl13||sgpm2ck||sgps2ck\';
NET_NAME
'SMB_BMC_MM13_R_SDA'
 '@SCM_LIB.SCM(SCH_1):SMB_BMC_MM13_R_SDA':
 C_SIGNAL='@scm_lib.scm(sch_1):smb_bmc_mm13_r_sda';
NODE_NAME     R424 1
 '@SCM_LIB.SCM(SCH_1):PAGE12_I253@PURE_QUANTA.Q_RES(CHIPS)':
 'A': CDS_PINID='A';
NODE_NAME     R818 1
 '@SCM_LIB.SCM(SCH_1):PAGE12_I392@PURE_QUANTA.Q_RES(CHIPS)':
 'A': CDS_PINID='A';
NODE_NAME     U5 L24
 '@SCM_LIB.SCM(SCH_1):PAGE12_I436@PURE_QUANTA.AST2600A3GP(CHIPS)':
 'GPIOA5||MAC2LINK||SDA13||SGPM2LD||SGPS2LD': CDS_PINID='\gpioa5||mac2link||sda13||sgpm2ld||sgps2ld\';
NET_NAME
'SMB_BMC_MM13_SCL'
 '@SCM_LIB.SCM(SCH_1):SMB_BMC_MM13_SCL':
 C_SIGNAL='@scm_lib.scm(sch_1):smb_bmc_mm13_scl';
NODE_NAME     GF1 A40
 '@SCM_LIB.SCM(SCH_1):PAGE10_I553@PURE_QUANTA.FCONN168_ME1016810202011_SCM(CHIPS)':
 'I2C_12_SCL': CDS_PINID='I2C_12_SCL';
NODE_NAME     R423 2
 '@SCM_LIB.SCM(SCH_1):PAGE12_I252@PURE_QUANTA.Q_RES(CHIPS)':
 'B': CDS_PINID='B';
NODE_NAME     R422 2
 '@SCM_LIB.SCM(SCH_1):PAGE27_I239@PURE_QUANTA.Q_RES(CHIPS)':
 'B': CDS_PINID='B';
NET_NAME
'SMB_BMC_MM13_SDA'
 '@SCM_LIB.SCM(SCH_1):SMB_BMC_MM13_SDA':
 C_SIGNAL='@scm_lib.scm(sch_1):smb_bmc_mm13_sda';
NODE_NAME     GF1 A41
 '@SCM_LIB.SCM(SCH_1):PAGE10_I553@PURE_QUANTA.FCONN168_ME1016810202011_SCM(CHIPS)':
 'I2C_12_SDA': CDS_PINID='I2C_12_SDA';
NODE_NAME     R424 2
 '@SCM_LIB.SCM(SCH_1):PAGE12_I253@PURE_QUANTA.Q_RES(CHIPS)':
 'B': CDS_PINID='B';
NODE_NAME     R428 2
 '@SCM_LIB.SCM(SCH_1):PAGE27_I240@PURE_QUANTA.Q_RES(CHIPS)':
 'B': CDS_PINID='B';
NET_NAME
'SMB_BMC_MM14_R1_SCL'
 '@SCM_LIB.SCM(SCH_1):SMB_BMC_MM14_R1_SCL':
 C_SIGNAL='@scm_lib.scm(sch_1):smb_bmc_mm14_r1_scl';
NODE_NAME     R36 2
 '@SCM_LIB.SCM(SCH_1):PAGE10_I458@PURE_QUANTA.Q_RES(CHIPS)':
 'B': CDS_PINID='B';
NODE_NAME     GF1 A1
 '@SCM_LIB.SCM(SCH_1):PAGE10_I553@PURE_QUANTA.FCONN168_ME1016810202011_SCM(CHIPS)':
 'I2C_0_SCL': CDS_PINID='I2C_0_SCL';
NET_NAME
'SMB_BMC_MM14_R1_SDA'
 '@SCM_LIB.SCM(SCH_1):SMB_BMC_MM14_R1_SDA':
 C_SIGNAL='@scm_lib.scm(sch_1):smb_bmc_mm14_r1_sda';
NODE_NAME     R46 2
 '@SCM_LIB.SCM(SCH_1):PAGE10_I459@PURE_QUANTA.Q_RES(CHIPS)':
 'B': CDS_PINID='B';
NODE_NAME     GF1 A2
 '@SCM_LIB.SCM(SCH_1):PAGE10_I553@PURE_QUANTA.FCONN168_ME1016810202011_SCM(CHIPS)':
 'I2C_0_SDA': CDS_PINID='I2C_0_SDA';
NET_NAME
'SMB_BMC_MM14_R_SCL'
 '@SCM_LIB.SCM(SCH_1):SMB_BMC_MM14_R_SCL':
 C_SIGNAL='@scm_lib.scm(sch_1):smb_bmc_mm14_r_scl';
NODE_NAME     R425 1
 '@SCM_LIB.SCM(SCH_1):PAGE12_I254@PURE_QUANTA.Q_RES(CHIPS)':
 'A': CDS_PINID='A';
NODE_NAME     R819 1
 '@SCM_LIB.SCM(SCH_1):PAGE12_I391@PURE_QUANTA.Q_RES(CHIPS)':
 'A': CDS_PINID='A';
NODE_NAME     U5 L23
 '@SCM_LIB.SCM(SCH_1):PAGE12_I436@PURE_QUANTA.AST2600A3GP(CHIPS)':
 'GPIOA6||MAC3LINK||SCL14||SGPM2O||SGPS2I0': CDS_PINID='\gpioa6||mac3link||scl14||sgpm2o||sgps2i0\';
NET_NAME
'SMB_BMC_MM14_R_SDA'
 '@SCM_LIB.SCM(SCH_1):SMB_BMC_MM14_R_SDA':
 C_SIGNAL='@scm_lib.scm(sch_1):smb_bmc_mm14_r_sda';
NODE_NAME     R426 1
 '@SCM_LIB.SCM(SCH_1):PAGE12_I255@PURE_QUANTA.Q_RES(CHIPS)':
 'A': CDS_PINID='A';
NODE_NAME     R820 1
 '@SCM_LIB.SCM(SCH_1):PAGE12_I390@PURE_QUANTA.Q_RES(CHIPS)':
 'A': CDS_PINID='A';
NODE_NAME     U5 K25
 '@SCM_LIB.SCM(SCH_1):PAGE12_I436@PURE_QUANTA.AST2600A3GP(CHIPS)':
 'GPIOA7||MAC4LINK||SDA14||SGPM2I||SGPS2I1': CDS_PINID='\gpioa7||mac4link||sda14||sgpm2i||sgps2i1\';
NET_NAME
'SMB_BMC_MM14_SCL'
 '@SCM_LIB.SCM(SCH_1):SMB_BMC_MM14_SCL':
 C_SIGNAL='@scm_lib.scm(sch_1):smb_bmc_mm14_scl';
NODE_NAME     R36 1
 '@SCM_LIB.SCM(SCH_1):PAGE10_I458@PURE_QUANTA.Q_RES(CHIPS)':
 'A': CDS_PINID='A';
NODE_NAME     R425 2
 '@SCM_LIB.SCM(SCH_1):PAGE12_I254@PURE_QUANTA.Q_RES(CHIPS)':
 'B': CDS_PINID='B';
NODE_NAME     R429 2
 '@SCM_LIB.SCM(SCH_1):PAGE27_I241@PURE_QUANTA.Q_RES(CHIPS)':
 'B': CDS_PINID='B';
NET_NAME
'SMB_BMC_MM14_SDA'
 '@SCM_LIB.SCM(SCH_1):SMB_BMC_MM14_SDA':
 C_SIGNAL='@scm_lib.scm(sch_1):smb_bmc_mm14_sda';
NODE_NAME     R46 1
 '@SCM_LIB.SCM(SCH_1):PAGE10_I459@PURE_QUANTA.Q_RES(CHIPS)':
 'A': CDS_PINID='A';
NODE_NAME     R426 2
 '@SCM_LIB.SCM(SCH_1):PAGE12_I255@PURE_QUANTA.Q_RES(CHIPS)':
 'B': CDS_PINID='B';
NODE_NAME     R438 2
 '@SCM_LIB.SCM(SCH_1):PAGE27_I242@PURE_QUANTA.Q_RES(CHIPS)':
 'B': CDS_PINID='B';
NET_NAME
'SMB_BMC_MM15_R1_SCL'
 '@SCM_LIB.SCM(SCH_1):SMB_BMC_MM15_R1_SCL':
 C_SIGNAL='@scm_lib.scm(sch_1):smb_bmc_mm15_r1_scl';
NODE_NAME     U37 2
 '@SCM_LIB.SCM(SCH_1):PAGE28_I99@PURE_QUANTA.PCA9517ADP(CHIPS)':
 'SCLA': CDS_PINID='SCLA';
NODE_NAME     R135 2
 '@SCM_LIB.SCM(SCH_1):PAGE28_I109@PURE_QUANTA.Q_RES(CHIPS)':
 'B': CDS_PINID='B';
NET_NAME
'SMB_BMC_MM15_R1_SDA'
 '@SCM_LIB.SCM(SCH_1):SMB_BMC_MM15_R1_SDA':
 C_SIGNAL='@scm_lib.scm(sch_1):smb_bmc_mm15_r1_sda';
NODE_NAME     U37 3
 '@SCM_LIB.SCM(SCH_1):PAGE28_I99@PURE_QUANTA.PCA9517ADP(CHIPS)':
 'SDAA': CDS_PINID='SDAA';
NODE_NAME     R294 2
 '@SCM_LIB.SCM(SCH_1):PAGE28_I108@PURE_QUANTA.Q_RES(CHIPS)':
 'B': CDS_PINID='B';
NET_NAME
'SMB_BMC_MM15_R_SCL'
 '@SCM_LIB.SCM(SCH_1):SMB_BMC_MM15_R_SCL':
 C_SIGNAL='@scm_lib.scm(sch_1):smb_bmc_mm15_r_scl';
NODE_NAME     R162 2
 '@SCM_LIB.SCM(SCH_1):PAGE12_I245@PURE_QUANTA.Q_RES(CHIPS)':
 'B': CDS_PINID='B';
NODE_NAME     U5 D18
 '@SCM_LIB.SCM(SCH_1):PAGE12_I436@PURE_QUANTA.AST2600A3GP(CHIPS)':
 'GPIOH4||SGPS1CK||SCL15': CDS_PINID='\gpioh4||sgps1ck||scl15\';
NET_NAME
'SMB_BMC_MM15_R_SDA'
 '@SCM_LIB.SCM(SCH_1):SMB_BMC_MM15_R_SDA':
 C_SIGNAL='@scm_lib.scm(sch_1):smb_bmc_mm15_r_sda';
NODE_NAME     R236 2
 '@SCM_LIB.SCM(SCH_1):PAGE12_I244@PURE_QUANTA.Q_RES(CHIPS)':
 'B': CDS_PINID='B';
NODE_NAME     U5 B17
 '@SCM_LIB.SCM(SCH_1):PAGE12_I436@PURE_QUANTA.AST2600A3GP(CHIPS)':
 'GPIOH5||SGPS1LD||SDA15': CDS_PINID='\gpioh5||sgps1ld||sda15\';
NET_NAME
'SMB_BMC_MM15_SCL'
 '@SCM_LIB.SCM(SCH_1):SMB_BMC_MM15_SCL':
 C_SIGNAL='@scm_lib.scm(sch_1):smb_bmc_mm15_scl';
NODE_NAME     R162 1
 '@SCM_LIB.SCM(SCH_1):PAGE12_I245@PURE_QUANTA.Q_RES(CHIPS)':
 'A': CDS_PINID='A';
NODE_NAME     R135 1
 '@SCM_LIB.SCM(SCH_1):PAGE28_I109@PURE_QUANTA.Q_RES(CHIPS)':
 'A': CDS_PINID='A';
NODE_NAME     R610 2
 '@SCM_LIB.SCM(SCH_1):PAGE27_I237@PURE_QUANTA.Q_RES(CHIPS)':
 'B': CDS_PINID='B';
NET_NAME
'SMB_BMC_MM15_SDA'
 '@SCM_LIB.SCM(SCH_1):SMB_BMC_MM15_SDA':
 C_SIGNAL='@scm_lib.scm(sch_1):smb_bmc_mm15_sda';
NODE_NAME     R236 1
 '@SCM_LIB.SCM(SCH_1):PAGE12_I244@PURE_QUANTA.Q_RES(CHIPS)':
 'A': CDS_PINID='A';
NODE_NAME     R294 1
 '@SCM_LIB.SCM(SCH_1):PAGE28_I108@PURE_QUANTA.Q_RES(CHIPS)':
 'A': CDS_PINID='A';
NODE_NAME     R692 2
 '@SCM_LIB.SCM(SCH_1):PAGE27_I238@PURE_QUANTA.Q_RES(CHIPS)':
 'B': CDS_PINID='B';
NET_NAME
'SMB_BMC_MM16_R1_SCL'
 '@SCM_LIB.SCM(SCH_1):SMB_BMC_MM16_R1_SCL':
 C_SIGNAL='@scm_lib.scm(sch_1):smb_bmc_mm16_r1_scl';
NODE_NAME     J4 40
 '@SCM_LIB.SCM(SCH_1):PAGE21_I84@PURE_QUANTA.SCONN67_NASA0S6730TS67(CHIPS)':
 '40': CDS_PINID='\40\';
NODE_NAME     R849 2
 '@SCM_LIB.SCM(SCH_1):PAGE21_I157@PURE_QUANTA.Q_RES(CHIPS)':
 'B': CDS_PINID='B';
NET_NAME
'SMB_BMC_MM16_R1_SDA'
 '@SCM_LIB.SCM(SCH_1):SMB_BMC_MM16_R1_SDA':
 C_SIGNAL='@scm_lib.scm(sch_1):smb_bmc_mm16_r1_sda';
NODE_NAME     J4 42
 '@SCM_LIB.SCM(SCH_1):PAGE21_I84@PURE_QUANTA.SCONN67_NASA0S6730TS67(CHIPS)':
 '42': CDS_PINID='\42\';
NODE_NAME     R850 2
 '@SCM_LIB.SCM(SCH_1):PAGE21_I156@PURE_QUANTA.Q_RES(CHIPS)':
 'B': CDS_PINID='B';
NET_NAME
'SMB_BMC_MM16_R2_SCL'
 '@SCM_LIB.SCM(SCH_1):SMB_BMC_MM16_R2_SCL':
 C_SIGNAL='@scm_lib.scm(sch_1):smb_bmc_mm16_r2_scl';
NODE_NAME     U19 6
 '@SCM_LIB.SCM(SCH_1):PAGE26_I15@PURE_QUANTA.M24128BWDW6TP(CHIPS)':
 'SCL': CDS_PINID='SCL';
NODE_NAME     R420 1
 '@SCM_LIB.SCM(SCH_1):PAGE26_I69@PURE_QUANTA.Q_RES(CHIPS)':
 'A': CDS_PINID='A';
NET_NAME
'SMB_BMC_MM16_R2_SDA'
 '@SCM_LIB.SCM(SCH_1):SMB_BMC_MM16_R2_SDA':
 C_SIGNAL='@scm_lib.scm(sch_1):smb_bmc_mm16_r2_sda';
NODE_NAME     U19 5
 '@SCM_LIB.SCM(SCH_1):PAGE26_I15@PURE_QUANTA.M24128BWDW6TP(CHIPS)':
 'SDA': CDS_PINID='SDA';
NODE_NAME     R421 1
 '@SCM_LIB.SCM(SCH_1):PAGE26_I33@PURE_QUANTA.Q_RES(CHIPS)':
 'A': CDS_PINID='A';
NET_NAME
'SMB_BMC_MM16_R3_SCL'
 '@SCM_LIB.SCM(SCH_1):SMB_BMC_MM16_R3_SCL':
 C_SIGNAL='@scm_lib.scm(sch_1):smb_bmc_mm16_r3_scl';
NODE_NAME     U25 A9
 '@SCM_LIB.SCM(SCH_1):PAGE34_I1@PURE_QUANTA.LCMXO3LF2100C5BG256C(CHIPS)':
 'PT18C||SCL||PCLKT0_0': CDS_PINID='\pt18c||scl||pclkt0_0\';
NODE_NAME     R272 1
 '@SCM_LIB.SCM(SCH_1):PAGE34_I165@PURE_QUANTA.Q_RES(CHIPS)':
 'A': CDS_PINID='A';
NET_NAME
'SMB_BMC_MM16_R3_SDA'
 '@SCM_LIB.SCM(SCH_1):SMB_BMC_MM16_R3_SDA':
 C_SIGNAL='@scm_lib.scm(sch_1):smb_bmc_mm16_r3_sda';
NODE_NAME     U25 C9
 '@SCM_LIB.SCM(SCH_1):PAGE34_I1@PURE_QUANTA.LCMXO3LF2100C5BG256C(CHIPS)':
 'PT18D||SDA||PCLKC0_0': CDS_PINID='\pt18d||sda||pclkc0_0\';
NODE_NAME     R303 1
 '@SCM_LIB.SCM(SCH_1):PAGE34_I166@PURE_QUANTA.Q_RES(CHIPS)':
 'A': CDS_PINID='A';
NET_NAME
'SMB_BMC_MM16_R4_SCL'
 '@SCM_LIB.SCM(SCH_1):SMB_BMC_MM16_R4_SCL':
 C_SIGNAL='@scm_lib.scm(sch_1):smb_bmc_mm16_r4_scl';
NODE_NAME     U25 T15
 '@SCM_LIB.SCM(SCH_1):PAGE36_I1@PURE_QUANTA.LCMXO3LF2100C5BG256C(CHIPS)':
 'PB25C': CDS_PINID='PB25C';
NODE_NAME     R105 1
 '@SCM_LIB.SCM(SCH_1):PAGE36_I58@PURE_QUANTA.Q_RES(CHIPS)':
 'A': CDS_PINID='A';
NET_NAME
'SMB_BMC_MM16_R4_SDA'
 '@SCM_LIB.SCM(SCH_1):SMB_BMC_MM16_R4_SDA':
 C_SIGNAL='@scm_lib.scm(sch_1):smb_bmc_mm16_r4_sda';
NODE_NAME     U25 R14
 '@SCM_LIB.SCM(SCH_1):PAGE36_I1@PURE_QUANTA.LCMXO3LF2100C5BG256C(CHIPS)':
 'PB25D': CDS_PINID='PB25D';
NODE_NAME     R114 1
 '@SCM_LIB.SCM(SCH_1):PAGE36_I57@PURE_QUANTA.Q_RES(CHIPS)':
 'A': CDS_PINID='A';
NET_NAME
'SMB_BMC_MM16_R5_SCL'
 '@SCM_LIB.SCM(SCH_1):SMB_BMC_MM16_R5_SCL':
 C_SIGNAL='@scm_lib.scm(sch_1):smb_bmc_mm16_r5_scl';
NODE_NAME     R47 2
 '@SCM_LIB.SCM(SCH_1):PAGE46_I106@PURE_QUANTA.Q_RES(CHIPS)':
 'B': CDS_PINID='B';
NODE_NAME     R105 2
 '@SCM_LIB.SCM(SCH_1):PAGE36_I58@PURE_QUANTA.Q_RES(CHIPS)':
 'B': CDS_PINID='B';
NODE_NAME     R849 1
 '@SCM_LIB.SCM(SCH_1):PAGE21_I157@PURE_QUANTA.Q_RES(CHIPS)':
 'A': CDS_PINID='A';
NODE_NAME     R879 1
 '@SCM_LIB.SCM(SCH_1):PAGE12_I510@PURE_QUANTA.Q_RES(CHIPS)':
 'A': CDS_PINID='A';
NODE_NAME     R272 2
 '@SCM_LIB.SCM(SCH_1):PAGE34_I165@PURE_QUANTA.Q_RES(CHIPS)':
 'B': CDS_PINID='B';
NET_NAME
'SMB_BMC_MM16_R5_SDA'
 '@SCM_LIB.SCM(SCH_1):SMB_BMC_MM16_R5_SDA':
 C_SIGNAL='@scm_lib.scm(sch_1):smb_bmc_mm16_r5_sda';
NODE_NAME     R33 1
 '@SCM_LIB.SCM(SCH_1):PAGE46_I117@PURE_QUANTA.Q_RES(CHIPS)':
 'A': CDS_PINID='A';
NODE_NAME     R114 2
 '@SCM_LIB.SCM(SCH_1):PAGE36_I57@PURE_QUANTA.Q_RES(CHIPS)':
 'B': CDS_PINID='B';
NODE_NAME     R850 1
 '@SCM_LIB.SCM(SCH_1):PAGE21_I156@PURE_QUANTA.Q_RES(CHIPS)':
 'A': CDS_PINID='A';
NODE_NAME     R880 1
 '@SCM_LIB.SCM(SCH_1):PAGE12_I458@PURE_QUANTA.Q_RES(CHIPS)':
 'A': CDS_PINID='A';
NODE_NAME     R303 2
 '@SCM_LIB.SCM(SCH_1):PAGE34_I166@PURE_QUANTA.Q_RES(CHIPS)':
 'B': CDS_PINID='B';
NET_NAME
'SMB_BMC_MM16_R_SCL'
 '@SCM_LIB.SCM(SCH_1):SMB_BMC_MM16_R_SCL':
 C_SIGNAL='@scm_lib.scm(sch_1):smb_bmc_mm16_r_scl';
NODE_NAME     R152 2
 '@SCM_LIB.SCM(SCH_1):PAGE12_I249@PURE_QUANTA.Q_RES(CHIPS)':
 'B': CDS_PINID='B';
NODE_NAME     U5 C17
 '@SCM_LIB.SCM(SCH_1):PAGE12_I436@PURE_QUANTA.AST2600A3GP(CHIPS)':
 'GPIOH6||SGPS1I0||SCL16': CDS_PINID='\gpioh6||sgps1i0||scl16\';
NET_NAME
'SMB_BMC_MM16_R_SDA'
 '@SCM_LIB.SCM(SCH_1):SMB_BMC_MM16_R_SDA':
 C_SIGNAL='@scm_lib.scm(sch_1):smb_bmc_mm16_r_sda';
NODE_NAME     R153 2
 '@SCM_LIB.SCM(SCH_1):PAGE12_I248@PURE_QUANTA.Q_RES(CHIPS)':
 'B': CDS_PINID='B';
NODE_NAME     U5 E18
 '@SCM_LIB.SCM(SCH_1):PAGE12_I436@PURE_QUANTA.AST2600A3GP(CHIPS)':
 'GPIOH7||SGPS1I1||SDA16': CDS_PINID='\gpioh7||sgps1i1||sda16\';
NET_NAME
'SMB_BMC_MM16_SCL'
 '@SCM_LIB.SCM(SCH_1):SMB_BMC_MM16_SCL':
 C_SIGNAL='@scm_lib.scm(sch_1):smb_bmc_mm16_scl';
NODE_NAME     R152 1
 '@SCM_LIB.SCM(SCH_1):PAGE12_I249@PURE_QUANTA.Q_RES(CHIPS)':
 'A': CDS_PINID='A';
NODE_NAME     R264 2
 '@SCM_LIB.SCM(SCH_1):PAGE27_I89@PURE_QUANTA.Q_RES(CHIPS)':
 'B': CDS_PINID='B';
NODE_NAME     R879 2
 '@SCM_LIB.SCM(SCH_1):PAGE12_I510@PURE_QUANTA.Q_RES(CHIPS)':
 'B': CDS_PINID='B';
NODE_NAME     R420 2
 '@SCM_LIB.SCM(SCH_1):PAGE26_I69@PURE_QUANTA.Q_RES(CHIPS)':
 'B': CDS_PINID='B';
NET_NAME
'SMB_BMC_MM16_SDA'
 '@SCM_LIB.SCM(SCH_1):SMB_BMC_MM16_SDA':
 C_SIGNAL='@scm_lib.scm(sch_1):smb_bmc_mm16_sda';
NODE_NAME     R153 1
 '@SCM_LIB.SCM(SCH_1):PAGE12_I248@PURE_QUANTA.Q_RES(CHIPS)':
 'A': CDS_PINID='A';
NODE_NAME     R421 2
 '@SCM_LIB.SCM(SCH_1):PAGE26_I33@PURE_QUANTA.Q_RES(CHIPS)':
 'B': CDS_PINID='B';
NODE_NAME     R265 2
 '@SCM_LIB.SCM(SCH_1):PAGE27_I88@PURE_QUANTA.Q_RES(CHIPS)':
 'B': CDS_PINID='B';
NODE_NAME     R880 2
 '@SCM_LIB.SCM(SCH_1):PAGE12_I458@PURE_QUANTA.Q_RES(CHIPS)':
 'B': CDS_PINID='B';
NET_NAME
'SMB_BMC_MM1_R_SCL'
 '@SCM_LIB.SCM(SCH_1):SMB_BMC_MM1_R_SCL':
 C_SIGNAL='@scm_lib.scm(sch_1):smb_bmc_mm1_r_scl';
NODE_NAME     R132 1
 '@SCM_LIB.SCM(SCH_1):PAGE12_I98@PURE_QUANTA.Q_RES(CHIPS)':
 'A': CDS_PINID='A';
NODE_NAME     U5 B20
 '@SCM_LIB.SCM(SCH_1):PAGE12_I436@PURE_QUANTA.AST2600A3GP(CHIPS)':
 'GPIOJ0||HVI3C3SCL||SCL1': CDS_PINID='\gpioj0||hvi3c3scl||scl1\';
NET_NAME
'SMB_BMC_MM1_R_SDA'
 '@SCM_LIB.SCM(SCH_1):SMB_BMC_MM1_R_SDA':
 C_SIGNAL='@scm_lib.scm(sch_1):smb_bmc_mm1_r_sda';
NODE_NAME     R133 1
 '@SCM_LIB.SCM(SCH_1):PAGE12_I97@PURE_QUANTA.Q_RES(CHIPS)':
 'A': CDS_PINID='A';
NODE_NAME     U5 A20
 '@SCM_LIB.SCM(SCH_1):PAGE12_I436@PURE_QUANTA.AST2600A3GP(CHIPS)':
 'GPIOJ1||HVI3C3SDA||SDA1': CDS_PINID='\gpioj1||hvi3c3sda||sda1\';
NET_NAME
'SMB_BMC_MM1_SCL'
 '@SCM_LIB.SCM(SCH_1):SMB_BMC_MM1_SCL':
 C_SIGNAL='@scm_lib.scm(sch_1):smb_bmc_mm1_scl';
NODE_NAME     GF1 A3
 '@SCM_LIB.SCM(SCH_1):PAGE10_I553@PURE_QUANTA.FCONN168_ME1016810202011_SCM(CHIPS)':
 'I2C_1_SCL': CDS_PINID='I2C_1_SCL';
NODE_NAME     R132 2
 '@SCM_LIB.SCM(SCH_1):PAGE12_I98@PURE_QUANTA.Q_RES(CHIPS)':
 'B': CDS_PINID='B';
NODE_NAME     R244 2
 '@SCM_LIB.SCM(SCH_1):PAGE27_I147@PURE_QUANTA.Q_RES(CHIPS)':
 'B': CDS_PINID='B';
NET_NAME
'SMB_BMC_MM1_SDA'
 '@SCM_LIB.SCM(SCH_1):SMB_BMC_MM1_SDA':
 C_SIGNAL='@scm_lib.scm(sch_1):smb_bmc_mm1_sda';
NODE_NAME     GF1 A4
 '@SCM_LIB.SCM(SCH_1):PAGE10_I553@PURE_QUANTA.FCONN168_ME1016810202011_SCM(CHIPS)':
 'I2C_1_SDA': CDS_PINID='I2C_1_SDA';
NODE_NAME     R133 2
 '@SCM_LIB.SCM(SCH_1):PAGE12_I97@PURE_QUANTA.Q_RES(CHIPS)':
 'B': CDS_PINID='B';
NODE_NAME     R245 2
 '@SCM_LIB.SCM(SCH_1):PAGE27_I146@PURE_QUANTA.Q_RES(CHIPS)':
 'B': CDS_PINID='B';
NET_NAME
'SMB_BMC_MM2_R_SCL'
 '@SCM_LIB.SCM(SCH_1):SMB_BMC_MM2_R_SCL':
 C_SIGNAL='@scm_lib.scm(sch_1):smb_bmc_mm2_r_scl';
NODE_NAME     R165 1
 '@SCM_LIB.SCM(SCH_1):PAGE12_I315@PURE_QUANTA.Q_RES(CHIPS)':
 'A': CDS_PINID='A';
NODE_NAME     U5 E19
 '@SCM_LIB.SCM(SCH_1):PAGE12_I436@PURE_QUANTA.AST2600A3GP(CHIPS)':
 'GPIOJ2||HVI3C4SCL||SCL2': CDS_PINID='\gpioj2||hvi3c4scl||scl2\';
NET_NAME
'SMB_BMC_MM2_R_SDA'
 '@SCM_LIB.SCM(SCH_1):SMB_BMC_MM2_R_SDA':
 C_SIGNAL='@scm_lib.scm(sch_1):smb_bmc_mm2_r_sda';
NODE_NAME     R394 1
 '@SCM_LIB.SCM(SCH_1):PAGE12_I314@PURE_QUANTA.Q_RES(CHIPS)':
 'A': CDS_PINID='A';
NODE_NAME     U5 D20
 '@SCM_LIB.SCM(SCH_1):PAGE12_I436@PURE_QUANTA.AST2600A3GP(CHIPS)':
 'GPIOJ3||HVI3C4SDA||SDA2': CDS_PINID='\gpioj3||hvi3c4sda||sda2\';
NET_NAME
'SMB_BMC_MM2_SCL'
 '@SCM_LIB.SCM(SCH_1):SMB_BMC_MM2_SCL':
 C_SIGNAL='@scm_lib.scm(sch_1):smb_bmc_mm2_scl';
NODE_NAME     R165 2
 '@SCM_LIB.SCM(SCH_1):PAGE12_I315@PURE_QUANTA.Q_RES(CHIPS)':
 'B': CDS_PINID='B';
NODE_NAME     R410 2
 '@SCM_LIB.SCM(SCH_1):PAGE26_I56@PURE_QUANTA.Q_RES(CHIPS)':
 'B': CDS_PINID='B';
NODE_NAME     R246 2
 '@SCM_LIB.SCM(SCH_1):PAGE27_I145@PURE_QUANTA.Q_RES(CHIPS)':
 'B': CDS_PINID='B';
NODE_NAME     R455 1
 '@SCM_LIB.SCM(SCH_1):PAGE10_I557@PURE_QUANTA.Q_RES(CHIPS)':
 'A': CDS_PINID='A';
NET_NAME
'SMB_BMC_MM2_SCL_R1'
 '@SCM_LIB.SCM(SCH_1):SMB_BMC_MM2_SCL_R1':
 C_SIGNAL='@scm_lib.scm(sch_1):smb_bmc_mm2_scl_r1';
NODE_NAME     GF1 A5
 '@SCM_LIB.SCM(SCH_1):PAGE10_I553@PURE_QUANTA.FCONN168_ME1016810202011_SCM(CHIPS)':
 'I2C_2_SCL': CDS_PINID='I2C_2_SCL';
NODE_NAME     R455 2
 '@SCM_LIB.SCM(SCH_1):PAGE10_I557@PURE_QUANTA.Q_RES(CHIPS)':
 'B': CDS_PINID='B';
NET_NAME
'SMB_BMC_MM2_SDA'
 '@SCM_LIB.SCM(SCH_1):SMB_BMC_MM2_SDA':
 C_SIGNAL='@scm_lib.scm(sch_1):smb_bmc_mm2_sda';
NODE_NAME     GF1 A6
 '@SCM_LIB.SCM(SCH_1):PAGE10_I553@PURE_QUANTA.FCONN168_ME1016810202011_SCM(CHIPS)':
 'I2C_2_SDA': CDS_PINID='I2C_2_SDA';
NODE_NAME     R394 2
 '@SCM_LIB.SCM(SCH_1):PAGE12_I314@PURE_QUANTA.Q_RES(CHIPS)':
 'B': CDS_PINID='B';
NODE_NAME     R409 2
 '@SCM_LIB.SCM(SCH_1):PAGE26_I57@PURE_QUANTA.Q_RES(CHIPS)':
 'B': CDS_PINID='B';
NODE_NAME     R247 2
 '@SCM_LIB.SCM(SCH_1):PAGE27_I109@PURE_QUANTA.Q_RES(CHIPS)':
 'B': CDS_PINID='B';
NET_NAME
'SMB_BMC_MM3_R_SCL'
 '@SCM_LIB.SCM(SCH_1):SMB_BMC_MM3_R_SCL':
 C_SIGNAL='@scm_lib.scm(sch_1):smb_bmc_mm3_r_scl';
NODE_NAME     R589 1
 '@SCM_LIB.SCM(SCH_1):PAGE12_I316@PURE_QUANTA.Q_RES(CHIPS)':
 'A': CDS_PINID='A';
NODE_NAME     U5 C19
 '@SCM_LIB.SCM(SCH_1):PAGE12_I436@PURE_QUANTA.AST2600A3GP(CHIPS)':
 'GPIOJ4||HVI3C5SCL||SCL3': CDS_PINID='\gpioj4||hvi3c5scl||scl3\';
NET_NAME
'SMB_BMC_MM3_R_SDA'
 '@SCM_LIB.SCM(SCH_1):SMB_BMC_MM3_R_SDA':
 C_SIGNAL='@scm_lib.scm(sch_1):smb_bmc_mm3_r_sda';
NODE_NAME     R590 1
 '@SCM_LIB.SCM(SCH_1):PAGE12_I317@PURE_QUANTA.Q_RES(CHIPS)':
 'A': CDS_PINID='A';
NODE_NAME     U5 A19
 '@SCM_LIB.SCM(SCH_1):PAGE12_I436@PURE_QUANTA.AST2600A3GP(CHIPS)':
 'GPIOJ5||HVI3C5SDA||SDA3': CDS_PINID='\gpioj5||hvi3c5sda||sda3\';
NET_NAME
'SMB_BMC_MM3_SCL'
 '@SCM_LIB.SCM(SCH_1):SMB_BMC_MM3_SCL':
 C_SIGNAL='@scm_lib.scm(sch_1):smb_bmc_mm3_scl';
NODE_NAME     GF1 A7
 '@SCM_LIB.SCM(SCH_1):PAGE10_I553@PURE_QUANTA.FCONN168_ME1016810202011_SCM(CHIPS)':
 'I2C_3_SCL': CDS_PINID='I2C_3_SCL';
NODE_NAME     R589 2
 '@SCM_LIB.SCM(SCH_1):PAGE12_I316@PURE_QUANTA.Q_RES(CHIPS)':
 'B': CDS_PINID='B';
NODE_NAME     R248 2
 '@SCM_LIB.SCM(SCH_1):PAGE27_I107@PURE_QUANTA.Q_RES(CHIPS)':
 'B': CDS_PINID='B';
NET_NAME
'SMB_BMC_MM3_SDA'
 '@SCM_LIB.SCM(SCH_1):SMB_BMC_MM3_SDA':
 C_SIGNAL='@scm_lib.scm(sch_1):smb_bmc_mm3_sda';
NODE_NAME     GF1 A8
 '@SCM_LIB.SCM(SCH_1):PAGE10_I553@PURE_QUANTA.FCONN168_ME1016810202011_SCM(CHIPS)':
 'I2C_3_SDA': CDS_PINID='I2C_3_SDA';
NODE_NAME     R590 2
 '@SCM_LIB.SCM(SCH_1):PAGE12_I317@PURE_QUANTA.Q_RES(CHIPS)':
 'B': CDS_PINID='B';
NODE_NAME     R249 2
 '@SCM_LIB.SCM(SCH_1):PAGE27_I108@PURE_QUANTA.Q_RES(CHIPS)':
 'B': CDS_PINID='B';
NET_NAME
'SMB_BMC_MM4_R_SCL'
 '@SCM_LIB.SCM(SCH_1):SMB_BMC_MM4_R_SCL':
 C_SIGNAL='@scm_lib.scm(sch_1):smb_bmc_mm4_r_scl';
NODE_NAME     U5 C20
 '@SCM_LIB.SCM(SCH_1):PAGE12_I436@PURE_QUANTA.AST2600A3GP(CHIPS)':
 'GPIOJ6||HVI3C6SCL||SCL4': CDS_PINID='\gpioj6||hvi3c6scl||scl4\';
NODE_NAME     R138 1
 '@SCM_LIB.SCM(SCH_1):PAGE12_I513@PURE_QUANTA.Q_RES(CHIPS)':
 'A': CDS_PINID='A';
NET_NAME
'SMB_BMC_MM4_R_SDA'
 '@SCM_LIB.SCM(SCH_1):SMB_BMC_MM4_R_SDA':
 C_SIGNAL='@scm_lib.scm(sch_1):smb_bmc_mm4_r_sda';
NODE_NAME     U5 D19
 '@SCM_LIB.SCM(SCH_1):PAGE12_I436@PURE_QUANTA.AST2600A3GP(CHIPS)':
 'GPIOJ7||HVI3C6SDA||SDA4': CDS_PINID='\gpioj7||hvi3c6sda||sda4\';
NODE_NAME     R139 1
 '@SCM_LIB.SCM(SCH_1):PAGE12_I512@PURE_QUANTA.Q_RES(CHIPS)':
 'A': CDS_PINID='A';
NET_NAME
'SMB_BMC_MM4_SCL'
 '@SCM_LIB.SCM(SCH_1):SMB_BMC_MM4_SCL':
 C_SIGNAL='@scm_lib.scm(sch_1):smb_bmc_mm4_scl';
NODE_NAME     GF1 A9
 '@SCM_LIB.SCM(SCH_1):PAGE10_I553@PURE_QUANTA.FCONN168_ME1016810202011_SCM(CHIPS)':
 'I2C_4_SCL': CDS_PINID='I2C_4_SCL';
NODE_NAME     R250 2
 '@SCM_LIB.SCM(SCH_1):PAGE27_I106@PURE_QUANTA.Q_RES(CHIPS)':
 'B': CDS_PINID='B';
NODE_NAME     R138 2
 '@SCM_LIB.SCM(SCH_1):PAGE12_I513@PURE_QUANTA.Q_RES(CHIPS)':
 'B': CDS_PINID='B';
NET_NAME
'SMB_BMC_MM4_SDA'
 '@SCM_LIB.SCM(SCH_1):SMB_BMC_MM4_SDA':
 C_SIGNAL='@scm_lib.scm(sch_1):smb_bmc_mm4_sda';
NODE_NAME     GF1 A10
 '@SCM_LIB.SCM(SCH_1):PAGE10_I553@PURE_QUANTA.FCONN168_ME1016810202011_SCM(CHIPS)':
 'I2C_4_SDA': CDS_PINID='I2C_4_SDA';
NODE_NAME     R251 2
 '@SCM_LIB.SCM(SCH_1):PAGE27_I247@PURE_QUANTA.Q_RES(CHIPS)':
 'B': CDS_PINID='B';
NODE_NAME     R139 2
 '@SCM_LIB.SCM(SCH_1):PAGE12_I512@PURE_QUANTA.Q_RES(CHIPS)':
 'B': CDS_PINID='B';
NET_NAME
'SMB_BMC_MM5_R_SCL'
 '@SCM_LIB.SCM(SCH_1):SMB_BMC_MM5_R_SCL':
 C_SIGNAL='@scm_lib.scm(sch_1):smb_bmc_mm5_r_scl';
NODE_NAME     R71 1
 '@SCM_LIB.SCM(SCH_1):PAGE12_I277@PURE_QUANTA.Q_RES(CHIPS)':
 'A': CDS_PINID='A';
NODE_NAME     U5 A11
 '@SCM_LIB.SCM(SCH_1):PAGE12_I436@PURE_QUANTA.AST2600A3GP(CHIPS)':
 'GPIOK0||SCL5': CDS_PINID='\gpiok0||scl5\';
NODE_NAME     R252 2
 '@SCM_LIB.SCM(SCH_1):PAGE27_I105@PURE_QUANTA.Q_RES(CHIPS)':
 'B': CDS_PINID='B';
NET_NAME
'SMB_BMC_MM5_R_SDA'
 '@SCM_LIB.SCM(SCH_1):SMB_BMC_MM5_R_SDA':
 C_SIGNAL='@scm_lib.scm(sch_1):smb_bmc_mm5_r_sda';
NODE_NAME     R93 1
 '@SCM_LIB.SCM(SCH_1):PAGE12_I276@PURE_QUANTA.Q_RES(CHIPS)':
 'A': CDS_PINID='A';
NODE_NAME     U5 C11
 '@SCM_LIB.SCM(SCH_1):PAGE12_I436@PURE_QUANTA.AST2600A3GP(CHIPS)':
 'GPIOK1||SDA5': CDS_PINID='\gpiok1||sda5\';
NODE_NAME     R253 2
 '@SCM_LIB.SCM(SCH_1):PAGE27_I103@PURE_QUANTA.Q_RES(CHIPS)':
 'B': CDS_PINID='B';
NET_NAME
'SMB_BMC_MM5_SCL'
 '@SCM_LIB.SCM(SCH_1):SMB_BMC_MM5_SCL':
 C_SIGNAL='@scm_lib.scm(sch_1):smb_bmc_mm5_scl';
NODE_NAME     GF1 A11
 '@SCM_LIB.SCM(SCH_1):PAGE10_I553@PURE_QUANTA.FCONN168_ME1016810202011_SCM(CHIPS)':
 'I2C_5_SCL': CDS_PINID='I2C_5_SCL';
NODE_NAME     R71 2
 '@SCM_LIB.SCM(SCH_1):PAGE12_I277@PURE_QUANTA.Q_RES(CHIPS)':
 'B': CDS_PINID='B';
NET_NAME
'SMB_BMC_MM5_SDA'
 '@SCM_LIB.SCM(SCH_1):SMB_BMC_MM5_SDA':
 C_SIGNAL='@scm_lib.scm(sch_1):smb_bmc_mm5_sda';
NODE_NAME     GF1 A12
 '@SCM_LIB.SCM(SCH_1):PAGE10_I553@PURE_QUANTA.FCONN168_ME1016810202011_SCM(CHIPS)':
 'I2C_5_SDA': CDS_PINID='I2C_5_SDA';
NODE_NAME     R93 2
 '@SCM_LIB.SCM(SCH_1):PAGE12_I276@PURE_QUANTA.Q_RES(CHIPS)':
 'B': CDS_PINID='B';
NET_NAME
'SMB_BMC_MM6_R_SCL'
 '@SCM_LIB.SCM(SCH_1):SMB_BMC_MM6_R_SCL':
 C_SIGNAL='@scm_lib.scm(sch_1):smb_bmc_mm6_r_scl';
NODE_NAME     R142 1
 '@SCM_LIB.SCM(SCH_1):PAGE12_I88@PURE_QUANTA.Q_RES(CHIPS)':
 'A': CDS_PINID='A';
NODE_NAME     U5 D12
 '@SCM_LIB.SCM(SCH_1):PAGE12_I436@PURE_QUANTA.AST2600A3GP(CHIPS)':
 'GPIOK2||SCL6': CDS_PINID='\gpiok2||scl6\';
NET_NAME
'SMB_BMC_MM6_R_SDA'
 '@SCM_LIB.SCM(SCH_1):SMB_BMC_MM6_R_SDA':
 C_SIGNAL='@scm_lib.scm(sch_1):smb_bmc_mm6_r_sda';
NODE_NAME     R143 1
 '@SCM_LIB.SCM(SCH_1):PAGE12_I89@PURE_QUANTA.Q_RES(CHIPS)':
 'A': CDS_PINID='A';
NODE_NAME     U5 E13
 '@SCM_LIB.SCM(SCH_1):PAGE12_I436@PURE_QUANTA.AST2600A3GP(CHIPS)':
 'GPIOK3||SDA6': CDS_PINID='\gpiok3||sda6\';
NET_NAME
'SMB_BMC_MM6_SCL'
 '@SCM_LIB.SCM(SCH_1):SMB_BMC_MM6_SCL':
 C_SIGNAL='@scm_lib.scm(sch_1):smb_bmc_mm6_scl';
NODE_NAME     GF1 A23
 '@SCM_LIB.SCM(SCH_1):PAGE10_I553@PURE_QUANTA.FCONN168_ME1016810202011_SCM(CHIPS)':
 'I2C_6_SCL': CDS_PINID='I2C_6_SCL';
NODE_NAME     R142 2
 '@SCM_LIB.SCM(SCH_1):PAGE12_I88@PURE_QUANTA.Q_RES(CHIPS)':
 'B': CDS_PINID='B';
NODE_NAME     R254 2
 '@SCM_LIB.SCM(SCH_1):PAGE27_I101@PURE_QUANTA.Q_RES(CHIPS)':
 'B': CDS_PINID='B';
NET_NAME
'SMB_BMC_MM6_SDA'
 '@SCM_LIB.SCM(SCH_1):SMB_BMC_MM6_SDA':
 C_SIGNAL='@scm_lib.scm(sch_1):smb_bmc_mm6_sda';
NODE_NAME     GF1 A24
 '@SCM_LIB.SCM(SCH_1):PAGE10_I553@PURE_QUANTA.FCONN168_ME1016810202011_SCM(CHIPS)':
 'I2C_6_SDA': CDS_PINID='I2C_6_SDA';
NODE_NAME     R143 2
 '@SCM_LIB.SCM(SCH_1):PAGE12_I89@PURE_QUANTA.Q_RES(CHIPS)':
 'B': CDS_PINID='B';
NODE_NAME     R255 2
 '@SCM_LIB.SCM(SCH_1):PAGE27_I102@PURE_QUANTA.Q_RES(CHIPS)':
 'B': CDS_PINID='B';
NET_NAME
'SMB_BMC_MM7_R_SCL'
 '@SCM_LIB.SCM(SCH_1):SMB_BMC_MM7_R_SCL':
 C_SIGNAL='@scm_lib.scm(sch_1):smb_bmc_mm7_r_scl';
NODE_NAME     R567 1
 '@SCM_LIB.SCM(SCH_1):PAGE12_I274@PURE_QUANTA.Q_RES(CHIPS)':
 'A': CDS_PINID='A';
NODE_NAME     U5 D11
 '@SCM_LIB.SCM(SCH_1):PAGE12_I436@PURE_QUANTA.AST2600A3GP(CHIPS)':
 'GPIOK4||SCL7': CDS_PINID='\gpiok4||scl7\';
NODE_NAME     R256 2
 '@SCM_LIB.SCM(SCH_1):PAGE27_I100@PURE_QUANTA.Q_RES(CHIPS)':
 'B': CDS_PINID='B';
NET_NAME
'SMB_BMC_MM7_R_SDA'
 '@SCM_LIB.SCM(SCH_1):SMB_BMC_MM7_R_SDA':
 C_SIGNAL='@scm_lib.scm(sch_1):smb_bmc_mm7_r_sda';
NODE_NAME     R570 1
 '@SCM_LIB.SCM(SCH_1):PAGE12_I275@PURE_QUANTA.Q_RES(CHIPS)':
 'A': CDS_PINID='A';
NODE_NAME     U5 E11
 '@SCM_LIB.SCM(SCH_1):PAGE12_I436@PURE_QUANTA.AST2600A3GP(CHIPS)':
 'GPIOK5||SDA7': CDS_PINID='\gpiok5||sda7\';
NODE_NAME     R257 2
 '@SCM_LIB.SCM(SCH_1):PAGE27_I99@PURE_QUANTA.Q_RES(CHIPS)':
 'B': CDS_PINID='B';
NET_NAME
'SMB_BMC_MM7_SCL'
 '@SCM_LIB.SCM(SCH_1):SMB_BMC_MM7_SCL':
 C_SIGNAL='@scm_lib.scm(sch_1):smb_bmc_mm7_scl';
NODE_NAME     GF1 A25
 '@SCM_LIB.SCM(SCH_1):PAGE10_I553@PURE_QUANTA.FCONN168_ME1016810202011_SCM(CHIPS)':
 'I2C_7_SCL': CDS_PINID='I2C_7_SCL';
NODE_NAME     R567 2
 '@SCM_LIB.SCM(SCH_1):PAGE12_I274@PURE_QUANTA.Q_RES(CHIPS)':
 'B': CDS_PINID='B';
NET_NAME
'SMB_BMC_MM7_SDA'
 '@SCM_LIB.SCM(SCH_1):SMB_BMC_MM7_SDA':
 C_SIGNAL='@scm_lib.scm(sch_1):smb_bmc_mm7_sda';
NODE_NAME     GF1 A26
 '@SCM_LIB.SCM(SCH_1):PAGE10_I553@PURE_QUANTA.FCONN168_ME1016810202011_SCM(CHIPS)':
 'I2C_7_SDA': CDS_PINID='I2C_7_SDA';
NODE_NAME     R570 2
 '@SCM_LIB.SCM(SCH_1):PAGE12_I275@PURE_QUANTA.Q_RES(CHIPS)':
 'B': CDS_PINID='B';
NET_NAME
'SMB_BMC_MM8_R_SCL'
 '@SCM_LIB.SCM(SCH_1):SMB_BMC_MM8_R_SCL':
 C_SIGNAL='@scm_lib.scm(sch_1):smb_bmc_mm8_r_scl';
NODE_NAME     R146 1
 '@SCM_LIB.SCM(SCH_1):PAGE12_I235@PURE_QUANTA.Q_RES(CHIPS)':
 'A': CDS_PINID='A';
NODE_NAME     U5 F13
 '@SCM_LIB.SCM(SCH_1):PAGE12_I436@PURE_QUANTA.AST2600A3GP(CHIPS)':
 'GPIOK6||SCL8': CDS_PINID='\gpiok6||scl8\';
NET_NAME
'SMB_BMC_MM8_R_SDA'
 '@SCM_LIB.SCM(SCH_1):SMB_BMC_MM8_R_SDA':
 C_SIGNAL='@scm_lib.scm(sch_1):smb_bmc_mm8_r_sda';
NODE_NAME     R147 1
 '@SCM_LIB.SCM(SCH_1):PAGE12_I236@PURE_QUANTA.Q_RES(CHIPS)':
 'A': CDS_PINID='A';
NODE_NAME     U5 E12
 '@SCM_LIB.SCM(SCH_1):PAGE12_I436@PURE_QUANTA.AST2600A3GP(CHIPS)':
 'GPIOK7||SDA8': CDS_PINID='\gpiok7||sda8\';
NET_NAME
'SMB_BMC_MM8_SCL'
 '@SCM_LIB.SCM(SCH_1):SMB_BMC_MM8_SCL':
 C_SIGNAL='@scm_lib.scm(sch_1):smb_bmc_mm8_scl';
NODE_NAME     GF1 A27
 '@SCM_LIB.SCM(SCH_1):PAGE10_I553@PURE_QUANTA.FCONN168_ME1016810202011_SCM(CHIPS)':
 'I2C_8_SCL': CDS_PINID='I2C_8_SCL';
NODE_NAME     R146 2
 '@SCM_LIB.SCM(SCH_1):PAGE12_I235@PURE_QUANTA.Q_RES(CHIPS)':
 'B': CDS_PINID='B';
NODE_NAME     R258 2
 '@SCM_LIB.SCM(SCH_1):PAGE27_I98@PURE_QUANTA.Q_RES(CHIPS)':
 'B': CDS_PINID='B';
NET_NAME
'SMB_BMC_MM8_SDA'
 '@SCM_LIB.SCM(SCH_1):SMB_BMC_MM8_SDA':
 C_SIGNAL='@scm_lib.scm(sch_1):smb_bmc_mm8_sda';
NODE_NAME     GF1 A28
 '@SCM_LIB.SCM(SCH_1):PAGE10_I553@PURE_QUANTA.FCONN168_ME1016810202011_SCM(CHIPS)':
 'I2C_8_SDA': CDS_PINID='I2C_8_SDA';
NODE_NAME     R147 2
 '@SCM_LIB.SCM(SCH_1):PAGE12_I236@PURE_QUANTA.Q_RES(CHIPS)':
 'B': CDS_PINID='B';
NODE_NAME     R259 2
 '@SCM_LIB.SCM(SCH_1):PAGE27_I96@PURE_QUANTA.Q_RES(CHIPS)':
 'B': CDS_PINID='B';
NET_NAME
'SMB_BMC_MM9_R_SCL'
 '@SCM_LIB.SCM(SCH_1):SMB_BMC_MM9_R_SCL':
 C_SIGNAL='@scm_lib.scm(sch_1):smb_bmc_mm9_r_scl';
NODE_NAME     R580 1
 '@SCM_LIB.SCM(SCH_1):PAGE12_I321@PURE_QUANTA.Q_RES(CHIPS)':
 'A': CDS_PINID='A';
NODE_NAME     U5 D15
 '@SCM_LIB.SCM(SCH_1):PAGE12_I436@PURE_QUANTA.AST2600A3GP(CHIPS)':
 'GPIOL0||SCL9': CDS_PINID='\gpiol0||scl9\';
NET_NAME
'SMB_BMC_MM9_R_SDA'
 '@SCM_LIB.SCM(SCH_1):SMB_BMC_MM9_R_SDA':
 C_SIGNAL='@scm_lib.scm(sch_1):smb_bmc_mm9_r_sda';
NODE_NAME     R582 1
 '@SCM_LIB.SCM(SCH_1):PAGE12_I318@PURE_QUANTA.Q_RES(CHIPS)':
 'A': CDS_PINID='A';
NODE_NAME     U5 A14
 '@SCM_LIB.SCM(SCH_1):PAGE12_I436@PURE_QUANTA.AST2600A3GP(CHIPS)':
 'GPIOL1||SDA9': CDS_PINID='\gpiol1||sda9\';
NET_NAME
'SMB_BMC_MM9_SCL'
 '@SCM_LIB.SCM(SCH_1):SMB_BMC_MM9_SCL':
 C_SIGNAL='@scm_lib.scm(sch_1):smb_bmc_mm9_scl';
NODE_NAME     GF1 A29
 '@SCM_LIB.SCM(SCH_1):PAGE10_I553@PURE_QUANTA.FCONN168_ME1016810202011_SCM(CHIPS)':
 'I2C_9_SCL': CDS_PINID='I2C_9_SCL';
NODE_NAME     R580 2
 '@SCM_LIB.SCM(SCH_1):PAGE12_I321@PURE_QUANTA.Q_RES(CHIPS)':
 'B': CDS_PINID='B';
NODE_NAME     R260 2
 '@SCM_LIB.SCM(SCH_1):PAGE27_I97@PURE_QUANTA.Q_RES(CHIPS)':
 'B': CDS_PINID='B';
NET_NAME
'SMB_BMC_MM9_SDA'
 '@SCM_LIB.SCM(SCH_1):SMB_BMC_MM9_SDA':
 C_SIGNAL='@scm_lib.scm(sch_1):smb_bmc_mm9_sda';
NODE_NAME     GF1 A30
 '@SCM_LIB.SCM(SCH_1):PAGE10_I553@PURE_QUANTA.FCONN168_ME1016810202011_SCM(CHIPS)':
 'I2C_9_SDA': CDS_PINID='I2C_9_SDA';
NODE_NAME     R582 2
 '@SCM_LIB.SCM(SCH_1):PAGE12_I318@PURE_QUANTA.Q_RES(CHIPS)':
 'B': CDS_PINID='B';
NODE_NAME     R261 2
 '@SCM_LIB.SCM(SCH_1):PAGE27_I94@PURE_QUANTA.Q_RES(CHIPS)':
 'B': CDS_PINID='B';
NET_NAME
'SMB_BMC_TPM_MM16_SCL'
 '@SCM_LIB.SCM(SCH_1):SMB_BMC_TPM_MM16_SCL':
 C_SIGNAL='@scm_lib.scm(sch_1):smb_bmc_tpm_mm16_scl';
NODE_NAME     R47 1
 '@SCM_LIB.SCM(SCH_1):PAGE46_I106@PURE_QUANTA.Q_RES(CHIPS)':
 'A': CDS_PINID='A';
NODE_NAME     J10 10
 '@SCM_LIB.SCM(SCH_1):PAGE46_I113@PURE_QUANTA.SCONN11_9192031111LF(CHIPS)':
 '10': CDS_PINID='\10\';
NET_NAME
'SMB_BMC_TPM_MM16_SDA'
 '@SCM_LIB.SCM(SCH_1):SMB_BMC_TPM_MM16_SDA':
 C_SIGNAL='@scm_lib.scm(sch_1):smb_bmc_tpm_mm16_sda';
NODE_NAME     J10 6
 '@SCM_LIB.SCM(SCH_1):PAGE46_I113@PURE_QUANTA.SCONN11_9192031111LF(CHIPS)':
 '6': CDS_PINID='\6\';
NODE_NAME     R33 2
 '@SCM_LIB.SCM(SCH_1):PAGE46_I117@PURE_QUANTA.Q_RES(CHIPS)':
 'B': CDS_PINID='B';
NET_NAME
'SMB_DEBUG_AUX_LVC3_USB_R1_SCL'
 '@SCM_LIB.SCM(SCH_1):SMB_DEBUG_AUX_LVC3_USB_R1_SCL':
 C_SIGNAL='@scm_lib.scm(sch_1):smb_debug_aux_lvc3_usb_r1_scl';
NODE_NAME     R298 2
 '@SCM_LIB.SCM(SCH_1):PAGE28_I96@PURE_QUANTA.Q_RES(CHIPS)':
 'B': CDS_PINID='B';
NODE_NAME     U37 7
 '@SCM_LIB.SCM(SCH_1):PAGE28_I99@PURE_QUANTA.PCA9517ADP(CHIPS)':
 'SCLB': CDS_PINID='SCLB';
NODE_NAME     R300 1
 '@SCM_LIB.SCM(SCH_1):PAGE28_I183@PURE_QUANTA.Q_RES(CHIPS)':
 'A': CDS_PINID='A';
NET_NAME
'SMB_DEBUG_AUX_LVC3_USB_R1_SDA'
 '@SCM_LIB.SCM(SCH_1):SMB_DEBUG_AUX_LVC3_USB_R1_SDA':
 C_SIGNAL='@scm_lib.scm(sch_1):smb_debug_aux_lvc3_usb_r1_sda';
NODE_NAME     R299 2
 '@SCM_LIB.SCM(SCH_1):PAGE28_I91@PURE_QUANTA.Q_RES(CHIPS)':
 'B': CDS_PINID='B';
NODE_NAME     U37 6
 '@SCM_LIB.SCM(SCH_1):PAGE28_I99@PURE_QUANTA.PCA9517ADP(CHIPS)':
 'SDAB': CDS_PINID='SDAB';
NODE_NAME     R302 1
 '@SCM_LIB.SCM(SCH_1):PAGE28_I184@PURE_QUANTA.Q_RES(CHIPS)':
 'A': CDS_PINID='A';
NET_NAME
'SMB_DEBUG_AUX_LVC3_USB_R2_SCL'
 '@SCM_LIB.SCM(SCH_1):SMB_DEBUG_AUX_LVC3_USB_R2_SCL':
 C_SIGNAL='@scm_lib.scm(sch_1):smb_debug_aux_lvc3_usb_r2_scl';
NODE_NAME     R732 2
 '@SCM_LIB.SCM(SCH_1):PAGE29_I136@PURE_QUANTA.Q_RES(CHIPS)':
 'B': CDS_PINID='B';
NODE_NAME     U22 12
 '@SCM_LIB.SCM(SCH_1):PAGE29_I206@PURE_QUANTA.PI3PCIE3212ZBEX(CHIPS)':
 'C1_N': CDS_PINID='C1_N';
NET_NAME
'SMB_DEBUG_AUX_LVC3_USB_R2_SDA'
 '@SCM_LIB.SCM(SCH_1):SMB_DEBUG_AUX_LVC3_USB_R2_SDA':
 C_SIGNAL='@scm_lib.scm(sch_1):smb_debug_aux_lvc3_usb_r2_sda';
NODE_NAME     R731 2
 '@SCM_LIB.SCM(SCH_1):PAGE29_I135@PURE_QUANTA.Q_RES(CHIPS)':
 'B': CDS_PINID='B';
NODE_NAME     U22 13
 '@SCM_LIB.SCM(SCH_1):PAGE29_I206@PURE_QUANTA.PI3PCIE3212ZBEX(CHIPS)':
 'C1_P': CDS_PINID='C1_P';
NET_NAME
'SMB_DEBUG_AUX_LVC3_USB_R3_SCL'
 '@SCM_LIB.SCM(SCH_1):SMB_DEBUG_AUX_LVC3_USB_R3_SCL':
 C_SIGNAL='@scm_lib.scm(sch_1):smb_debug_aux_lvc3_usb_r3_scl';
NODE_NAME     U40 22
 '@SCM_LIB.SCM(SCH_1):PAGE28_I141@PURE_QUANTA.PCA9555PW(CHIPS)':
 'SCL': CDS_PINID='SCL';
NODE_NAME     R632 2
 '@SCM_LIB.SCM(SCH_1):PAGE28_I153@PURE_QUANTA.Q_RES(CHIPS)':
 'B': CDS_PINID='B';
NET_NAME
'SMB_DEBUG_AUX_LVC3_USB_R3_SDA'
 '@SCM_LIB.SCM(SCH_1):SMB_DEBUG_AUX_LVC3_USB_R3_SDA':
 C_SIGNAL='@scm_lib.scm(sch_1):smb_debug_aux_lvc3_usb_r3_sda';
NODE_NAME     U40 23
 '@SCM_LIB.SCM(SCH_1):PAGE28_I141@PURE_QUANTA.PCA9555PW(CHIPS)':
 'SDA': CDS_PINID='SDA';
NODE_NAME     R95 2
 '@SCM_LIB.SCM(SCH_1):PAGE28_I152@PURE_QUANTA.Q_RES(CHIPS)':
 'B': CDS_PINID='B';
NET_NAME
'SMB_DEBUG_AUX_LVC3_USB_SCL'
 '@SCM_LIB.SCM(SCH_1):SMB_DEBUG_AUX_LVC3_USB_SCL':
 C_SIGNAL='@scm_lib.scm(sch_1):smb_debug_aux_lvc3_usb_scl';
NODE_NAME     R632 1
 '@SCM_LIB.SCM(SCH_1):PAGE28_I153@PURE_QUANTA.Q_RES(CHIPS)':
 'A': CDS_PINID='A';
NODE_NAME     R732 1
 '@SCM_LIB.SCM(SCH_1):PAGE29_I136@PURE_QUANTA.Q_RES(CHIPS)':
 'A': CDS_PINID='A';
NODE_NAME     R300 2
 '@SCM_LIB.SCM(SCH_1):PAGE28_I183@PURE_QUANTA.Q_RES(CHIPS)':
 'B': CDS_PINID='B';
NET_NAME
'SMB_DEBUG_AUX_LVC3_USB_SDA'
 '@SCM_LIB.SCM(SCH_1):SMB_DEBUG_AUX_LVC3_USB_SDA':
 C_SIGNAL='@scm_lib.scm(sch_1):smb_debug_aux_lvc3_usb_sda';
NODE_NAME     R95 1
 '@SCM_LIB.SCM(SCH_1):PAGE28_I152@PURE_QUANTA.Q_RES(CHIPS)':
 'A': CDS_PINID='A';
NODE_NAME     R731 1
 '@SCM_LIB.SCM(SCH_1):PAGE29_I135@PURE_QUANTA.Q_RES(CHIPS)':
 'A': CDS_PINID='A';
NODE_NAME     R302 2
 '@SCM_LIB.SCM(SCH_1):PAGE28_I184@PURE_QUANTA.Q_RES(CHIPS)':
 'B': CDS_PINID='B';
NET_NAME
'SMB_PCH_TPM_SCL'
 '@SCM_LIB.SCM(SCH_1):SMB_PCH_TPM_SCL':
 C_SIGNAL='@scm_lib.scm(sch_1):smb_pch_tpm_scl';
NODE_NAME     J5 10
 '@SCM_LIB.SCM(SCH_1):PAGE46_I56@PURE_QUANTA.SCONN11_9192031111LF(CHIPS)':
 '10': CDS_PINID='\10\';
NODE_NAME     R136 2
 '@SCM_LIB.SCM(SCH_1):PAGE46_I132@PURE_QUANTA.Q_RES(CHIPS)':
 'B': CDS_PINID='B';
NET_NAME
'SMB_PCH_TPM_SDA'
 '@SCM_LIB.SCM(SCH_1):SMB_PCH_TPM_SDA':
 C_SIGNAL='@scm_lib.scm(sch_1):smb_pch_tpm_sda';
NODE_NAME     J5 6
 '@SCM_LIB.SCM(SCH_1):PAGE46_I56@PURE_QUANTA.SCONN11_9192031111LF(CHIPS)':
 '6': CDS_PINID='\6\';
NODE_NAME     R126 1
 '@SCM_LIB.SCM(SCH_1):PAGE46_I134@PURE_QUANTA.Q_RES(CHIPS)':
 'A': CDS_PINID='A';
NET_NAME
'SMB_TMP421_BMC_MM2_SCL'
 '@SCM_LIB.SCM(SCH_1):SMB_TMP421_BMC_MM2_SCL':
 C_SIGNAL='@scm_lib.scm(sch_1):smb_tmp421_bmc_mm2_scl';
NODE_NAME     R410 1
 '@SCM_LIB.SCM(SCH_1):PAGE26_I56@PURE_QUANTA.Q_RES(CHIPS)':
 'A': CDS_PINID='A';
NODE_NAME     J14 4
 '@SCM_LIB.SCM(SCH_1):PAGE26_I71@PURE_QUANTA.CONN8_TSW10407FD(CHIPS)':
 '4': CDS_PINID='\4\';
NET_NAME
'SMB_TMP421_BMC_MM2_SDA'
 '@SCM_LIB.SCM(SCH_1):SMB_TMP421_BMC_MM2_SDA':
 C_SIGNAL='@scm_lib.scm(sch_1):smb_tmp421_bmc_mm2_sda';
NODE_NAME     R409 1
 '@SCM_LIB.SCM(SCH_1):PAGE26_I57@PURE_QUANTA.Q_RES(CHIPS)':
 'A': CDS_PINID='A';
NODE_NAME     J14 2
 '@SCM_LIB.SCM(SCH_1):PAGE26_I71@PURE_QUANTA.CONN8_TSW10407FD(CHIPS)':
 '2': CDS_PINID='\2\';
NET_NAME
'SPA_SIN_SW_BUF'
 '@SCM_LIB.SCM(SCH_1):SPA_SIN_SW_BUF':
 C_SIGNAL='@scm_lib.scm(sch_1):spa_sin_sw_buf';
NODE_NAME     R737 2
 '@SCM_LIB.SCM(SCH_1):PAGE30_I192@PURE_QUANTA.Q_RES(CHIPS)':
 'B': CDS_PINID='B';
NODE_NAME     U3 7
 '@SCM_LIB.SCM(SCH_1):PAGE30_I251@PURE_QUANTA.FSA3357K8X(CHIPS)':
 'A': CDS_PINID='A';
NODE_NAME     R726 2
 '@SCM_LIB.SCM(SCH_1):PAGE30_I266@PURE_QUANTA.Q_RES(CHIPS)':
 'B': CDS_PINID='B';
NET_NAME
'SPA_SIN_SW_BUF_R'
 '@SCM_LIB.SCM(SCH_1):SPA_SIN_SW_BUF_R':
 C_SIGNAL='@scm_lib.scm(sch_1):spa_sin_sw_buf_r';
NODE_NAME     R726 1
 '@SCM_LIB.SCM(SCH_1):PAGE30_I266@PURE_QUANTA.Q_RES(CHIPS)':
 'A': CDS_PINID='A';
NODE_NAME     U20 4
 '@SCM_LIB.SCM(SCH_1):PAGE31_I38@PURE_QUANTA.NC7SB3157(CHIPS)':
 'A': CDS_PINID='A';
NET_NAME
'SPA_SIN_SW_DBG'
 '@SCM_LIB.SCM(SCH_1):SPA_SIN_SW_DBG':
 C_SIGNAL='@scm_lib.scm(sch_1):spa_sin_sw_dbg';
NODE_NAME     U36 4
 '@SCM_LIB.SCM(SCH_1):PAGE29_I164@PURE_QUANTA.74HC1G126GW(CHIPS)':
 '4': CDS_PINID='\4\';
NODE_NAME     R193 2
 '@SCM_LIB.SCM(SCH_1):PAGE29_I166@PURE_QUANTA.Q_RES(CHIPS)':
 'B': CDS_PINID='B';
NODE_NAME     R628 1
 '@SCM_LIB.SCM(SCH_1):PAGE31_I77@PURE_QUANTA.Q_RES(CHIPS)':
 'A': CDS_PINID='A';
NET_NAME
'SPA_SIN_SW_DBG_R'
 '@SCM_LIB.SCM(SCH_1):SPA_SIN_SW_DBG_R':
 C_SIGNAL='@scm_lib.scm(sch_1):spa_sin_sw_dbg_r';
NODE_NAME     U20 1
 '@SCM_LIB.SCM(SCH_1):PAGE31_I38@PURE_QUANTA.NC7SB3157(CHIPS)':
 'B1': CDS_PINID='B1';
NODE_NAME     R628 2
 '@SCM_LIB.SCM(SCH_1):PAGE31_I77@PURE_QUANTA.Q_RES(CHIPS)':
 'B': CDS_PINID='B';
NET_NAME
'SPA_SOUT_SW_BUF'
 '@SCM_LIB.SCM(SCH_1):SPA_SOUT_SW_BUF':
 C_SIGNAL='@scm_lib.scm(sch_1):spa_sout_sw_buf';
NODE_NAME     R742 2
 '@SCM_LIB.SCM(SCH_1):PAGE30_I195@PURE_QUANTA.Q_RES(CHIPS)':
 'B': CDS_PINID='B';
NODE_NAME     U2 7
 '@SCM_LIB.SCM(SCH_1):PAGE30_I250@PURE_QUANTA.FSA3357K8X(CHIPS)':
 'A': CDS_PINID='A';
NODE_NAME     R39 2
 '@SCM_LIB.SCM(SCH_1):PAGE30_I267@PURE_QUANTA.Q_RES(CHIPS)':
 'B': CDS_PINID='B';
NET_NAME
'SPA_SOUT_SW_BUF_R'
 '@SCM_LIB.SCM(SCH_1):SPA_SOUT_SW_BUF_R':
 C_SIGNAL='@scm_lib.scm(sch_1):spa_sout_sw_buf_r';
NODE_NAME     R39 1
 '@SCM_LIB.SCM(SCH_1):PAGE30_I267@PURE_QUANTA.Q_RES(CHIPS)':
 'A': CDS_PINID='A';
NODE_NAME     U7 4
 '@SCM_LIB.SCM(SCH_1):PAGE31_I27@PURE_QUANTA.NC7SB3157(CHIPS)':
 'A': CDS_PINID='A';
NET_NAME
'SPA_SOUT_SW_DBG'
 '@SCM_LIB.SCM(SCH_1):SPA_SOUT_SW_DBG':
 C_SIGNAL='@scm_lib.scm(sch_1):spa_sout_sw_dbg';
NODE_NAME     U29 2
 '@SCM_LIB.SCM(SCH_1):PAGE29_I174@PURE_QUANTA.74HC1G126GW(CHIPS)':
 '2': CDS_PINID='\2\';
NODE_NAME     R546 1
 '@SCM_LIB.SCM(SCH_1):PAGE31_I75@PURE_QUANTA.Q_RES(CHIPS)':
 'A': CDS_PINID='A';
NET_NAME
'SPA_SOUT_SW_DBG_R'
 '@SCM_LIB.SCM(SCH_1):SPA_SOUT_SW_DBG_R':
 C_SIGNAL='@scm_lib.scm(sch_1):spa_sout_sw_dbg_r';
NODE_NAME     U7 1
 '@SCM_LIB.SCM(SCH_1):PAGE31_I27@PURE_QUANTA.NC7SB3157(CHIPS)':
 'B1': CDS_PINID='B1';
NODE_NAME     R546 2
 '@SCM_LIB.SCM(SCH_1):PAGE31_I75@PURE_QUANTA.Q_RES(CHIPS)':
 'B': CDS_PINID='B';
NET_NAME
'SPI_BMC_BIOS_CS0_N'
 '@SCM_LIB.SCM(SCH_1):SPI_BMC_BIOS_CS0_N':
 C_SIGNAL='@scm_lib.scm(sch_1):spi_bmc_bios_cs0_n';
NODE_NAME     R799 1
 '@SCM_LIB.SCM(SCH_1):PAGE13_I215@PURE_QUANTA.Q_RES(CHIPS)':
 'A': CDS_PINID='A';
NODE_NAME     R728 1
 '@SCM_LIB.SCM(SCH_1):PAGE44_I336@PURE_QUANTA.Q_RES(CHIPS)':
 'A': CDS_PINID='A';
NET_NAME
'SPI_BMC_BIOS_CS0_R1_N'
 '@SCM_LIB.SCM(SCH_1):SPI_BMC_BIOS_CS0_R1_N':
 C_SIGNAL='@scm_lib.scm(sch_1):spi_bmc_bios_cs0_r1_n';
NODE_NAME     R799 2
 '@SCM_LIB.SCM(SCH_1):PAGE13_I215@PURE_QUANTA.Q_RES(CHIPS)':
 'B': CDS_PINID='B';
NODE_NAME     U5 AE8
 '@SCM_LIB.SCM(SCH_1):PAGE13_I363@PURE_QUANTA.AST2600A3GP(CHIPS)':
 'GPIOX0||SPI2CS0#': CDS_PINID='\gpiox0||spi2cs0#\';
NET_NAME
'SPI_BMC_BIOS_ROM_CLK'
 '@SCM_LIB.SCM(SCH_1):SPI_BMC_BIOS_ROM_CLK':
 C_SIGNAL='@scm_lib.scm(sch_1):spi_bmc_bios_rom_clk';
NODE_NAME     U5 AF8
 '@SCM_LIB.SCM(SCH_1):PAGE13_I363@PURE_QUANTA.AST2600A3GP(CHIPS)':
 'GPIOX3||SPI2CK': CDS_PINID='\gpiox3||spi2ck\';
NODE_NAME     R174 1
 '@SCM_LIB.SCM(SCH_1):PAGE44_I331@PURE_QUANTA.Q_RES(CHIPS)':
 'A': CDS_PINID='A';
NET_NAME
'SPI_BMC_BIOS_ROM_IO2'
 '@SCM_LIB.SCM(SCH_1):SPI_BMC_BIOS_ROM_IO2':
 C_SIGNAL='@scm_lib.scm(sch_1):spi_bmc_bios_rom_io2';
NODE_NAME     U5 AF9
 '@SCM_LIB.SCM(SCH_1):PAGE13_I363@PURE_QUANTA.AST2600A3GP(CHIPS)':
 'GPIOX6||SPI2DQ2||TXD12': CDS_PINID='\gpiox6||spi2dq2||txd12\';
NODE_NAME     R724 1
 '@SCM_LIB.SCM(SCH_1):PAGE44_I333@PURE_QUANTA.Q_RES(CHIPS)':
 'A': CDS_PINID='A';
NET_NAME
'SPI_BMC_BIOS_ROM_IO3'
 '@SCM_LIB.SCM(SCH_1):SPI_BMC_BIOS_ROM_IO3':
 C_SIGNAL='@scm_lib.scm(sch_1):spi_bmc_bios_rom_io3';
NODE_NAME     U5 AB10
 '@SCM_LIB.SCM(SCH_1):PAGE13_I363@PURE_QUANTA.AST2600A3GP(CHIPS)':
 'GPIOX7||SPI2DQ3||RXD12': CDS_PINID='\gpiox7||spi2dq3||rxd12\';
NODE_NAME     R725 1
 '@SCM_LIB.SCM(SCH_1):PAGE44_I334@PURE_QUANTA.Q_RES(CHIPS)':
 'A': CDS_PINID='A';
NET_NAME
'SPI_BMC_BIOS_ROM_MISO'
 '@SCM_LIB.SCM(SCH_1):SPI_BMC_BIOS_ROM_MISO':
 C_SIGNAL='@scm_lib.scm(sch_1):spi_bmc_bios_rom_miso';
NODE_NAME     U5 AD9
 '@SCM_LIB.SCM(SCH_1):PAGE13_I363@PURE_QUANTA.AST2600A3GP(CHIPS)':
 'GPIOX5||SPI2MISO': CDS_PINID='\gpiox5||spi2miso\';
NODE_NAME     R176 1
 '@SCM_LIB.SCM(SCH_1):PAGE44_I332@PURE_QUANTA.Q_RES(CHIPS)':
 'A': CDS_PINID='A';
NET_NAME
'SPI_BMC_BIOS_ROM_MOSI'
 '@SCM_LIB.SCM(SCH_1):SPI_BMC_BIOS_ROM_MOSI':
 C_SIGNAL='@scm_lib.scm(sch_1):spi_bmc_bios_rom_mosi';
NODE_NAME     U5 AB9
 '@SCM_LIB.SCM(SCH_1):PAGE13_I363@PURE_QUANTA.AST2600A3GP(CHIPS)':
 'GPIOX4||SPI2MOSI': CDS_PINID='\gpiox4||spi2mosi\';
NODE_NAME     R175 1
 '@SCM_LIB.SCM(SCH_1):PAGE44_I330@PURE_QUANTA.Q_RES(CHIPS)':
 'A': CDS_PINID='A';
NET_NAME
'SPI_BMC_BIOS_ROM_R_CLK'
 '@SCM_LIB.SCM(SCH_1):SPI_BMC_BIOS_ROM_R_CLK':
 C_SIGNAL='@scm_lib.scm(sch_1):spi_bmc_bios_rom_r_clk';
NODE_NAME     U30 10
 '@SCM_LIB.SCM(SCH_1):PAGE44_I271@PURE_QUANTA.IDTQS3VH257PAG(CHIPS)':
 'I_1C': CDS_PINID='I_1C';
NODE_NAME     R174 2
 '@SCM_LIB.SCM(SCH_1):PAGE44_I331@PURE_QUANTA.Q_RES(CHIPS)':
 'B': CDS_PINID='B';
NET_NAME
'SPI_BMC_BIOS_ROM_R_IO2'
 '@SCM_LIB.SCM(SCH_1):SPI_BMC_BIOS_ROM_R_IO2':
 C_SIGNAL='@scm_lib.scm(sch_1):spi_bmc_bios_rom_r_io2';
NODE_NAME     U21 3
 '@SCM_LIB.SCM(SCH_1):PAGE44_I296@PURE_QUANTA.IDTQS3VH257PAG(CHIPS)':
 'I_1A': CDS_PINID='I_1A';
NODE_NAME     R724 2
 '@SCM_LIB.SCM(SCH_1):PAGE44_I333@PURE_QUANTA.Q_RES(CHIPS)':
 'B': CDS_PINID='B';
NET_NAME
'SPI_BMC_BIOS_ROM_R_IO3'
 '@SCM_LIB.SCM(SCH_1):SPI_BMC_BIOS_ROM_R_IO3':
 C_SIGNAL='@scm_lib.scm(sch_1):spi_bmc_bios_rom_r_io3';
NODE_NAME     U30 6
 '@SCM_LIB.SCM(SCH_1):PAGE44_I271@PURE_QUANTA.IDTQS3VH257PAG(CHIPS)':
 'I_1B': CDS_PINID='I_1B';
NODE_NAME     R725 2
 '@SCM_LIB.SCM(SCH_1):PAGE44_I334@PURE_QUANTA.Q_RES(CHIPS)':
 'B': CDS_PINID='B';
NET_NAME
'SPI_BMC_BIOS_ROM_R_MISO'
 '@SCM_LIB.SCM(SCH_1):SPI_BMC_BIOS_ROM_R_MISO':
 C_SIGNAL='@scm_lib.scm(sch_1):spi_bmc_bios_rom_r_miso';
NODE_NAME     U21 6
 '@SCM_LIB.SCM(SCH_1):PAGE44_I296@PURE_QUANTA.IDTQS3VH257PAG(CHIPS)':
 'I_1B': CDS_PINID='I_1B';
NODE_NAME     R176 2
 '@SCM_LIB.SCM(SCH_1):PAGE44_I332@PURE_QUANTA.Q_RES(CHIPS)':
 'B': CDS_PINID='B';
NET_NAME
'SPI_BMC_BIOS_ROM_R_MOSI'
 '@SCM_LIB.SCM(SCH_1):SPI_BMC_BIOS_ROM_R_MOSI':
 C_SIGNAL='@scm_lib.scm(sch_1):spi_bmc_bios_rom_r_mosi';
NODE_NAME     U30 3
 '@SCM_LIB.SCM(SCH_1):PAGE44_I271@PURE_QUANTA.IDTQS3VH257PAG(CHIPS)':
 'I_1A': CDS_PINID='I_1A';
NODE_NAME     R175 2
 '@SCM_LIB.SCM(SCH_1):PAGE44_I330@PURE_QUANTA.Q_RES(CHIPS)':
 'B': CDS_PINID='B';
NET_NAME
'SPI_BMC_BIOS_SOURCE_CS0_N'
 '@SCM_LIB.SCM(SCH_1):SPI_BMC_BIOS_SOURCE_CS0_N':
 C_SIGNAL='@scm_lib.scm(sch_1):spi_bmc_bios_source_cs0_n';
NODE_NAME     U21 10
 '@SCM_LIB.SCM(SCH_1):PAGE44_I296@PURE_QUANTA.IDTQS3VH257PAG(CHIPS)':
 'I_1C': CDS_PINID='I_1C';
NODE_NAME     R728 2
 '@SCM_LIB.SCM(SCH_1):PAGE44_I336@PURE_QUANTA.Q_RES(CHIPS)':
 'B': CDS_PINID='B';
NET_NAME
'SPI_BMC_BOOT_CLK'
 '@SCM_LIB.SCM(SCH_1):SPI_BMC_BOOT_CLK':
 C_SIGNAL='@scm_lib.scm(sch_1):spi_bmc_boot_clk';
NODE_NAME     R178 2
 '@SCM_LIB.SCM(SCH_1):PAGE13_I94@PURE_QUANTA.Q_RES(CHIPS)':
 'B': CDS_PINID='B';
NODE_NAME     R699 2
 '@SCM_LIB.SCM(SCH_1):PAGE27_I163@PURE_QUANTA.Q_RES(CHIPS)':
 'B': CDS_PINID='B';
NODE_NAME     R549 2
 '@SCM_LIB.SCM(SCH_1):PAGE21_I177@PURE_QUANTA.Q_RES(CHIPS)':
 'B': CDS_PINID='B';
NET_NAME
'SPI_BMC_BOOT_CS0_R1_N'
 '@SCM_LIB.SCM(SCH_1):SPI_BMC_BOOT_CS0_R1_N':
 C_SIGNAL='@scm_lib.scm(sch_1):spi_bmc_boot_cs0_r1_n';
NODE_NAME     R801 2
 '@SCM_LIB.SCM(SCH_1):PAGE13_I217@PURE_QUANTA.Q_RES(CHIPS)':
 'B': CDS_PINID='B';
NODE_NAME     U5 AB14
 '@SCM_LIB.SCM(SCH_1):PAGE13_I363@PURE_QUANTA.AST2600A3GP(CHIPS)':
 'FWSPICS0#': CDS_PINID='\fwspics0#\';
NET_NAME
'SPI_BMC_BOOT_CS0_R_N'
 '@SCM_LIB.SCM(SCH_1):SPI_BMC_BOOT_CS0_R_N':
 C_SIGNAL='@scm_lib.scm(sch_1):spi_bmc_boot_cs0_r_n';
NODE_NAME     R801 1
 '@SCM_LIB.SCM(SCH_1):PAGE13_I217@PURE_QUANTA.Q_RES(CHIPS)':
 'A': CDS_PINID='A';
NODE_NAME     R553 2
 '@SCM_LIB.SCM(SCH_1):PAGE21_I175@PURE_QUANTA.Q_RES(CHIPS)':
 'B': CDS_PINID='B';
NET_NAME
'SPI_BMC_BOOT_CS1_R1_N'
 '@SCM_LIB.SCM(SCH_1):SPI_BMC_BOOT_CS1_R1_N':
 C_SIGNAL='@scm_lib.scm(sch_1):spi_bmc_boot_cs1_r1_n';
NODE_NAME     R802 2
 '@SCM_LIB.SCM(SCH_1):PAGE13_I218@PURE_QUANTA.Q_RES(CHIPS)':
 'B': CDS_PINID='B';
NODE_NAME     U5 AA13
 '@SCM_LIB.SCM(SCH_1):PAGE13_I363@PURE_QUANTA.AST2600A3GP(CHIPS)':
 'FWSPICS1#': CDS_PINID='\fwspics1#\';
NET_NAME
'SPI_BMC_BOOT_CS1_R_N'
 '@SCM_LIB.SCM(SCH_1):SPI_BMC_BOOT_CS1_R_N':
 C_SIGNAL='@scm_lib.scm(sch_1):spi_bmc_boot_cs1_r_n';
NODE_NAME     R802 1
 '@SCM_LIB.SCM(SCH_1):PAGE13_I218@PURE_QUANTA.Q_RES(CHIPS)':
 'A': CDS_PINID='A';
NODE_NAME     R547 2
 '@SCM_LIB.SCM(SCH_1):PAGE21_I176@PURE_QUANTA.Q_RES(CHIPS)':
 'B': CDS_PINID='B';
NET_NAME
'SPI_BMC_BOOT_MISO'
 '@SCM_LIB.SCM(SCH_1):SPI_BMC_BOOT_MISO':
 C_SIGNAL='@scm_lib.scm(sch_1):spi_bmc_boot_miso';
NODE_NAME     R180 2
 '@SCM_LIB.SCM(SCH_1):PAGE13_I96@PURE_QUANTA.Q_RES(CHIPS)':
 'B': CDS_PINID='B';
NODE_NAME     R753 2
 '@SCM_LIB.SCM(SCH_1):PAGE27_I233@PURE_QUANTA.Q_RES(CHIPS)':
 'B': CDS_PINID='B';
NODE_NAME     R164 1
 '@SCM_LIB.SCM(SCH_1):PAGE27_I244@PURE_QUANTA.Q_RES(CHIPS)':
 'A': CDS_PINID='A';
NODE_NAME     R552 2
 '@SCM_LIB.SCM(SCH_1):PAGE21_I179@PURE_QUANTA.Q_RES(CHIPS)':
 'B': CDS_PINID='B';
NET_NAME
'SPI_BMC_BOOT_MOSI'
 '@SCM_LIB.SCM(SCH_1):SPI_BMC_BOOT_MOSI':
 C_SIGNAL='@scm_lib.scm(sch_1):spi_bmc_boot_mosi';
NODE_NAME     R179 2
 '@SCM_LIB.SCM(SCH_1):PAGE13_I95@PURE_QUANTA.Q_RES(CHIPS)':
 'B': CDS_PINID='B';
NODE_NAME     R140 2
 '@SCM_LIB.SCM(SCH_1):PAGE27_I228@PURE_QUANTA.Q_RES(CHIPS)':
 'B': CDS_PINID='B';
NODE_NAME     R94 1
 '@SCM_LIB.SCM(SCH_1):PAGE27_I246@PURE_QUANTA.Q_RES(CHIPS)':
 'A': CDS_PINID='A';
NODE_NAME     R550 2
 '@SCM_LIB.SCM(SCH_1):PAGE21_I178@PURE_QUANTA.Q_RES(CHIPS)':
 'B': CDS_PINID='B';
NET_NAME
'SPI_BMC_BT_WP0_N_R'
 '@SCM_LIB.SCM(SCH_1):SPI_BMC_BT_WP0_N_R':
 C_SIGNAL='@scm_lib.scm(sch_1):spi_bmc_bt_wp0_n_r';
NODE_NAME     J4 5
 '@SCM_LIB.SCM(SCH_1):PAGE21_I84@PURE_QUANTA.SCONN67_NASA0S6730TS67(CHIPS)':
 '5': CDS_PINID='\5\';
NODE_NAME     R665 1
 '@SCM_LIB.SCM(SCH_1):PAGE21_I125@PURE_QUANTA.Q_RES(CHIPS)':
 'A': CDS_PINID='A';
NODE_NAME     R559 1
 '@SCM_LIB.SCM(SCH_1):PAGE25_I176@PURE_QUANTA.Q_RES(CHIPS)':
 'A': CDS_PINID='A';
NET_NAME
'SPI_BMC_BT_WP1_N_R'
 '@SCM_LIB.SCM(SCH_1):SPI_BMC_BT_WP1_N_R':
 C_SIGNAL='@scm_lib.scm(sch_1):spi_bmc_bt_wp1_n_r';
NODE_NAME     J4 3
 '@SCM_LIB.SCM(SCH_1):PAGE21_I84@PURE_QUANTA.SCONN67_NASA0S6730TS67(CHIPS)':
 '3': CDS_PINID='\3\';
NODE_NAME     R664 1
 '@SCM_LIB.SCM(SCH_1):PAGE21_I128@PURE_QUANTA.Q_RES(CHIPS)':
 'A': CDS_PINID='A';
NODE_NAME     R556 1
 '@SCM_LIB.SCM(SCH_1):PAGE25_I175@PURE_QUANTA.Q_RES(CHIPS)':
 'A': CDS_PINID='A';
NET_NAME
'SPI_BMC_CLK_FLASH_R'
 '@SCM_LIB.SCM(SCH_1):SPI_BMC_CLK_FLASH_R':
 C_SIGNAL='@scm_lib.scm(sch_1):spi_bmc_clk_flash_r';
NODE_NAME     J4 31
 '@SCM_LIB.SCM(SCH_1):PAGE21_I84@PURE_QUANTA.SCONN67_NASA0S6730TS67(CHIPS)':
 '31': CDS_PINID='\31\';
NODE_NAME     R549 1
 '@SCM_LIB.SCM(SCH_1):PAGE21_I177@PURE_QUANTA.Q_RES(CHIPS)':
 'A': CDS_PINID='A';
NET_NAME
'SPI_BMC_CLK_R'
 '@SCM_LIB.SCM(SCH_1):SPI_BMC_CLK_R':
 C_SIGNAL='@scm_lib.scm(sch_1):spi_bmc_clk_r';
NODE_NAME     R178 1
 '@SCM_LIB.SCM(SCH_1):PAGE13_I94@PURE_QUANTA.Q_RES(CHIPS)':
 'A': CDS_PINID='A';
NODE_NAME     R678 1
 '@SCM_LIB.SCM(SCH_1):PAGE13_I239@PURE_QUANTA.Q_RES(CHIPS)':
 'A': CDS_PINID='A';
NODE_NAME     U5 AF13
 '@SCM_LIB.SCM(SCH_1):PAGE13_I363@PURE_QUANTA.AST2600A3GP(CHIPS)':
 'FWSPICK': CDS_PINID='FWSPICK';
NET_NAME
'SPI_BMC_CS0_FLASH_R_N'
 '@SCM_LIB.SCM(SCH_1):SPI_BMC_CS0_FLASH_R_N':
 C_SIGNAL='@scm_lib.scm(sch_1):spi_bmc_cs0_flash_r_n';
NODE_NAME     J4 37
 '@SCM_LIB.SCM(SCH_1):PAGE21_I84@PURE_QUANTA.SCONN67_NASA0S6730TS67(CHIPS)':
 '37': CDS_PINID='\37\';
NODE_NAME     R557 2
 '@SCM_LIB.SCM(SCH_1):PAGE21_I173@PURE_QUANTA.Q_RES(CHIPS)':
 'B': CDS_PINID='B';
NODE_NAME     R553 1
 '@SCM_LIB.SCM(SCH_1):PAGE21_I175@PURE_QUANTA.Q_RES(CHIPS)':
 'A': CDS_PINID='A';
NET_NAME
'SPI_BMC_CS1_FLASH_R_N'
 '@SCM_LIB.SCM(SCH_1):SPI_BMC_CS1_FLASH_R_N':
 C_SIGNAL='@scm_lib.scm(sch_1):spi_bmc_cs1_flash_r_n';
NODE_NAME     J4 35
 '@SCM_LIB.SCM(SCH_1):PAGE21_I84@PURE_QUANTA.SCONN67_NASA0S6730TS67(CHIPS)':
 '35': CDS_PINID='\35\';
NODE_NAME     R558 2
 '@SCM_LIB.SCM(SCH_1):PAGE21_I174@PURE_QUANTA.Q_RES(CHIPS)':
 'B': CDS_PINID='B';
NODE_NAME     R547 1
 '@SCM_LIB.SCM(SCH_1):PAGE21_I176@PURE_QUANTA.Q_RES(CHIPS)':
 'A': CDS_PINID='A';
NET_NAME
'SPI_BMC_HOLD0_N'
 '@SCM_LIB.SCM(SCH_1):SPI_BMC_HOLD0_N':
 C_SIGNAL='@scm_lib.scm(sch_1):spi_bmc_hold0_n';
NODE_NAME     J4 28
 '@SCM_LIB.SCM(SCH_1):PAGE21_I84@PURE_QUANTA.SCONN67_NASA0S6730TS67(CHIPS)':
 '28': CDS_PINID='\28\';
NODE_NAME     R58 2
 '@SCM_LIB.SCM(SCH_1):PAGE21_I168@PURE_QUANTA.Q_RES(CHIPS)':
 'B': CDS_PINID='B';
NET_NAME
'SPI_BMC_HOLD1_N'
 '@SCM_LIB.SCM(SCH_1):SPI_BMC_HOLD1_N':
 C_SIGNAL='@scm_lib.scm(sch_1):spi_bmc_hold1_n';
NODE_NAME     J4 26
 '@SCM_LIB.SCM(SCH_1):PAGE21_I84@PURE_QUANTA.SCONN67_NASA0S6730TS67(CHIPS)':
 '26': CDS_PINID='\26\';
NODE_NAME     R543 2
 '@SCM_LIB.SCM(SCH_1):PAGE21_I147@PURE_QUANTA.Q_RES(CHIPS)':
 'B': CDS_PINID='B';
NET_NAME
'SPI_BMC_IO0_FLASH_R'
 '@SCM_LIB.SCM(SCH_1):SPI_BMC_IO0_FLASH_R':
 C_SIGNAL='@scm_lib.scm(sch_1):spi_bmc_io0_flash_r';
NODE_NAME     J4 27
 '@SCM_LIB.SCM(SCH_1):PAGE21_I84@PURE_QUANTA.SCONN67_NASA0S6730TS67(CHIPS)':
 '27': CDS_PINID='\27\';
NODE_NAME     R550 1
 '@SCM_LIB.SCM(SCH_1):PAGE21_I178@PURE_QUANTA.Q_RES(CHIPS)':
 'A': CDS_PINID='A';
NET_NAME
'SPI_BMC_IO1_FLASH_R'
 '@SCM_LIB.SCM(SCH_1):SPI_BMC_IO1_FLASH_R':
 C_SIGNAL='@scm_lib.scm(sch_1):spi_bmc_io1_flash_r';
NODE_NAME     J4 25
 '@SCM_LIB.SCM(SCH_1):PAGE21_I84@PURE_QUANTA.SCONN67_NASA0S6730TS67(CHIPS)':
 '25': CDS_PINID='\25\';
NODE_NAME     R552 1
 '@SCM_LIB.SCM(SCH_1):PAGE21_I179@PURE_QUANTA.Q_RES(CHIPS)':
 'A': CDS_PINID='A';
NET_NAME
'SPI_BMC_IO2_R'
 '@SCM_LIB.SCM(SCH_1):SPI_BMC_IO2_R':
 C_SIGNAL='@scm_lib.scm(sch_1):spi_bmc_io2_r';
NODE_NAME     R681 1
 '@SCM_LIB.SCM(SCH_1):PAGE13_I245@PURE_QUANTA.Q_RES(CHIPS)':
 'A': CDS_PINID='A';
NODE_NAME     U5 AE12
 '@SCM_LIB.SCM(SCH_1):PAGE13_I363@PURE_QUANTA.AST2600A3GP(CHIPS)':
 'GPIOY4||FWSPIDQ2': CDS_PINID='\gpioy4||fwspidq2\';
NET_NAME
'SPI_BMC_IO3_R'
 '@SCM_LIB.SCM(SCH_1):SPI_BMC_IO3_R':
 C_SIGNAL='@scm_lib.scm(sch_1):spi_bmc_io3_r';
NODE_NAME     R682 1
 '@SCM_LIB.SCM(SCH_1):PAGE13_I246@PURE_QUANTA.Q_RES(CHIPS)':
 'A': CDS_PINID='A';
NODE_NAME     U5 AF12
 '@SCM_LIB.SCM(SCH_1):PAGE13_I363@PURE_QUANTA.AST2600A3GP(CHIPS)':
 'GPIOY5||FWSPIDQ3': CDS_PINID='\gpioy5||fwspidq3\';
NET_NAME
'SPI_BMC_MISO_IO1_R'
 '@SCM_LIB.SCM(SCH_1):SPI_BMC_MISO_IO1_R':
 C_SIGNAL='@scm_lib.scm(sch_1):spi_bmc_miso_io1_r';
NODE_NAME     R180 1
 '@SCM_LIB.SCM(SCH_1):PAGE13_I96@PURE_QUANTA.Q_RES(CHIPS)':
 'A': CDS_PINID='A';
NODE_NAME     R680 1
 '@SCM_LIB.SCM(SCH_1):PAGE13_I248@PURE_QUANTA.Q_RES(CHIPS)':
 'A': CDS_PINID='A';
NODE_NAME     U5 AB13
 '@SCM_LIB.SCM(SCH_1):PAGE13_I363@PURE_QUANTA.AST2600A3GP(CHIPS)':
 'FWSPIMISO': CDS_PINID='FWSPIMISO';
NET_NAME
'SPI_BMC_MOSI_IO0_R'
 '@SCM_LIB.SCM(SCH_1):SPI_BMC_MOSI_IO0_R':
 C_SIGNAL='@scm_lib.scm(sch_1):spi_bmc_mosi_io0_r';
NODE_NAME     R179 1
 '@SCM_LIB.SCM(SCH_1):PAGE13_I95@PURE_QUANTA.Q_RES(CHIPS)':
 'A': CDS_PINID='A';
NODE_NAME     R679 1
 '@SCM_LIB.SCM(SCH_1):PAGE13_I247@PURE_QUANTA.Q_RES(CHIPS)':
 'A': CDS_PINID='A';
NODE_NAME     U5 AC14
 '@SCM_LIB.SCM(SCH_1):PAGE13_I363@PURE_QUANTA.AST2600A3GP(CHIPS)':
 'FWSPIMOSI': CDS_PINID='FWSPIMOSI';
NET_NAME
'SPI_BMC_TPM_CLK'
 '@SCM_LIB.SCM(SCH_1):SPI_BMC_TPM_CLK':
 C_SIGNAL='@scm_lib.scm(sch_1):spi_bmc_tpm_clk';
NODE_NAME     R109 2
 '@SCM_LIB.SCM(SCH_1):PAGE46_I114@PURE_QUANTA.Q_RES(CHIPS)':
 'B': CDS_PINID='B';
NODE_NAME     R408 2
 '@SCM_LIB.SCM(SCH_1):PAGE46_I139@PURE_QUANTA.Q_RES(CHIPS)':
 'B': CDS_PINID='B';
NODE_NAME     R468 2
 '@SCM_LIB.SCM(SCH_1):PAGE13_I449@PURE_QUANTA.Q_RES(CHIPS)':
 'B': CDS_PINID='B';
NET_NAME
'SPI_BMC_TPM_CLK_R'
 '@SCM_LIB.SCM(SCH_1):SPI_BMC_TPM_CLK_R':
 C_SIGNAL='@scm_lib.scm(sch_1):spi_bmc_tpm_clk_r';
NODE_NAME     J10 1
 '@SCM_LIB.SCM(SCH_1):PAGE46_I113@PURE_QUANTA.SCONN11_9192031111LF(CHIPS)':
 '1': CDS_PINID='\1\';
NODE_NAME     R109 1
 '@SCM_LIB.SCM(SCH_1):PAGE46_I114@PURE_QUANTA.Q_RES(CHIPS)':
 'A': CDS_PINID='A';
NET_NAME
'SPI_BMC_TPM_CLK_R1'
 '@SCM_LIB.SCM(SCH_1):SPI_BMC_TPM_CLK_R1':
 C_SIGNAL='@scm_lib.scm(sch_1):spi_bmc_tpm_clk_r1';
NODE_NAME     U5 AB11
 '@SCM_LIB.SCM(SCH_1):PAGE13_I363@PURE_QUANTA.AST2600A3GP(CHIPS)':
 'GPIOZ3||SPI1CK': CDS_PINID='\gpioz3||spi1ck\';
NODE_NAME     R468 1
 '@SCM_LIB.SCM(SCH_1):PAGE13_I449@PURE_QUANTA.Q_RES(CHIPS)':
 'A': CDS_PINID='A';
NET_NAME
'SPI_BMC_TPM_CS2_N_R'
 '@SCM_LIB.SCM(SCH_1):SPI_BMC_TPM_CS2_N_R':
 C_SIGNAL='@scm_lib.scm(sch_1):spi_bmc_tpm_cs2_n_r';
NODE_NAME     J10 5
 '@SCM_LIB.SCM(SCH_1):PAGE46_I113@PURE_QUANTA.SCONN11_9192031111LF(CHIPS)':
 '5': CDS_PINID='\5\';
NODE_NAME     R100 1
 '@SCM_LIB.SCM(SCH_1):PAGE46_I147@PURE_QUANTA.Q_RES(CHIPS)':
 'A': CDS_PINID='A';
NET_NAME
'SPI_BMC_TPM_CS2_R1_N'
 '@SCM_LIB.SCM(SCH_1):SPI_BMC_TPM_CS2_R1_N':
 C_SIGNAL='@scm_lib.scm(sch_1):spi_bmc_tpm_cs2_r1_n';
NODE_NAME     R460 2
 '@SCM_LIB.SCM(SCH_1):PAGE13_I312@PURE_QUANTA.Q_RES(CHIPS)':
 'B': CDS_PINID='B';
NODE_NAME     U5 AC10
 '@SCM_LIB.SCM(SCH_1):PAGE13_I363@PURE_QUANTA.AST2600A3GP(CHIPS)':
 'GPIOZ0||SPI1CS1#': CDS_PINID='\gpioz0||spi1cs1#\';
NET_NAME
'SPI_BMC_TPM_CS2_R_N'
 '@SCM_LIB.SCM(SCH_1):SPI_BMC_TPM_CS2_R_N':
 C_SIGNAL='@scm_lib.scm(sch_1):spi_bmc_tpm_cs2_r_n';
NODE_NAME     R238 2
 '@SCM_LIB.SCM(SCH_1):PAGE13_I184@PURE_QUANTA.Q_RES(CHIPS)':
 'B': CDS_PINID='B';
NODE_NAME     R460 1
 '@SCM_LIB.SCM(SCH_1):PAGE13_I312@PURE_QUANTA.Q_RES(CHIPS)':
 'A': CDS_PINID='A';
NODE_NAME     R100 2
 '@SCM_LIB.SCM(SCH_1):PAGE46_I147@PURE_QUANTA.Q_RES(CHIPS)':
 'B': CDS_PINID='B';
NET_NAME
'SPI_BMC_TPM_MISO'
 '@SCM_LIB.SCM(SCH_1):SPI_BMC_TPM_MISO':
 C_SIGNAL='@scm_lib.scm(sch_1):spi_bmc_tpm_miso';
NODE_NAME     R469 2
 '@SCM_LIB.SCM(SCH_1):PAGE13_I319@PURE_QUANTA.Q_RES(CHIPS)':
 'B': CDS_PINID='B';
NODE_NAME     R98 2
 '@SCM_LIB.SCM(SCH_1):PAGE46_I119@PURE_QUANTA.Q_RES(CHIPS)':
 'B': CDS_PINID='B';
NODE_NAME     R414 2
 '@SCM_LIB.SCM(SCH_1):PAGE46_I140@PURE_QUANTA.Q_RES(CHIPS)':
 'B': CDS_PINID='B';
NET_NAME
'SPI_BMC_TPM_MISO_R'
 '@SCM_LIB.SCM(SCH_1):SPI_BMC_TPM_MISO_R':
 C_SIGNAL='@scm_lib.scm(sch_1):spi_bmc_tpm_miso_r';
NODE_NAME     J10 4
 '@SCM_LIB.SCM(SCH_1):PAGE46_I113@PURE_QUANTA.SCONN11_9192031111LF(CHIPS)':
 '4': CDS_PINID='\4\';
NODE_NAME     R98 1
 '@SCM_LIB.SCM(SCH_1):PAGE46_I119@PURE_QUANTA.Q_RES(CHIPS)':
 'A': CDS_PINID='A';
NET_NAME
'SPI_BMC_TPM_MISO_R1'
 '@SCM_LIB.SCM(SCH_1):SPI_BMC_TPM_MISO_R1':
 C_SIGNAL='@scm_lib.scm(sch_1):spi_bmc_tpm_miso_r1';
NODE_NAME     R469 1
 '@SCM_LIB.SCM(SCH_1):PAGE13_I319@PURE_QUANTA.Q_RES(CHIPS)':
 'A': CDS_PINID='A';
NODE_NAME     U5 AA11
 '@SCM_LIB.SCM(SCH_1):PAGE13_I363@PURE_QUANTA.AST2600A3GP(CHIPS)':
 'GPIOZ5||SPI1MISO': CDS_PINID='\gpioz5||spi1miso\';
NET_NAME
'SPI_BMC_TPM_MOSI'
 '@SCM_LIB.SCM(SCH_1):SPI_BMC_TPM_MOSI':
 C_SIGNAL='@scm_lib.scm(sch_1):spi_bmc_tpm_mosi';
NODE_NAME     R309 2
 '@SCM_LIB.SCM(SCH_1):PAGE13_I360@PURE_QUANTA.Q_RES(CHIPS)':
 'B': CDS_PINID='B';
NODE_NAME     R97 2
 '@SCM_LIB.SCM(SCH_1):PAGE46_I115@PURE_QUANTA.Q_RES(CHIPS)':
 'B': CDS_PINID='B';
NODE_NAME     Q7 S
 '@SCM_LIB.SCM(SCH_1):PAGE27_I243@PURE_QUANTA.2N7002A7(CHIPS)':
 'S': CDS_PINID='S';
NET_NAME
'SPI_BMC_TPM_MOSI_R'
 '@SCM_LIB.SCM(SCH_1):SPI_BMC_TPM_MOSI_R':
 C_SIGNAL='@scm_lib.scm(sch_1):spi_bmc_tpm_mosi_r';
NODE_NAME     J10 3
 '@SCM_LIB.SCM(SCH_1):PAGE46_I113@PURE_QUANTA.SCONN11_9192031111LF(CHIPS)':
 '3': CDS_PINID='\3\';
NODE_NAME     R97 1
 '@SCM_LIB.SCM(SCH_1):PAGE46_I115@PURE_QUANTA.Q_RES(CHIPS)':
 'A': CDS_PINID='A';
NET_NAME
'SPI_BMC_TPM_MOSI_R1'
 '@SCM_LIB.SCM(SCH_1):SPI_BMC_TPM_MOSI_R1':
 C_SIGNAL='@scm_lib.scm(sch_1):spi_bmc_tpm_mosi_r1';
NODE_NAME     R309 1
 '@SCM_LIB.SCM(SCH_1):PAGE13_I360@PURE_QUANTA.Q_RES(CHIPS)':
 'A': CDS_PINID='A';
NODE_NAME     U5 AC11
 '@SCM_LIB.SCM(SCH_1):PAGE13_I363@PURE_QUANTA.AST2600A3GP(CHIPS)':
 'GPIOZ4||SPI1MOSI': CDS_PINID='\gpioz4||spi1mosi\';
NET_NAME
'SPI_PCH_CLK_FLASH_R1'
 '@SCM_LIB.SCM(SCH_1):SPI_PCH_CLK_FLASH_R1':
 C_SIGNAL='@scm_lib.scm(sch_1):spi_pch_clk_flash_r1';
NODE_NAME     R481 2
 '@SCM_LIB.SCM(SCH_1):PAGE45_I24@PURE_QUANTA.Q_RES(CHIPS)':
 'B': CDS_PINID='B';
NODE_NAME     J40 16
 '@SCM_LIB.SCM(SCH_1):PAGE45_I53@PURE_QUANTA.SCONN16_ACASPI006P06(CHIPS)':
 'CLK': CDS_PINID='CLK';
NODE_NAME     U17 16
 '@SCM_LIB.SCM(SCH_1):PAGE45_I54@PURE_QUANTA.MX25L51245GMI10G(CHIPS)':
 'SCLK': CDS_PINID='SCLK';
NET_NAME
'SPI_PCH_CS0_FLASH_R1_N'
 '@SCM_LIB.SCM(SCH_1):SPI_PCH_CS0_FLASH_R1_N':
 C_SIGNAL='@scm_lib.scm(sch_1):spi_pch_cs0_flash_r1_n';
NODE_NAME     R485 2
 '@SCM_LIB.SCM(SCH_1):PAGE45_I20@PURE_QUANTA.Q_RES(CHIPS)':
 'B': CDS_PINID='B';
NODE_NAME     R490 2
 '@SCM_LIB.SCM(SCH_1):PAGE45_I34@PURE_QUANTA.Q_RES(CHIPS)':
 'B': CDS_PINID='B';
NODE_NAME     R487 1
 '@SCM_LIB.SCM(SCH_1):PAGE45_I51@PURE_QUANTA.Q_RES(CHIPS)':
 'A': CDS_PINID='A';
NODE_NAME     J40 7
 '@SCM_LIB.SCM(SCH_1):PAGE45_I53@PURE_QUANTA.SCONN16_ACASPI006P06(CHIPS)':
 'CS_N': CDS_PINID='CS_N';
NODE_NAME     U17 7
 '@SCM_LIB.SCM(SCH_1):PAGE45_I54@PURE_QUANTA.MX25L51245GMI10G(CHIPS)':
 'CS#': CDS_PINID='\cs#\';
NET_NAME
'SPI_PCH_IO0_FLASH_R1'
 '@SCM_LIB.SCM(SCH_1):SPI_PCH_IO0_FLASH_R1':
 C_SIGNAL='@scm_lib.scm(sch_1):spi_pch_io0_flash_r1';
NODE_NAME     R482 2
 '@SCM_LIB.SCM(SCH_1):PAGE45_I22@PURE_QUANTA.Q_RES(CHIPS)':
 'B': CDS_PINID='B';
NODE_NAME     J40 15
 '@SCM_LIB.SCM(SCH_1):PAGE45_I53@PURE_QUANTA.SCONN16_ACASPI006P06(CHIPS)':
 'DI': CDS_PINID='DI';
NODE_NAME     U17 15
 '@SCM_LIB.SCM(SCH_1):PAGE45_I54@PURE_QUANTA.MX25L51245GMI10G(CHIPS)':
 'SI_SIO0': CDS_PINID='SI_SIO0';
NET_NAME
'SPI_PCH_IO1_FLASH_R1'
 '@SCM_LIB.SCM(SCH_1):SPI_PCH_IO1_FLASH_R1':
 C_SIGNAL='@scm_lib.scm(sch_1):spi_pch_io1_flash_r1';
NODE_NAME     R484 2
 '@SCM_LIB.SCM(SCH_1):PAGE45_I21@PURE_QUANTA.Q_RES(CHIPS)':
 'B': CDS_PINID='B';
NODE_NAME     J40 8
 '@SCM_LIB.SCM(SCH_1):PAGE45_I53@PURE_QUANTA.SCONN16_ACASPI006P06(CHIPS)':
 'DO': CDS_PINID='DO';
NODE_NAME     U17 8
 '@SCM_LIB.SCM(SCH_1):PAGE45_I54@PURE_QUANTA.MX25L51245GMI10G(CHIPS)':
 'SO_SIO1': CDS_PINID='SO_SIO1';
NET_NAME
'SPI_PCH_IO2_FLASH_R1'
 '@SCM_LIB.SCM(SCH_1):SPI_PCH_IO2_FLASH_R1':
 C_SIGNAL='@scm_lib.scm(sch_1):spi_pch_io2_flash_r1';
NODE_NAME     R483 2
 '@SCM_LIB.SCM(SCH_1):PAGE45_I23@PURE_QUANTA.Q_RES(CHIPS)':
 'B': CDS_PINID='B';
NODE_NAME     R488 2
 '@SCM_LIB.SCM(SCH_1):PAGE45_I33@PURE_QUANTA.Q_RES(CHIPS)':
 'B': CDS_PINID='B';
NODE_NAME     J40 9
 '@SCM_LIB.SCM(SCH_1):PAGE45_I53@PURE_QUANTA.SCONN16_ACASPI006P06(CHIPS)':
 'WP_N': CDS_PINID='WP_N';
NODE_NAME     U17 9
 '@SCM_LIB.SCM(SCH_1):PAGE45_I54@PURE_QUANTA.MX25L51245GMI10G(CHIPS)':
 'WP#_SIO2': CDS_PINID='\wp#_sio2\';
NET_NAME
'SPI_PCH_IO3_FLASH_R1'
 '@SCM_LIB.SCM(SCH_1):SPI_PCH_IO3_FLASH_R1':
 C_SIGNAL='@scm_lib.scm(sch_1):spi_pch_io3_flash_r1';
NODE_NAME     R486 2
 '@SCM_LIB.SCM(SCH_1):PAGE45_I19@PURE_QUANTA.Q_RES(CHIPS)':
 'B': CDS_PINID='B';
NODE_NAME     R492 2
 '@SCM_LIB.SCM(SCH_1):PAGE45_I35@PURE_QUANTA.Q_RES(CHIPS)':
 'B': CDS_PINID='B';
NODE_NAME     J40 1
 '@SCM_LIB.SCM(SCH_1):PAGE45_I53@PURE_QUANTA.SCONN16_ACASPI006P06(CHIPS)':
 'HOLD_N': CDS_PINID='HOLD_N';
NODE_NAME     U17 1
 '@SCM_LIB.SCM(SCH_1):PAGE45_I54@PURE_QUANTA.MX25L51245GMI10G(CHIPS)':
 'NC_SIO3': CDS_PINID='NC_SIO3';
NET_NAME
'SPI_PCH_MUXED_CLK'
 '@SCM_LIB.SCM(SCH_1):SPI_PCH_MUXED_CLK':
 C_SIGNAL='@scm_lib.scm(sch_1):spi_pch_muxed_clk';
NODE_NAME     U30 9
 '@SCM_LIB.SCM(SCH_1):PAGE44_I271@PURE_QUANTA.IDTQS3VH257PAG(CHIPS)':
 'YC': CDS_PINID='YC';
NODE_NAME     R481 1
 '@SCM_LIB.SCM(SCH_1):PAGE45_I24@PURE_QUANTA.Q_RES(CHIPS)':
 'A': CDS_PINID='A';
NET_NAME
'SPI_PCH_MUXED_CS0_N'
 '@SCM_LIB.SCM(SCH_1):SPI_PCH_MUXED_CS0_N':
 C_SIGNAL='@scm_lib.scm(sch_1):spi_pch_muxed_cs0_n';
NODE_NAME     U21 9
 '@SCM_LIB.SCM(SCH_1):PAGE44_I296@PURE_QUANTA.IDTQS3VH257PAG(CHIPS)':
 'YC': CDS_PINID='YC';
NODE_NAME     R485 1
 '@SCM_LIB.SCM(SCH_1):PAGE45_I20@PURE_QUANTA.Q_RES(CHIPS)':
 'A': CDS_PINID='A';
NET_NAME
'SPI_PCH_MUXED_IO0'
 '@SCM_LIB.SCM(SCH_1):SPI_PCH_MUXED_IO0':
 C_SIGNAL='@scm_lib.scm(sch_1):spi_pch_muxed_io0';
NODE_NAME     U30 4
 '@SCM_LIB.SCM(SCH_1):PAGE44_I271@PURE_QUANTA.IDTQS3VH257PAG(CHIPS)':
 'YA': CDS_PINID='YA';
NODE_NAME     R482 1
 '@SCM_LIB.SCM(SCH_1):PAGE45_I22@PURE_QUANTA.Q_RES(CHIPS)':
 'A': CDS_PINID='A';
NET_NAME
'SPI_PCH_MUXED_IO1'
 '@SCM_LIB.SCM(SCH_1):SPI_PCH_MUXED_IO1':
 C_SIGNAL='@scm_lib.scm(sch_1):spi_pch_muxed_io1';
NODE_NAME     U21 7
 '@SCM_LIB.SCM(SCH_1):PAGE44_I296@PURE_QUANTA.IDTQS3VH257PAG(CHIPS)':
 'YB': CDS_PINID='YB';
NODE_NAME     R484 1
 '@SCM_LIB.SCM(SCH_1):PAGE45_I21@PURE_QUANTA.Q_RES(CHIPS)':
 'A': CDS_PINID='A';
NET_NAME
'SPI_PCH_MUXED_IO2'
 '@SCM_LIB.SCM(SCH_1):SPI_PCH_MUXED_IO2':
 C_SIGNAL='@scm_lib.scm(sch_1):spi_pch_muxed_io2';
NODE_NAME     U21 4
 '@SCM_LIB.SCM(SCH_1):PAGE44_I296@PURE_QUANTA.IDTQS3VH257PAG(CHIPS)':
 'YA': CDS_PINID='YA';
NODE_NAME     R483 1
 '@SCM_LIB.SCM(SCH_1):PAGE45_I23@PURE_QUANTA.Q_RES(CHIPS)':
 'A': CDS_PINID='A';
NET_NAME
'SPI_PCH_MUXED_IO3'
 '@SCM_LIB.SCM(SCH_1):SPI_PCH_MUXED_IO3':
 C_SIGNAL='@scm_lib.scm(sch_1):spi_pch_muxed_io3';
NODE_NAME     U30 7
 '@SCM_LIB.SCM(SCH_1):PAGE44_I271@PURE_QUANTA.IDTQS3VH257PAG(CHIPS)':
 'YB': CDS_PINID='YB';
NODE_NAME     R486 1
 '@SCM_LIB.SCM(SCH_1):PAGE45_I19@PURE_QUANTA.Q_RES(CHIPS)':
 'A': CDS_PINID='A';
NET_NAME
'SPI_PCH_SECURE_CS0_N'
 '@SCM_LIB.SCM(SCH_1):SPI_PCH_SECURE_CS0_N':
 C_SIGNAL='@scm_lib.scm(sch_1):spi_pch_secure_cs0_n';
NODE_NAME     U21 11
 '@SCM_LIB.SCM(SCH_1):PAGE44_I296@PURE_QUANTA.IDTQS3VH257PAG(CHIPS)':
 'I_0C': CDS_PINID='I_0C';
NODE_NAME     R864 2
 '@SCM_LIB.SCM(SCH_1):PAGE44_I342@PURE_QUANTA.Q_RES(CHIPS)':
 'B': CDS_PINID='B';
NET_NAME
'SPI_SYS_CS0_N'
 '@SCM_LIB.SCM(SCH_1):SPI_SYS_CS0_N':
 C_SIGNAL='@scm_lib.scm(sch_1):spi_sys_cs0_n';
NODE_NAME     GF1 B12
 '@SCM_LIB.SCM(SCH_1):PAGE10_I553@PURE_QUANTA.FCONN168_ME1016810202011_SCM(CHIPS)':
 'QSPI0_CS0_N': CDS_PINID='QSPI0_CS0_N';
NODE_NAME     R864 1
 '@SCM_LIB.SCM(SCH_1):PAGE44_I342@PURE_QUANTA.Q_RES(CHIPS)':
 'A': CDS_PINID='A';
NET_NAME
'SPI_SYS_HOLD_R_IO3'
 '@SCM_LIB.SCM(SCH_1):SPI_SYS_HOLD_R_IO3':
 C_SIGNAL='@scm_lib.scm(sch_1):spi_sys_hold_r_io3';
NODE_NAME     GF1 B16
 '@SCM_LIB.SCM(SCH_1):PAGE10_I553@PURE_QUANTA.FCONN168_ME1016810202011_SCM(CHIPS)':
 'QSPI0_D3': CDS_PINID='QSPI0_D3';
NODE_NAME     R863 1
 '@SCM_LIB.SCM(SCH_1):PAGE44_I365@PURE_QUANTA.Q_RES(CHIPS)':
 'A': CDS_PINID='A';
NET_NAME
'SPI_SYS_MUX_CLK'
 '@SCM_LIB.SCM(SCH_1):SPI_SYS_MUX_CLK':
 C_SIGNAL='@scm_lib.scm(sch_1):spi_sys_mux_clk';
NODE_NAME     U30 11
 '@SCM_LIB.SCM(SCH_1):PAGE44_I271@PURE_QUANTA.IDTQS3VH257PAG(CHIPS)':
 'I_0C': CDS_PINID='I_0C';
NODE_NAME     R859 2
 '@SCM_LIB.SCM(SCH_1):PAGE44_I339@PURE_QUANTA.Q_RES(CHIPS)':
 'B': CDS_PINID='B';
NET_NAME
'SPI_SYS_MUX_HOLD_IO3'
 '@SCM_LIB.SCM(SCH_1):SPI_SYS_MUX_HOLD_IO3':
 C_SIGNAL='@scm_lib.scm(sch_1):spi_sys_mux_hold_io3';
NODE_NAME     U30 5
 '@SCM_LIB.SCM(SCH_1):PAGE44_I271@PURE_QUANTA.IDTQS3VH257PAG(CHIPS)':
 'I_0B': CDS_PINID='I_0B';
NODE_NAME     R863 2
 '@SCM_LIB.SCM(SCH_1):PAGE44_I365@PURE_QUANTA.Q_RES(CHIPS)':
 'B': CDS_PINID='B';
NET_NAME
'SPI_SYS_MUX_MISO'
 '@SCM_LIB.SCM(SCH_1):SPI_SYS_MUX_MISO':
 C_SIGNAL='@scm_lib.scm(sch_1):spi_sys_mux_miso';
NODE_NAME     U21 5
 '@SCM_LIB.SCM(SCH_1):PAGE44_I296@PURE_QUANTA.IDTQS3VH257PAG(CHIPS)':
 'I_0B': CDS_PINID='I_0B';
NODE_NAME     R861 2
 '@SCM_LIB.SCM(SCH_1):PAGE44_I363@PURE_QUANTA.Q_RES(CHIPS)':
 'B': CDS_PINID='B';
NET_NAME
'SPI_SYS_MUX_MOSI'
 '@SCM_LIB.SCM(SCH_1):SPI_SYS_MUX_MOSI':
 C_SIGNAL='@scm_lib.scm(sch_1):spi_sys_mux_mosi';
NODE_NAME     U30 2
 '@SCM_LIB.SCM(SCH_1):PAGE44_I271@PURE_QUANTA.IDTQS3VH257PAG(CHIPS)':
 'I_0A': CDS_PINID='I_0A';
NODE_NAME     R860 2
 '@SCM_LIB.SCM(SCH_1):PAGE44_I362@PURE_QUANTA.Q_RES(CHIPS)':
 'B': CDS_PINID='B';
NET_NAME
'SPI_SYS_MUX_WP_IO2'
 '@SCM_LIB.SCM(SCH_1):SPI_SYS_MUX_WP_IO2':
 C_SIGNAL='@scm_lib.scm(sch_1):spi_sys_mux_wp_io2';
NODE_NAME     U21 2
 '@SCM_LIB.SCM(SCH_1):PAGE44_I296@PURE_QUANTA.IDTQS3VH257PAG(CHIPS)':
 'I_0A': CDS_PINID='I_0A';
NODE_NAME     R862 2
 '@SCM_LIB.SCM(SCH_1):PAGE44_I364@PURE_QUANTA.Q_RES(CHIPS)':
 'B': CDS_PINID='B';
NET_NAME
'SPI_SYS_R1_CLK'
 '@SCM_LIB.SCM(SCH_1):SPI_SYS_R1_CLK':
 C_SIGNAL='@scm_lib.scm(sch_1):spi_sys_r1_clk';
NODE_NAME     J5 1
 '@SCM_LIB.SCM(SCH_1):PAGE46_I56@PURE_QUANTA.SCONN11_9192031111LF(CHIPS)':
 '1': CDS_PINID='\1\';
NODE_NAME     R501 1
 '@SCM_LIB.SCM(SCH_1):PAGE46_I58@PURE_QUANTA.Q_RES(CHIPS)':
 'A': CDS_PINID='A';
NET_NAME
'SPI_SYS_R1_MISO'
 '@SCM_LIB.SCM(SCH_1):SPI_SYS_R1_MISO':
 C_SIGNAL='@scm_lib.scm(sch_1):spi_sys_r1_miso';
NODE_NAME     J5 4
 '@SCM_LIB.SCM(SCH_1):PAGE46_I56@PURE_QUANTA.SCONN11_9192031111LF(CHIPS)':
 '4': CDS_PINID='\4\';
NODE_NAME     R499 2
 '@SCM_LIB.SCM(SCH_1):PAGE46_I136@PURE_QUANTA.Q_RES(CHIPS)':
 'B': CDS_PINID='B';
NET_NAME
'SPI_SYS_R1_MOSI'
 '@SCM_LIB.SCM(SCH_1):SPI_SYS_R1_MOSI':
 C_SIGNAL='@scm_lib.scm(sch_1):spi_sys_r1_mosi';
NODE_NAME     J5 3
 '@SCM_LIB.SCM(SCH_1):PAGE46_I56@PURE_QUANTA.SCONN11_9192031111LF(CHIPS)':
 '3': CDS_PINID='\3\';
NODE_NAME     R498 2
 '@SCM_LIB.SCM(SCH_1):PAGE46_I137@PURE_QUANTA.Q_RES(CHIPS)':
 'B': CDS_PINID='B';
NET_NAME
'SPI_SYS_R_CLK'
 '@SCM_LIB.SCM(SCH_1):SPI_SYS_R_CLK':
 C_SIGNAL='@scm_lib.scm(sch_1):spi_sys_r_clk';
NODE_NAME     GF1 B11
 '@SCM_LIB.SCM(SCH_1):PAGE10_I553@PURE_QUANTA.FCONN168_ME1016810202011_SCM(CHIPS)':
 'QSPI0_CLK': CDS_PINID='QSPI0_CLK';
NODE_NAME     R859 1
 '@SCM_LIB.SCM(SCH_1):PAGE44_I339@PURE_QUANTA.Q_RES(CHIPS)':
 'A': CDS_PINID='A';
NODE_NAME     R501 2
 '@SCM_LIB.SCM(SCH_1):PAGE46_I58@PURE_QUANTA.Q_RES(CHIPS)':
 'B': CDS_PINID='B';
NET_NAME
'SPI_SYS_R_MISO'
 '@SCM_LIB.SCM(SCH_1):SPI_SYS_R_MISO':
 C_SIGNAL='@scm_lib.scm(sch_1):spi_sys_r_miso';
NODE_NAME     GF1 B14
 '@SCM_LIB.SCM(SCH_1):PAGE10_I553@PURE_QUANTA.FCONN168_ME1016810202011_SCM(CHIPS)':
 'QSPI0_D1': CDS_PINID='QSPI0_D1';
NODE_NAME     R861 1
 '@SCM_LIB.SCM(SCH_1):PAGE44_I363@PURE_QUANTA.Q_RES(CHIPS)':
 'A': CDS_PINID='A';
NODE_NAME     R499 1
 '@SCM_LIB.SCM(SCH_1):PAGE46_I136@PURE_QUANTA.Q_RES(CHIPS)':
 'A': CDS_PINID='A';
NET_NAME
'SPI_SYS_R_MOSI'
 '@SCM_LIB.SCM(SCH_1):SPI_SYS_R_MOSI':
 C_SIGNAL='@scm_lib.scm(sch_1):spi_sys_r_mosi';
NODE_NAME     GF1 B13
 '@SCM_LIB.SCM(SCH_1):PAGE10_I553@PURE_QUANTA.FCONN168_ME1016810202011_SCM(CHIPS)':
 'QSPI0_D0': CDS_PINID='QSPI0_D0';
NODE_NAME     R860 1
 '@SCM_LIB.SCM(SCH_1):PAGE44_I362@PURE_QUANTA.Q_RES(CHIPS)':
 'A': CDS_PINID='A';
NODE_NAME     R498 1
 '@SCM_LIB.SCM(SCH_1):PAGE46_I137@PURE_QUANTA.Q_RES(CHIPS)':
 'A': CDS_PINID='A';
NET_NAME
'SPI_SYS_WP_R_IO2'
 '@SCM_LIB.SCM(SCH_1):SPI_SYS_WP_R_IO2':
 C_SIGNAL='@scm_lib.scm(sch_1):spi_sys_wp_r_io2';
NODE_NAME     GF1 B15
 '@SCM_LIB.SCM(SCH_1):PAGE10_I553@PURE_QUANTA.FCONN168_ME1016810202011_SCM(CHIPS)':
 'QSPI0_D2': CDS_PINID='QSPI0_D2';
NODE_NAME     R862 1
 '@SCM_LIB.SCM(SCH_1):PAGE44_I364@PURE_QUANTA.Q_RES(CHIPS)':
 'A': CDS_PINID='A';
NET_NAME
'SPI_TPM_CS_N'
 '@SCM_LIB.SCM(SCH_1):SPI_TPM_CS_N':
 C_SIGNAL='@scm_lib.scm(sch_1):spi_tpm_cs_n';
NODE_NAME     GF1 OB12
 '@SCM_LIB.SCM(SCH_1):PAGE10_I553@PURE_QUANTA.FCONN168_ME1016810202011_SCM(CHIPS)':
 'SPI0_CS_N': CDS_PINID='SPI0_CS_N';
NODE_NAME     R594 1
 '@SCM_LIB.SCM(SCH_1):PAGE44_I360@PURE_QUANTA.Q_RES(CHIPS)':
 'A': CDS_PINID='A';
NET_NAME
'SPI_TPM_CS_N_R'
 '@SCM_LIB.SCM(SCH_1):SPI_TPM_CS_N_R':
 C_SIGNAL='@scm_lib.scm(sch_1):spi_tpm_cs_n_r';
NODE_NAME     J5 5
 '@SCM_LIB.SCM(SCH_1):PAGE46_I56@PURE_QUANTA.SCONN11_9192031111LF(CHIPS)':
 '5': CDS_PINID='\5\';
NODE_NAME     R500 1
 '@SCM_LIB.SCM(SCH_1):PAGE46_I65@PURE_QUANTA.Q_RES(CHIPS)':
 'A': CDS_PINID='A';
NET_NAME
'SPI_TPM_CS_R_N'
 '@SCM_LIB.SCM(SCH_1):SPI_TPM_CS_R_N':
 C_SIGNAL='@scm_lib.scm(sch_1):spi_tpm_cs_r_n';
NODE_NAME     R594 2
 '@SCM_LIB.SCM(SCH_1):PAGE44_I360@PURE_QUANTA.Q_RES(CHIPS)':
 'B': CDS_PINID='B';
NODE_NAME     R500 2
 '@SCM_LIB.SCM(SCH_1):PAGE46_I65@PURE_QUANTA.Q_RES(CHIPS)':
 'B': CDS_PINID='B';
NET_NAME
'SW_P1V0_AUX_BST'
 '@SCM_LIB.SCM(SCH_1):SW_P1V0_AUX_BST':
 C_SIGNAL='@scm_lib.scm(sch_1):sw_p1v0_aux_bst';
NODE_NAME     PU42 9
 '@SCM_LIB.SCM(SCH_1):PAGE56_I15@PURE_QUANTA.NB695GDZ(CHIPS)':
 'BST': CDS_PINID='BST';
NODE_NAME     PC264 1
 '@SCM_LIB.SCM(SCH_1):PAGE56_I19@PURE_QUANTA.Q_CAP(CHIPS)':
 'A': CDS_PINID='A';
NET_NAME
'SW_P1V0_AUX_FLT'
 '@SCM_LIB.SCM(SCH_1):SW_P1V0_AUX_FLT':
 C_SIGNAL='@scm_lib.scm(sch_1):sw_p1v0_aux_flt';
NODE_NAME     PU42 1
 '@SCM_LIB.SCM(SCH_1):PAGE56_I15@PURE_QUANTA.NB695GDZ(CHIPS)':
 'VIN': CDS_PINID='VIN';
NODE_NAME     PC263 1
 '@SCM_LIB.SCM(SCH_1):PAGE56_I16@PURE_QUANTA.Q_CAP(CHIPS)':
 'A': CDS_PINID='A';
NODE_NAME     PL32 2
 '@SCM_LIB.SCM(SCH_1):PAGE56_I34@PURE_QUANTA.Q_INDUCTOR(CHIPS)':
 '2': CDS_PINID='\2\';
NODE_NAME     PC262 1
 '@SCM_LIB.SCM(SCH_1):PAGE56_I43@PURE_QUANTA.Q_CAP(CHIPS)':
 'A': CDS_PINID='A';
NODE_NAME     PC261 1
 '@SCM_LIB.SCM(SCH_1):PAGE56_I44@PURE_QUANTA.Q_CAP(CHIPS)':
 'A': CDS_PINID='A';
NET_NAME
'SW_P1V0_AUX_SW'
 '@SCM_LIB.SCM(SCH_1):SW_P1V0_AUX_SW':
 C_SIGNAL='@scm_lib.scm(sch_1):sw_p1v0_aux_sw';
NODE_NAME     PU42 8
 '@SCM_LIB.SCM(SCH_1):PAGE56_I15@PURE_QUANTA.NB695GDZ(CHIPS)':
 'SW': CDS_PINID='SW';
NODE_NAME     PC264 2
 '@SCM_LIB.SCM(SCH_1):PAGE56_I19@PURE_QUANTA.Q_CAP(CHIPS)':
 'B': CDS_PINID='B';
NODE_NAME     PL33 1
 '@SCM_LIB.SCM(SCH_1):PAGE56_I37@PURE_QUANTA.Q_INDUCTOR(CHIPS)':
 '1': CDS_PINID='\1\';
NET_NAME
'SW_P1V2_AUX_BST'
 '@SCM_LIB.SCM(SCH_1):SW_P1V2_AUX_BST':
 C_SIGNAL='@scm_lib.scm(sch_1):sw_p1v2_aux_bst';
NODE_NAME     PU41 9
 '@SCM_LIB.SCM(SCH_1):PAGE55_I15@PURE_QUANTA.NB695GDZ(CHIPS)':
 'BST': CDS_PINID='BST';
NODE_NAME     PC254 1
 '@SCM_LIB.SCM(SCH_1):PAGE55_I19@PURE_QUANTA.Q_CAP(CHIPS)':
 'A': CDS_PINID='A';
NET_NAME
'SW_P1V2_AUX_FLT'
 '@SCM_LIB.SCM(SCH_1):SW_P1V2_AUX_FLT':
 C_SIGNAL='@scm_lib.scm(sch_1):sw_p1v2_aux_flt';
NODE_NAME     PU41 1
 '@SCM_LIB.SCM(SCH_1):PAGE55_I15@PURE_QUANTA.NB695GDZ(CHIPS)':
 'VIN': CDS_PINID='VIN';
NODE_NAME     PC253 1
 '@SCM_LIB.SCM(SCH_1):PAGE55_I16@PURE_QUANTA.Q_CAP(CHIPS)':
 'A': CDS_PINID='A';
NODE_NAME     PL29 2
 '@SCM_LIB.SCM(SCH_1):PAGE55_I31@PURE_QUANTA.Q_INDUCTOR(CHIPS)':
 '2': CDS_PINID='\2\';
NODE_NAME     PC252 1
 '@SCM_LIB.SCM(SCH_1):PAGE55_I42@PURE_QUANTA.Q_CAP(CHIPS)':
 'A': CDS_PINID='A';
NODE_NAME     PC251 1
 '@SCM_LIB.SCM(SCH_1):PAGE55_I43@PURE_QUANTA.Q_CAP(CHIPS)':
 'A': CDS_PINID='A';
NET_NAME
'SW_P1V2_AUX_SW'
 '@SCM_LIB.SCM(SCH_1):SW_P1V2_AUX_SW':
 C_SIGNAL='@scm_lib.scm(sch_1):sw_p1v2_aux_sw';
NODE_NAME     PU41 8
 '@SCM_LIB.SCM(SCH_1):PAGE55_I15@PURE_QUANTA.NB695GDZ(CHIPS)':
 'SW': CDS_PINID='SW';
NODE_NAME     PC254 2
 '@SCM_LIB.SCM(SCH_1):PAGE55_I19@PURE_QUANTA.Q_CAP(CHIPS)':
 'B': CDS_PINID='B';
NODE_NAME     PL31 1
 '@SCM_LIB.SCM(SCH_1):PAGE55_I21@PURE_QUANTA.Q_INDUCTOR(CHIPS)':
 '1': CDS_PINID='\1\';
NET_NAME
'SW_P3V3_AUX_BST'
 '@SCM_LIB.SCM(SCH_1):SW_P3V3_AUX_BST':
 C_SIGNAL='@scm_lib.scm(sch_1):sw_p3v3_aux_bst';
NODE_NAME     PC224 1
 '@SCM_LIB.SCM(SCH_1):PAGE52_I15@PURE_QUANTA.Q_CAP(CHIPS)':
 'A': CDS_PINID='A';
NODE_NAME     R415 2
 '@SCM_LIB.SCM(SCH_1):PAGE52_I146@PURE_QUANTA.Q_RES(CHIPS)':
 'B': CDS_PINID='B';
NET_NAME
'SW_P3V3_AUX_BST_R'
 '@SCM_LIB.SCM(SCH_1):SW_P3V3_AUX_BST_R':
 C_SIGNAL='@scm_lib.scm(sch_1):sw_p3v3_aux_bst_r';
NODE_NAME     PU1 10
 '@SCM_LIB.SCM(SCH_1):PAGE52_I82@PURE_QUANTA.MPQ8626GDZ(CHIPS)':
 'BST': CDS_PINID='BST';
NODE_NAME     R415 1
 '@SCM_LIB.SCM(SCH_1):PAGE52_I146@PURE_QUANTA.Q_RES(CHIPS)':
 'A': CDS_PINID='A';
NET_NAME
'SW_P3V3_AUX_FLT'
 '@SCM_LIB.SCM(SCH_1):SW_P3V3_AUX_FLT':
 C_SIGNAL='@scm_lib.scm(sch_1):sw_p3v3_aux_flt';
NODE_NAME     PC223 1
 '@SCM_LIB.SCM(SCH_1):PAGE52_I11@PURE_QUANTA.Q_CAP(CHIPS)':
 'A': CDS_PINID='A';
NODE_NAME     PL19 2
 '@SCM_LIB.SCM(SCH_1):PAGE52_I32@PURE_QUANTA.Q_INDUCTOR(CHIPS)':
 '2': CDS_PINID='\2\';
NODE_NAME     PC219 1
 '@SCM_LIB.SCM(SCH_1):PAGE52_I80@PURE_QUANTA.Q_CAP(CHIPS)':
 'A': CDS_PINID='A';
NODE_NAME     PC218 1
 '@SCM_LIB.SCM(SCH_1):PAGE52_I81@PURE_QUANTA.Q_CAP(CHIPS)':
 'A': CDS_PINID='A';
NODE_NAME     PU1 3
 '@SCM_LIB.SCM(SCH_1):PAGE52_I82@PURE_QUANTA.MPQ8626GDZ(CHIPS)':
 'VIN': CDS_PINID='VIN';
NODE_NAME     C265 1
 '@SCM_LIB.SCM(SCH_1):PAGE52_I102@PURE_QUANTA.Q_CAP(CHIPS)':
 'A': CDS_PINID='A';
NET_NAME
'SW_P3V3_AUX_SW'
 '@SCM_LIB.SCM(SCH_1):SW_P3V3_AUX_SW':
 C_SIGNAL='@scm_lib.scm(sch_1):sw_p3v3_aux_sw';
NODE_NAME     PC224 2
 '@SCM_LIB.SCM(SCH_1):PAGE52_I15@PURE_QUANTA.Q_CAP(CHIPS)':
 'B': CDS_PINID='B';
NODE_NAME     PU1 2
 '@SCM_LIB.SCM(SCH_1):PAGE52_I82@PURE_QUANTA.MPQ8626GDZ(CHIPS)':
 'SW1': CDS_PINID='SW1';
NODE_NAME     PU1 11
 '@SCM_LIB.SCM(SCH_1):PAGE52_I82@PURE_QUANTA.MPQ8626GDZ(CHIPS)':
 'SW2': CDS_PINID='SW2';
NODE_NAME     PL35 1
 '@SCM_LIB.SCM(SCH_1):PAGE52_I92@PURE_QUANTA.Q_INDUCTOR(CHIPS)':
 '1': CDS_PINID='\1\';
NET_NAME
'SW_P5V_AUX_BST'
 '@SCM_LIB.SCM(SCH_1):SW_P5V_AUX_BST':
 C_SIGNAL='@scm_lib.scm(sch_1):sw_p5v_aux_bst';
NODE_NAME     PC216 1
 '@SCM_LIB.SCM(SCH_1):PAGE51_I23@PURE_QUANTA.Q_CAP(CHIPS)':
 'A': CDS_PINID='A';
NODE_NAME     PU38 1
 '@SCM_LIB.SCM(SCH_1):PAGE51_I42@PURE_QUANTA.MPQ8633AGLEC807Z(CHIPS)':
 'BST': CDS_PINID='BST';
NET_NAME
'SW_P5V_AUX_FLT'
 '@SCM_LIB.SCM(SCH_1):SW_P5V_AUX_FLT':
 C_SIGNAL='@scm_lib.scm(sch_1):sw_p5v_aux_flt';
NODE_NAME     PL4 2
 '@SCM_LIB.SCM(SCH_1):PAGE51_I39@PURE_QUANTA.Q_INDUCTOR(CHIPS)':
 '2': CDS_PINID='\2\';
NODE_NAME     PU38 10
 '@SCM_LIB.SCM(SCH_1):PAGE51_I42@PURE_QUANTA.MPQ8633AGLEC807Z(CHIPS)':
 'VIN1': CDS_PINID='VIN1';
NODE_NAME     PU38 21
 '@SCM_LIB.SCM(SCH_1):PAGE51_I42@PURE_QUANTA.MPQ8633AGLEC807Z(CHIPS)':
 'VIN2': CDS_PINID='VIN2';
NODE_NAME     PC210 1
 '@SCM_LIB.SCM(SCH_1):PAGE51_I45@PURE_QUANTA.Q_CAP(CHIPS)':
 'A': CDS_PINID='A';
NODE_NAME     PC206 1
 '@SCM_LIB.SCM(SCH_1):PAGE51_I47@PURE_QUANTA.Q_CAP(CHIPS)':
 'A': CDS_PINID='A';
NODE_NAME     PC207 1
 '@SCM_LIB.SCM(SCH_1):PAGE51_I48@PURE_QUANTA.Q_CAP(CHIPS)':
 'A': CDS_PINID='A';
NET_NAME
'SW_P5V_AUX_SW'
 '@SCM_LIB.SCM(SCH_1):SW_P5V_AUX_SW':
 C_SIGNAL='@scm_lib.scm(sch_1):sw_p5v_aux_sw';
NODE_NAME     PC216 2
 '@SCM_LIB.SCM(SCH_1):PAGE51_I23@PURE_QUANTA.Q_CAP(CHIPS)':
 'B': CDS_PINID='B';
NODE_NAME     PL34 1
 '@SCM_LIB.SCM(SCH_1):PAGE51_I28@PURE_QUANTA.Q_INDUCTOR(CHIPS)':
 '1': CDS_PINID='\1\';
NODE_NAME     PU38 20
 '@SCM_LIB.SCM(SCH_1):PAGE51_I42@PURE_QUANTA.MPQ8633AGLEC807Z(CHIPS)':
 'SW': CDS_PINID='SW';
NET_NAME
'SYS_BMC_PWRBTN_R1_N'
 '@SCM_LIB.SCM(SCH_1):SYS_BMC_PWRBTN_R1_N':
 C_SIGNAL='@scm_lib.scm(sch_1):sys_bmc_pwrbtn_r1_n';
NODE_NAME     U5 W24
 '@SCM_LIB.SCM(SCH_1):PAGE15_I350@PURE_QUANTA.AST2600A3GP(CHIPS)':
 'GPIOP1||PWM9||THRUOUT0': CDS_PINID='\gpiop1||pwm9||thruout0\';
NODE_NAME     R804 1
 '@SCM_LIB.SCM(SCH_1):PAGE15_I367@PURE_QUANTA.Q_RES(CHIPS)':
 'A': CDS_PINID='A';
NODE_NAME     R462 2
 '@SCM_LIB.SCM(SCH_1):PAGE15_I391@PURE_QUANTA.Q_RES(CHIPS)':
 'B': CDS_PINID='B';
NET_NAME
'SYS_BMC_PWRBTN_R_N'
 '@SCM_LIB.SCM(SCH_1):SYS_BMC_PWRBTN_R_N':
 C_SIGNAL='@scm_lib.scm(sch_1):sys_bmc_pwrbtn_r_n';
NODE_NAME     R804 2
 '@SCM_LIB.SCM(SCH_1):PAGE15_I367@PURE_QUANTA.Q_RES(CHIPS)':
 'B': CDS_PINID='B';
NODE_NAME     U15 1
 '@SCM_LIB.SCM(SCH_1):PAGE15_I393@PURE_QUANTA.74LVC1G08GW(CHIPS)':
 'B': CDS_PINID='B';
NET_NAME
'SYS_PWRBTN_N'
 '@SCM_LIB.SCM(SCH_1):SYS_PWRBTN_N':
 C_SIGNAL='@scm_lib.scm(sch_1):sys_pwrbtn_n';
NODE_NAME     GF1 A47
 '@SCM_LIB.SCM(SCH_1):PAGE10_I553@PURE_QUANTA.FCONN168_ME1016810202011_SCM(CHIPS)':
 'SYS_PWRBTN_N': CDS_PINID='SYS_PWRBTN_N';
NODE_NAME     R44 2
 '@SCM_LIB.SCM(SCH_1):PAGE11_I175@PURE_QUANTA.Q_RES(CHIPS)':
 'B': CDS_PINID='B';
NODE_NAME     U15 4
 '@SCM_LIB.SCM(SCH_1):PAGE15_I393@PURE_QUANTA.74LVC1G08GW(CHIPS)':
 'Y': CDS_PINID='Y';
NET_NAME
'TDR_DIFF_100_BOT_DN'
 '@SCM_LIB.SCM(SCH_1):TDR_DIFF_100_BOT_DN':
 C_SIGNAL='@scm_lib.scm(sch_1):tdr_diff_100_bot_dn';
NODE_NAME     X18 4
 '@SCM_LIB.SCM(SCH_1):PAGE60_I42@PURE_QUANTA.TP_TDR_4P_FTS(CHIPS)':
 'S2': CDS_PINID='S2';
NODE_NAME     X24 1
 '@SCM_LIB.SCM(SCH_1):PAGE60_I43@PURE_QUANTA.TP_TDR_4P_FTS(CHIPS)':
 'S1': CDS_PINID='S1';
NET_NAME
'TDR_DIFF_100_BOT_DP'
 '@SCM_LIB.SCM(SCH_1):TDR_DIFF_100_BOT_DP':
 C_SIGNAL='@scm_lib.scm(sch_1):tdr_diff_100_bot_dp';
NODE_NAME     X18 1
 '@SCM_LIB.SCM(SCH_1):PAGE60_I42@PURE_QUANTA.TP_TDR_4P_FTS(CHIPS)':
 'S1': CDS_PINID='S1';
NODE_NAME     X24 4
 '@SCM_LIB.SCM(SCH_1):PAGE60_I43@PURE_QUANTA.TP_TDR_4P_FTS(CHIPS)':
 'S2': CDS_PINID='S2';
NET_NAME
'TDR_DIFF_100_IN1_DN'
 '@SCM_LIB.SCM(SCH_1):TDR_DIFF_100_IN1_DN':
 C_SIGNAL='@scm_lib.scm(sch_1):tdr_diff_100_in1_dn';
NODE_NAME     X14 4
 '@SCM_LIB.SCM(SCH_1):PAGE60_I58@PURE_QUANTA.TP_TDR_4P_FTS(CHIPS)':
 'S2': CDS_PINID='S2';
NODE_NAME     X20 1
 '@SCM_LIB.SCM(SCH_1):PAGE60_I59@PURE_QUANTA.TP_TDR_4P_FTS(CHIPS)':
 'S1': CDS_PINID='S1';
NET_NAME
'TDR_DIFF_100_IN1_DP'
 '@SCM_LIB.SCM(SCH_1):TDR_DIFF_100_IN1_DP':
 C_SIGNAL='@scm_lib.scm(sch_1):tdr_diff_100_in1_dp';
NODE_NAME     X14 1
 '@SCM_LIB.SCM(SCH_1):PAGE60_I58@PURE_QUANTA.TP_TDR_4P_FTS(CHIPS)':
 'S1': CDS_PINID='S1';
NODE_NAME     X20 4
 '@SCM_LIB.SCM(SCH_1):PAGE60_I59@PURE_QUANTA.TP_TDR_4P_FTS(CHIPS)':
 'S2': CDS_PINID='S2';
NET_NAME
'TDR_DIFF_100_IN4_DN'
 '@SCM_LIB.SCM(SCH_1):TDR_DIFF_100_IN4_DN':
 C_SIGNAL='@scm_lib.scm(sch_1):tdr_diff_100_in4_dn';
NODE_NAME     X17 4
 '@SCM_LIB.SCM(SCH_1):PAGE60_I46@PURE_QUANTA.TP_TDR_4P_FTS(CHIPS)':
 'S2': CDS_PINID='S2';
NODE_NAME     X23 1
 '@SCM_LIB.SCM(SCH_1):PAGE60_I47@PURE_QUANTA.TP_TDR_4P_FTS(CHIPS)':
 'S1': CDS_PINID='S1';
NET_NAME
'TDR_DIFF_100_IN4_DP'
 '@SCM_LIB.SCM(SCH_1):TDR_DIFF_100_IN4_DP':
 C_SIGNAL='@scm_lib.scm(sch_1):tdr_diff_100_in4_dp';
NODE_NAME     X17 1
 '@SCM_LIB.SCM(SCH_1):PAGE60_I46@PURE_QUANTA.TP_TDR_4P_FTS(CHIPS)':
 'S1': CDS_PINID='S1';
NODE_NAME     X23 4
 '@SCM_LIB.SCM(SCH_1):PAGE60_I47@PURE_QUANTA.TP_TDR_4P_FTS(CHIPS)':
 'S2': CDS_PINID='S2';
NET_NAME
'TDR_DIFF_100_TOP_DN'
 '@SCM_LIB.SCM(SCH_1):TDR_DIFF_100_TOP_DN':
 C_SIGNAL='@scm_lib.scm(sch_1):tdr_diff_100_top_dn';
NODE_NAME     X19 1
 '@SCM_LIB.SCM(SCH_1):PAGE60_I38@PURE_QUANTA.TP_TDR_4P_FTS(CHIPS)':
 'S1': CDS_PINID='S1';
NODE_NAME     X13 4
 '@SCM_LIB.SCM(SCH_1):PAGE60_I39@PURE_QUANTA.TP_TDR_4P_FTS(CHIPS)':
 'S2': CDS_PINID='S2';
NET_NAME
'TDR_DIFF_100_TOP_DP'
 '@SCM_LIB.SCM(SCH_1):TDR_DIFF_100_TOP_DP':
 C_SIGNAL='@scm_lib.scm(sch_1):tdr_diff_100_top_dp';
NODE_NAME     X19 4
 '@SCM_LIB.SCM(SCH_1):PAGE60_I38@PURE_QUANTA.TP_TDR_4P_FTS(CHIPS)':
 'S2': CDS_PINID='S2';
NODE_NAME     X13 1
 '@SCM_LIB.SCM(SCH_1):PAGE60_I39@PURE_QUANTA.TP_TDR_4P_FTS(CHIPS)':
 'S1': CDS_PINID='S1';
NET_NAME
'TDR_DIFF_85_BOT_DN'
 '@SCM_LIB.SCM(SCH_1):TDR_DIFF_85_BOT_DN':
 C_SIGNAL='@scm_lib.scm(sch_1):tdr_diff_85_bot_dn';
NODE_NAME     X12 1
 '@SCM_LIB.SCM(SCH_1):PAGE60_I18@PURE_QUANTA.TP_TDR_4P_FTS(CHIPS)':
 'S1': CDS_PINID='S1';
NODE_NAME     X6 4
 '@SCM_LIB.SCM(SCH_1):PAGE60_I19@PURE_QUANTA.TP_TDR_4P_FTS(CHIPS)':
 'S2': CDS_PINID='S2';
NET_NAME
'TDR_DIFF_85_BOT_DP'
 '@SCM_LIB.SCM(SCH_1):TDR_DIFF_85_BOT_DP':
 C_SIGNAL='@scm_lib.scm(sch_1):tdr_diff_85_bot_dp';
NODE_NAME     X12 4
 '@SCM_LIB.SCM(SCH_1):PAGE60_I18@PURE_QUANTA.TP_TDR_4P_FTS(CHIPS)':
 'S2': CDS_PINID='S2';
NODE_NAME     X6 1
 '@SCM_LIB.SCM(SCH_1):PAGE60_I19@PURE_QUANTA.TP_TDR_4P_FTS(CHIPS)':
 'S1': CDS_PINID='S1';
NET_NAME
'TDR_DIFF_85_IN1_DN'
 '@SCM_LIB.SCM(SCH_1):TDR_DIFF_85_IN1_DN':
 C_SIGNAL='@scm_lib.scm(sch_1):tdr_diff_85_in1_dn';
NODE_NAME     X8 1
 '@SCM_LIB.SCM(SCH_1):PAGE60_I34@PURE_QUANTA.TP_TDR_4P_FTS(CHIPS)':
 'S1': CDS_PINID='S1';
NODE_NAME     X2 4
 '@SCM_LIB.SCM(SCH_1):PAGE60_I35@PURE_QUANTA.TP_TDR_4P_FTS(CHIPS)':
 'S2': CDS_PINID='S2';
NET_NAME
'TDR_DIFF_85_IN1_DP'
 '@SCM_LIB.SCM(SCH_1):TDR_DIFF_85_IN1_DP':
 C_SIGNAL='@scm_lib.scm(sch_1):tdr_diff_85_in1_dp';
NODE_NAME     X8 4
 '@SCM_LIB.SCM(SCH_1):PAGE60_I34@PURE_QUANTA.TP_TDR_4P_FTS(CHIPS)':
 'S2': CDS_PINID='S2';
NODE_NAME     X2 1
 '@SCM_LIB.SCM(SCH_1):PAGE60_I35@PURE_QUANTA.TP_TDR_4P_FTS(CHIPS)':
 'S1': CDS_PINID='S1';
NET_NAME
'TDR_DIFF_85_IN4_DN'
 '@SCM_LIB.SCM(SCH_1):TDR_DIFF_85_IN4_DN':
 C_SIGNAL='@scm_lib.scm(sch_1):tdr_diff_85_in4_dn';
NODE_NAME     X11 1
 '@SCM_LIB.SCM(SCH_1):PAGE60_I22@PURE_QUANTA.TP_TDR_4P_FTS(CHIPS)':
 'S1': CDS_PINID='S1';
NODE_NAME     X5 4
 '@SCM_LIB.SCM(SCH_1):PAGE60_I23@PURE_QUANTA.TP_TDR_4P_FTS(CHIPS)':
 'S2': CDS_PINID='S2';
NET_NAME
'TDR_DIFF_85_IN4_DP'
 '@SCM_LIB.SCM(SCH_1):TDR_DIFF_85_IN4_DP':
 C_SIGNAL='@scm_lib.scm(sch_1):tdr_diff_85_in4_dp';
NODE_NAME     X11 4
 '@SCM_LIB.SCM(SCH_1):PAGE60_I22@PURE_QUANTA.TP_TDR_4P_FTS(CHIPS)':
 'S2': CDS_PINID='S2';
NODE_NAME     X5 1
 '@SCM_LIB.SCM(SCH_1):PAGE60_I23@PURE_QUANTA.TP_TDR_4P_FTS(CHIPS)':
 'S1': CDS_PINID='S1';
NET_NAME
'TDR_DIFF_85_TOP_DN'
 '@SCM_LIB.SCM(SCH_1):TDR_DIFF_85_TOP_DN':
 C_SIGNAL='@scm_lib.scm(sch_1):tdr_diff_85_top_dn';
NODE_NAME     X1 4
 '@SCM_LIB.SCM(SCH_1):PAGE60_I13@PURE_QUANTA.TP_TDR_4P_FTS(CHIPS)':
 'S2': CDS_PINID='S2';
NODE_NAME     X7 1
 '@SCM_LIB.SCM(SCH_1):PAGE60_I14@PURE_QUANTA.TP_TDR_4P_FTS(CHIPS)':
 'S1': CDS_PINID='S1';
NET_NAME
'TDR_DIFF_85_TOP_DP'
 '@SCM_LIB.SCM(SCH_1):TDR_DIFF_85_TOP_DP':
 C_SIGNAL='@scm_lib.scm(sch_1):tdr_diff_85_top_dp';
NODE_NAME     X1 1
 '@SCM_LIB.SCM(SCH_1):PAGE60_I13@PURE_QUANTA.TP_TDR_4P_FTS(CHIPS)':
 'S1': CDS_PINID='S1';
NODE_NAME     X7 4
 '@SCM_LIB.SCM(SCH_1):PAGE60_I14@PURE_QUANTA.TP_TDR_4P_FTS(CHIPS)':
 'S2': CDS_PINID='S2';
NET_NAME
'TDR_SE_50_OHM_BOT'
 '@SCM_LIB.SCM(SCH_1):TDR_SE_50_OHM_BOT':
 C_SIGNAL='@scm_lib.scm(sch_1):tdr_se_50_ohm_bot';
NODE_NAME     DB6 2
 '@SCM_LIB.SCM(SCH_1):PAGE60_I3@PURE_QUANTA.TDR_3P(CHIPS)':
 'IO1': CDS_PINID='IO1';
NODE_NAME     DB6 3
 '@SCM_LIB.SCM(SCH_1):PAGE60_I3@PURE_QUANTA.TDR_3P(CHIPS)':
 'IO2': CDS_PINID='IO2';
NET_NAME
'TDR_SE_50_OHM_IN1'
 '@SCM_LIB.SCM(SCH_1):TDR_SE_50_OHM_IN1':
 C_SIGNAL='@scm_lib.scm(sch_1):tdr_se_50_ohm_in1';
NODE_NAME     DB2 2
 '@SCM_LIB.SCM(SCH_1):PAGE60_I11@PURE_QUANTA.TDR_3P(CHIPS)':
 'IO1': CDS_PINID='IO1';
NODE_NAME     DB2 3
 '@SCM_LIB.SCM(SCH_1):PAGE60_I11@PURE_QUANTA.TDR_3P(CHIPS)':
 'IO2': CDS_PINID='IO2';
NET_NAME
'TDR_SE_50_OHM_IN2'
 '@SCM_LIB.SCM(SCH_1):TDR_SE_50_OHM_IN2':
 C_SIGNAL='@scm_lib.scm(sch_1):tdr_se_50_ohm_in2';
NODE_NAME     DB3 2
 '@SCM_LIB.SCM(SCH_1):PAGE60_I9@PURE_QUANTA.TDR_3P(CHIPS)':
 'IO1': CDS_PINID='IO1';
NODE_NAME     DB3 3
 '@SCM_LIB.SCM(SCH_1):PAGE60_I9@PURE_QUANTA.TDR_3P(CHIPS)':
 'IO2': CDS_PINID='IO2';
NET_NAME
'TDR_SE_50_OHM_IN3'
 '@SCM_LIB.SCM(SCH_1):TDR_SE_50_OHM_IN3':
 C_SIGNAL='@scm_lib.scm(sch_1):tdr_se_50_ohm_in3';
NODE_NAME     DB4 2
 '@SCM_LIB.SCM(SCH_1):PAGE60_I7@PURE_QUANTA.TDR_3P(CHIPS)':
 'IO1': CDS_PINID='IO1';
NODE_NAME     DB4 3
 '@SCM_LIB.SCM(SCH_1):PAGE60_I7@PURE_QUANTA.TDR_3P(CHIPS)':
 'IO2': CDS_PINID='IO2';
NET_NAME
'TDR_SE_50_OHM_IN4'
 '@SCM_LIB.SCM(SCH_1):TDR_SE_50_OHM_IN4':
 C_SIGNAL='@scm_lib.scm(sch_1):tdr_se_50_ohm_in4';
NODE_NAME     DB5 2
 '@SCM_LIB.SCM(SCH_1):PAGE60_I5@PURE_QUANTA.TDR_3P(CHIPS)':
 'IO1': CDS_PINID='IO1';
NODE_NAME     DB5 3
 '@SCM_LIB.SCM(SCH_1):PAGE60_I5@PURE_QUANTA.TDR_3P(CHIPS)':
 'IO2': CDS_PINID='IO2';
NET_NAME
'TDR_SE_50_OHM_TOP'
 '@SCM_LIB.SCM(SCH_1):TDR_SE_50_OHM_TOP':
 C_SIGNAL='@scm_lib.scm(sch_1):tdr_se_50_ohm_top';
NODE_NAME     DB1 2
 '@SCM_LIB.SCM(SCH_1):PAGE60_I1@PURE_QUANTA.TDR_3P(CHIPS)':
 'IO1': CDS_PINID='IO1';
NODE_NAME     DB1 3
 '@SCM_LIB.SCM(SCH_1):PAGE60_I1@PURE_QUANTA.TDR_3P(CHIPS)':
 'IO2': CDS_PINID='IO2';
NET_NAME
'TMC75_A0'
 '@SCM_LIB.SCM(SCH_1):TMC75_A0':
 C_SIGNAL='@scm_lib.scm(sch_1):tmc75_a0';
NODE_NAME     R417 1
 '@SCM_LIB.SCM(SCH_1):PAGE26_I39@PURE_QUANTA.Q_RES(CHIPS)':
 'A': CDS_PINID='A';
NODE_NAME     R416 2
 '@SCM_LIB.SCM(SCH_1):PAGE26_I41@PURE_QUANTA.Q_RES(CHIPS)':
 'B': CDS_PINID='B';
NODE_NAME     J14 3
 '@SCM_LIB.SCM(SCH_1):PAGE26_I71@PURE_QUANTA.CONN8_TSW10407FD(CHIPS)':
 '3': CDS_PINID='\3\';
NET_NAME
'TMC75_A1'
 '@SCM_LIB.SCM(SCH_1):TMC75_A1':
 C_SIGNAL='@scm_lib.scm(sch_1):tmc75_a1';
NODE_NAME     R53 1
 '@SCM_LIB.SCM(SCH_1):PAGE26_I66@PURE_QUANTA.Q_RES(CHIPS)':
 'A': CDS_PINID='A';
NODE_NAME     R52 2
 '@SCM_LIB.SCM(SCH_1):PAGE26_I67@PURE_QUANTA.Q_RES(CHIPS)':
 'B': CDS_PINID='B';
NODE_NAME     J14 5
 '@SCM_LIB.SCM(SCH_1):PAGE26_I71@PURE_QUANTA.CONN8_TSW10407FD(CHIPS)':
 '5': CDS_PINID='\5\';
NET_NAME
'TMC75_A2'
 '@SCM_LIB.SCM(SCH_1):TMC75_A2':
 C_SIGNAL='@scm_lib.scm(sch_1):tmc75_a2';
NODE_NAME     R419 1
 '@SCM_LIB.SCM(SCH_1):PAGE26_I37@PURE_QUANTA.Q_RES(CHIPS)':
 'A': CDS_PINID='A';
NODE_NAME     R418 2
 '@SCM_LIB.SCM(SCH_1):PAGE26_I40@PURE_QUANTA.Q_RES(CHIPS)':
 'B': CDS_PINID='B';
NODE_NAME     J14 7
 '@SCM_LIB.SCM(SCH_1):PAGE26_I71@PURE_QUANTA.CONN8_TSW10407FD(CHIPS)':
 '7': CDS_PINID='\7\';
NET_NAME
'TP4'
 '@SCM_LIB.SCM(SCH_1):TP4':
 C_SIGNAL='@scm_lib.scm(sch_1):tp4';
NODE_NAME     U35 5
 '@SCM_LIB.SCM(SCH_1):PAGE23_I155@PURE_QUANTA.DT1240E04LP7(CHIPS)':
 'IO4': CDS_PINID='IO4';
NET_NAME
'TP_BIOS_MUX0_PIN12'
 '@SCM_LIB.SCM(SCH_1):TP_BIOS_MUX0_PIN12':
 C_SIGNAL='@scm_lib.scm(sch_1):tp_bios_mux0_pin12';
NODE_NAME     U30 12
 '@SCM_LIB.SCM(SCH_1):PAGE44_I271@PURE_QUANTA.IDTQS3VH257PAG(CHIPS)':
 'YD': CDS_PINID='YD';
NET_NAME
'TP_BIOS_MUX0_PIN13'
 '@SCM_LIB.SCM(SCH_1):TP_BIOS_MUX0_PIN13':
 C_SIGNAL='@scm_lib.scm(sch_1):tp_bios_mux0_pin13';
NODE_NAME     U30 13
 '@SCM_LIB.SCM(SCH_1):PAGE44_I271@PURE_QUANTA.IDTQS3VH257PAG(CHIPS)':
 'I_1D': CDS_PINID='I_1D';
NET_NAME
'TP_BIOS_MUX0_PIN14'
 '@SCM_LIB.SCM(SCH_1):TP_BIOS_MUX0_PIN14':
 C_SIGNAL='@scm_lib.scm(sch_1):tp_bios_mux0_pin14';
NODE_NAME     U30 14
 '@SCM_LIB.SCM(SCH_1):PAGE44_I271@PURE_QUANTA.IDTQS3VH257PAG(CHIPS)':
 'I_0D': CDS_PINID='I_0D';
NET_NAME
'TP_BIOS_MUX1_PIN12'
 '@SCM_LIB.SCM(SCH_1):TP_BIOS_MUX1_PIN12':
 C_SIGNAL='@scm_lib.scm(sch_1):tp_bios_mux1_pin12';
NODE_NAME     U21 12
 '@SCM_LIB.SCM(SCH_1):PAGE44_I296@PURE_QUANTA.IDTQS3VH257PAG(CHIPS)':
 'YD': CDS_PINID='YD';
NET_NAME
'TP_BIOS_MUX1_PIN13'
 '@SCM_LIB.SCM(SCH_1):TP_BIOS_MUX1_PIN13':
 C_SIGNAL='@scm_lib.scm(sch_1):tp_bios_mux1_pin13';
NODE_NAME     U21 13
 '@SCM_LIB.SCM(SCH_1):PAGE44_I296@PURE_QUANTA.IDTQS3VH257PAG(CHIPS)':
 'I_1D': CDS_PINID='I_1D';
NET_NAME
'TP_BIOS_MUX1_PIN14'
 '@SCM_LIB.SCM(SCH_1):TP_BIOS_MUX1_PIN14':
 C_SIGNAL='@scm_lib.scm(sch_1):tp_bios_mux1_pin14';
NODE_NAME     U21 14
 '@SCM_LIB.SCM(SCH_1):PAGE44_I296@PURE_QUANTA.IDTQS3VH257PAG(CHIPS)':
 'I_0D': CDS_PINID='I_0D';
NET_NAME
'TP_BMC_SPICS0_N'
 '@SCM_LIB.SCM(SCH_1):TP_BMC_SPICS0_N':
 C_SIGNAL='@scm_lib.scm(sch_1):tp_bmc_spics0_n';
NODE_NAME     U5 AD13
 '@SCM_LIB.SCM(SCH_1):PAGE13_I363@PURE_QUANTA.AST2600A3GP(CHIPS)':
 'SPI1CS0#': CDS_PINID='\spi1cs0#\';
NET_NAME
'TP_BMC_SPICS2_N'
 '@SCM_LIB.SCM(SCH_1):TP_BMC_SPICS2_N':
 C_SIGNAL='@scm_lib.scm(sch_1):tp_bmc_spics2_n';
NODE_NAME     U5 AC13
 '@SCM_LIB.SCM(SCH_1):PAGE13_I363@PURE_QUANTA.AST2600A3GP(CHIPS)':
 'FWSPICS2#': CDS_PINID='\fwspics2#\';
NET_NAME
'TP_ESD_VGA_P4'
 '@SCM_LIB.SCM(SCH_1):TP_ESD_VGA_P4':
 C_SIGNAL='@scm_lib.scm(sch_1):tp_esd_vga_p4';
NODE_NAME     U35 6
 '@SCM_LIB.SCM(SCH_1):PAGE23_I155@PURE_QUANTA.DT1240E04LP7(CHIPS)':
 'NC1': CDS_PINID='NC1';
NET_NAME
'TP_GF1_B44'
 '@SCM_LIB.SCM(SCH_1):TP_GF1_B44':
 C_SIGNAL='@scm_lib.scm(sch_1):tp_gf1_b44';
NODE_NAME     GF1 B44
 '@SCM_LIB.SCM(SCH_1):PAGE10_I553@PURE_QUANTA.FCONN168_ME1016810202011_SCM(CHIPS)':
 'QSPI1_CS0_N': CDS_PINID='QSPI1_CS0_N';
NET_NAME
'TP_GF_A45'
 '@SCM_LIB.SCM(SCH_1):TP_GF_A45':
 C_SIGNAL='@scm_lib.scm(sch_1):tp_gf_a45';
NODE_NAME     GF1 A45
 '@SCM_LIB.SCM(SCH_1):PAGE10_I553@PURE_QUANTA.FCONN168_ME1016810202011_SCM(CHIPS)':
 'HPM_STBY_EN': CDS_PINID='HPM_STBY_EN';
NET_NAME
'TP_GF_A62'
 '@SCM_LIB.SCM(SCH_1):TP_GF_A62':
 C_SIGNAL='@scm_lib.scm(sch_1):tp_gf_a62';
NODE_NAME     GF1 A62
 '@SCM_LIB.SCM(SCH_1):PAGE10_I553@PURE_QUANTA.FCONN168_ME1016810202011_SCM(CHIPS)':
 'PCIE_HPM_RXP_1': CDS_PINID='PCIE_HPM_RXP_1';
NET_NAME
'TP_GF_A63'
 '@SCM_LIB.SCM(SCH_1):TP_GF_A63':
 C_SIGNAL='@scm_lib.scm(sch_1):tp_gf_a63';
NODE_NAME     GF1 A63
 '@SCM_LIB.SCM(SCH_1):PAGE10_I553@PURE_QUANTA.FCONN168_ME1016810202011_SCM(CHIPS)':
 'PCIE_HPM_RXN_1': CDS_PINID='PCIE_HPM_RXN_1';
NET_NAME
'TP_GF_B62'
 '@SCM_LIB.SCM(SCH_1):TP_GF_B62':
 C_SIGNAL='@scm_lib.scm(sch_1):tp_gf_b62';
NODE_NAME     GF1 B62
 '@SCM_LIB.SCM(SCH_1):PAGE10_I553@PURE_QUANTA.FCONN168_ME1016810202011_SCM(CHIPS)':
 'PCIE_HPM_TXP_1': CDS_PINID='PCIE_HPM_TXP_1';
NET_NAME
'TP_GF_B63'
 '@SCM_LIB.SCM(SCH_1):TP_GF_B63':
 C_SIGNAL='@scm_lib.scm(sch_1):tp_gf_b63';
NODE_NAME     GF1 B63
 '@SCM_LIB.SCM(SCH_1):PAGE10_I553@PURE_QUANTA.FCONN168_ME1016810202011_SCM(CHIPS)':
 'PCIE_HPM_TXN_1': CDS_PINID='PCIE_HPM_TXN_1';
NET_NAME
'TP_ID_BUF'
 '@SCM_LIB.SCM(SCH_1):TP_ID_BUF':
 C_SIGNAL='@scm_lib.scm(sch_1):tp_id_buf';
NODE_NAME     U32 1
 '@SCM_LIB.SCM(SCH_1):PAGE50_I49@PURE_QUANTA.74LVC1G17GW(CHIPS)':
 'NC': CDS_PINID='NC';
NET_NAME
'TP_J40_11'
 '@SCM_LIB.SCM(SCH_1):TP_J40_11':
 C_SIGNAL='@scm_lib.scm(sch_1):tp_j40_11';
NODE_NAME     J40 11
 '@SCM_LIB.SCM(SCH_1):PAGE45_I53@PURE_QUANTA.SCONN16_ACASPI006P06(CHIPS)':
 'NC4': CDS_PINID='NC4';
NODE_NAME     U17 11
 '@SCM_LIB.SCM(SCH_1):PAGE45_I54@PURE_QUANTA.MX25L51245GMI10G(CHIPS)':
 'DNU3': CDS_PINID='DNU3';
NET_NAME
'TP_J40_12'
 '@SCM_LIB.SCM(SCH_1):TP_J40_12':
 C_SIGNAL='@scm_lib.scm(sch_1):tp_j40_12';
NODE_NAME     J40 12
 '@SCM_LIB.SCM(SCH_1):PAGE45_I53@PURE_QUANTA.SCONN16_ACASPI006P06(CHIPS)':
 'NC6': CDS_PINID='NC6';
NODE_NAME     U17 12
 '@SCM_LIB.SCM(SCH_1):PAGE45_I54@PURE_QUANTA.MX25L51245GMI10G(CHIPS)':
 'DNU4': CDS_PINID='DNU4';
NET_NAME
'TP_J40_13'
 '@SCM_LIB.SCM(SCH_1):TP_J40_13':
 C_SIGNAL='@scm_lib.scm(sch_1):tp_j40_13';
NODE_NAME     J40 13
 '@SCM_LIB.SCM(SCH_1):PAGE45_I53@PURE_QUANTA.SCONN16_ACASPI006P06(CHIPS)':
 'NC7': CDS_PINID='NC7';
NODE_NAME     U17 13
 '@SCM_LIB.SCM(SCH_1):PAGE45_I54@PURE_QUANTA.MX25L51245GMI10G(CHIPS)':
 'NC2': CDS_PINID='NC2';
NET_NAME
'TP_J40_14'
 '@SCM_LIB.SCM(SCH_1):TP_J40_14':
 C_SIGNAL='@scm_lib.scm(sch_1):tp_j40_14';
NODE_NAME     J40 14
 '@SCM_LIB.SCM(SCH_1):PAGE45_I53@PURE_QUANTA.SCONN16_ACASPI006P06(CHIPS)':
 'NC8': CDS_PINID='NC8';
NODE_NAME     U17 14
 '@SCM_LIB.SCM(SCH_1):PAGE45_I54@PURE_QUANTA.MX25L51245GMI10G(CHIPS)':
 'NC3': CDS_PINID='NC3';
NET_NAME
'TP_J40_4'
 '@SCM_LIB.SCM(SCH_1):TP_J40_4':
 C_SIGNAL='@scm_lib.scm(sch_1):tp_j40_4';
NODE_NAME     J40 4
 '@SCM_LIB.SCM(SCH_1):PAGE45_I53@PURE_QUANTA.SCONN16_ACASPI006P06(CHIPS)':
 'NC1': CDS_PINID='NC1';
NODE_NAME     U17 4
 '@SCM_LIB.SCM(SCH_1):PAGE45_I54@PURE_QUANTA.MX25L51245GMI10G(CHIPS)':
 'NC1': CDS_PINID='NC1';
NET_NAME
'TP_J40_5'
 '@SCM_LIB.SCM(SCH_1):TP_J40_5':
 C_SIGNAL='@scm_lib.scm(sch_1):tp_j40_5';
NODE_NAME     J40 5
 '@SCM_LIB.SCM(SCH_1):PAGE45_I53@PURE_QUANTA.SCONN16_ACASPI006P06(CHIPS)':
 'NC2': CDS_PINID='NC2';
NODE_NAME     U17 5
 '@SCM_LIB.SCM(SCH_1):PAGE45_I54@PURE_QUANTA.MX25L51245GMI10G(CHIPS)':
 'DNU1': CDS_PINID='DNU1';
NET_NAME
'TP_J40_6'
 '@SCM_LIB.SCM(SCH_1):TP_J40_6':
 C_SIGNAL='@scm_lib.scm(sch_1):tp_j40_6';
NODE_NAME     J40 6
 '@SCM_LIB.SCM(SCH_1):PAGE45_I53@PURE_QUANTA.SCONN16_ACASPI006P06(CHIPS)':
 'NC3': CDS_PINID='NC3';
NODE_NAME     U17 6
 '@SCM_LIB.SCM(SCH_1):PAGE45_I54@PURE_QUANTA.MX25L51245GMI10G(CHIPS)':
 'DNU2': CDS_PINID='DNU2';
NET_NAME
'TP_PLD_19D'
 '@SCM_LIB.SCM(SCH_1):TP_PLD_19D':
 C_SIGNAL='@scm_lib.scm(sch_1):tp_pld_19d';
NODE_NAME     U25 E11
 '@SCM_LIB.SCM(SCH_1):PAGE34_I1@PURE_QUANTA.LCMXO3LF2100C5BG256C(CHIPS)':
 'PT19D': CDS_PINID='PT19D';
NET_NAME
'TP_PLD_C13'
 '@SCM_LIB.SCM(SCH_1):TP_PLD_C13':
 C_SIGNAL='@scm_lib.scm(sch_1):tp_pld_c13';
NODE_NAME     U25 P5
 '@SCM_LIB.SCM(SCH_1):PAGE36_I1@PURE_QUANTA.LCMXO3LF2100C5BG256C(CHIPS)':
 'PB5B': CDS_PINID='PB5B';
NET_NAME
'TP_PLD_CONN_P5'
 '@SCM_LIB.SCM(SCH_1):TP_PLD_CONN_P5':
 C_SIGNAL='@scm_lib.scm(sch_1):tp_pld_conn_p5';
NODE_NAME     J7 5
 '@SCM_LIB.SCM(SCH_1):PAGE32_I132@PURE_QUANTA.CONN8_210HP1080BR1(CHIPS)':
 '5': CDS_PINID='\5\';
NET_NAME
'TP_PLD_L3'
 '@SCM_LIB.SCM(SCH_1):TP_PLD_L3':
 C_SIGNAL='@scm_lib.scm(sch_1):tp_pld_l3';
NODE_NAME     U25 F12
 '@SCM_LIB.SCM(SCH_1):PAGE35_I1@PURE_QUANTA.LCMXO3LF2100C5BG256C(CHIPS)':
 'PR4C': CDS_PINID='PR4C';
NET_NAME
'TP_PWR_BUF'
 '@SCM_LIB.SCM(SCH_1):TP_PWR_BUF':
 C_SIGNAL='@scm_lib.scm(sch_1):tp_pwr_buf';
NODE_NAME     U31 1
 '@SCM_LIB.SCM(SCH_1):PAGE50_I151@PURE_QUANTA.74LVC1G07GW(CHIPS)':
 'NC': CDS_PINID='NC';
NET_NAME
'TP_U14_FLAG_N'
 '@SCM_LIB.SCM(SCH_1):TP_U14_FLAG_N':
 C_SIGNAL='@scm_lib.scm(sch_1):tp_u14_flag_n';
NODE_NAME     U14 3
 '@SCM_LIB.SCM(SCH_1):PAGE52_I79@PURE_QUANTA.AP22811AW57(CHIPS)':
 'FLG#': CDS_PINID='\flg#\';
NET_NAME
'T_GND'
 '@SCM_LIB.SCM(SCH_1):T_GND':
 C_SIGNAL='@scm_lib.scm(sch_1):t_gnd',
 CDS_GLOBAL_NET='TRUE';
NODE_NAME     DB1 1
 '@SCM_LIB.SCM(SCH_1):PAGE60_I1@PURE_QUANTA.TDR_3P(CHIPS)':
 'GND': CDS_PINID='GND';
NODE_NAME     DB6 1
 '@SCM_LIB.SCM(SCH_1):PAGE60_I3@PURE_QUANTA.TDR_3P(CHIPS)':
 'GND': CDS_PINID='GND';
NODE_NAME     DB5 1
 '@SCM_LIB.SCM(SCH_1):PAGE60_I5@PURE_QUANTA.TDR_3P(CHIPS)':
 'GND': CDS_PINID='GND';
NODE_NAME     DB4 1
 '@SCM_LIB.SCM(SCH_1):PAGE60_I7@PURE_QUANTA.TDR_3P(CHIPS)':
 'GND': CDS_PINID='GND';
NODE_NAME     DB3 1
 '@SCM_LIB.SCM(SCH_1):PAGE60_I9@PURE_QUANTA.TDR_3P(CHIPS)':
 'GND': CDS_PINID='GND';
NODE_NAME     DB2 1
 '@SCM_LIB.SCM(SCH_1):PAGE60_I11@PURE_QUANTA.TDR_3P(CHIPS)':
 'GND': CDS_PINID='GND';
NET_NAME
'U39_ADJ'
 '@SCM_LIB.SCM(SCH_1):U39_ADJ':
 C_SIGNAL='@scm_lib.scm(sch_1):u39_adj';
NODE_NAME     U39 4
 '@SCM_LIB.SCM(SCH_1):PAGE53_I60@PURE_QUANTA.RT9059GQW(CHIPS)':
 'ADJ': CDS_PINID='ADJ';
NODE_NAME     R830 1
 '@SCM_LIB.SCM(SCH_1):PAGE53_I61@PURE_QUANTA.Q_RES(CHIPS)':
 'A': CDS_PINID='A';
NODE_NAME     R829 2
 '@SCM_LIB.SCM(SCH_1):PAGE53_I62@PURE_QUANTA.Q_RES(CHIPS)':
 'B': CDS_PINID='B';
NET_NAME
'U41_ADJ'
 '@SCM_LIB.SCM(SCH_1):U41_ADJ':
 C_SIGNAL='@scm_lib.scm(sch_1):u41_adj';
NODE_NAME     U41 4
 '@SCM_LIB.SCM(SCH_1):PAGE54_I96@PURE_QUANTA.RT9059GQW(CHIPS)':
 'ADJ': CDS_PINID='ADJ';
NODE_NAME     R832 1
 '@SCM_LIB.SCM(SCH_1):PAGE54_I97@PURE_QUANTA.Q_RES(CHIPS)':
 'A': CDS_PINID='A';
NODE_NAME     R831 2
 '@SCM_LIB.SCM(SCH_1):PAGE54_I98@PURE_QUANTA.Q_RES(CHIPS)':
 'B': CDS_PINID='B';
NET_NAME
'U43_CT'
 '@SCM_LIB.SCM(SCH_1):U43_CT':
 C_SIGNAL='@scm_lib.scm(sch_1):u43_ct';
NODE_NAME     R710 2
 '@SCM_LIB.SCM(SCH_1):PAGE22_I55@PURE_QUANTA.Q_RES(CHIPS)':
 'B': CDS_PINID='B';
NODE_NAME     C264 1
 '@SCM_LIB.SCM(SCH_1):PAGE22_I59@PURE_QUANTA.Q_CAP(CHIPS)':
 'A': CDS_PINID='A';
NODE_NAME     U43 4
 '@SCM_LIB.SCM(SCH_1):PAGE22_I90@PURE_QUANTA.TPS3808G18DBVR(CHIPS)':
 'CT': CDS_PINID='CT';
NET_NAME
'U56_ADJ_1'
 '@SCM_LIB.SCM(SCH_1):U56_ADJ_1':
 C_SIGNAL='@scm_lib.scm(sch_1):u56_adj_1';
NODE_NAME     U56 4
 '@SCM_LIB.SCM(SCH_1):PAGE51_I56@PURE_QUANTA.AP2205W57(CHIPS)':
 'ADJ||NC': CDS_PINID='\adj||nc\';
NODE_NAME     R677 1
 '@SCM_LIB.SCM(SCH_1):PAGE51_I57@PURE_QUANTA.Q_RES(CHIPS)':
 'A': CDS_PINID='A';
NODE_NAME     R631 2
 '@SCM_LIB.SCM(SCH_1):PAGE51_I62@PURE_QUANTA.Q_RES(CHIPS)':
 'B': CDS_PINID='B';
NET_NAME
'UART_6_BMC_RXD'
 '@SCM_LIB.SCM(SCH_1):UART_6_BMC_RXD':
 C_SIGNAL='@scm_lib.scm(sch_1):uart_6_bmc_rxd';
NODE_NAME     R762 1
 '@SCM_LIB.SCM(SCH_1):PAGE12_I474@PURE_QUANTA.Q_RES(CHIPS)':
 'A': CDS_PINID='A';
NODE_NAME     R901 1
 '@SCM_LIB.SCM(SCH_1):PAGE31_I71@PURE_QUANTA.Q_RES(CHIPS)':
 'A': CDS_PINID='A';
NET_NAME
'UART_6_BMC_RXD_R'
 '@SCM_LIB.SCM(SCH_1):UART_6_BMC_RXD_R':
 C_SIGNAL='@scm_lib.scm(sch_1):uart_6_bmc_rxd_r';
NODE_NAME     U50 3
 '@SCM_LIB.SCM(SCH_1):PAGE31_I23@PURE_QUANTA.NC7SB3157(CHIPS)':
 'B0': CDS_PINID='B0';
NODE_NAME     R538 2
 '@SCM_LIB.SCM(SCH_1):PAGE31_I25@PURE_QUANTA.Q_RES(CHIPS)':
 'B': CDS_PINID='B';
NODE_NAME     R901 2
 '@SCM_LIB.SCM(SCH_1):PAGE31_I71@PURE_QUANTA.Q_RES(CHIPS)':
 'B': CDS_PINID='B';
NET_NAME
'UART_6_BMC_R_RXD'
 '@SCM_LIB.SCM(SCH_1):UART_6_BMC_R_RXD':
 C_SIGNAL='@scm_lib.scm(sch_1):uart_6_bmc_r_rxd';
NODE_NAME     U5 B22
 '@SCM_LIB.SCM(SCH_1):PAGE12_I436@PURE_QUANTA.AST2600A3GP(CHIPS)':
 'GPIOG1||RXD6||SD2CMD||SALT10': CDS_PINID='\gpiog1||rxd6||sd2cmd||salt10\';
NODE_NAME     R762 2
 '@SCM_LIB.SCM(SCH_1):PAGE12_I474@PURE_QUANTA.Q_RES(CHIPS)':
 'B': CDS_PINID='B';
NET_NAME
'UART_6_BMC_R_TXD'
 '@SCM_LIB.SCM(SCH_1):UART_6_BMC_R_TXD':
 C_SIGNAL='@scm_lib.scm(sch_1):uart_6_bmc_r_txd';
NODE_NAME     U5 E21
 '@SCM_LIB.SCM(SCH_1):PAGE12_I436@PURE_QUANTA.AST2600A3GP(CHIPS)':
 'GPIOG0||TXD6||SD2CLK||SALT9': CDS_PINID='\gpiog0||txd6||sd2clk||salt9\';
NODE_NAME     R761 2
 '@SCM_LIB.SCM(SCH_1):PAGE12_I473@PURE_QUANTA.Q_RES(CHIPS)':
 'B': CDS_PINID='B';
NET_NAME
'UART_6_BMC_TXD'
 '@SCM_LIB.SCM(SCH_1):UART_6_BMC_TXD':
 C_SIGNAL='@scm_lib.scm(sch_1):uart_6_bmc_txd';
NODE_NAME     R761 1
 '@SCM_LIB.SCM(SCH_1):PAGE12_I473@PURE_QUANTA.Q_RES(CHIPS)':
 'A': CDS_PINID='A';
NODE_NAME     R903 1
 '@SCM_LIB.SCM(SCH_1):PAGE31_I73@PURE_QUANTA.Q_RES(CHIPS)':
 'A': CDS_PINID='A';
NET_NAME
'UART_6_BMC_TXD_R'
 '@SCM_LIB.SCM(SCH_1):UART_6_BMC_TXD_R':
 C_SIGNAL='@scm_lib.scm(sch_1):uart_6_bmc_txd_r';
NODE_NAME     U51 3
 '@SCM_LIB.SCM(SCH_1):PAGE31_I24@PURE_QUANTA.NC7SB3157(CHIPS)':
 'B0': CDS_PINID='B0';
NODE_NAME     R903 2
 '@SCM_LIB.SCM(SCH_1):PAGE31_I73@PURE_QUANTA.Q_RES(CHIPS)':
 'B': CDS_PINID='B';
NET_NAME
'UART_BIC_DBG_RX'
 '@SCM_LIB.SCM(SCH_1):UART_BIC_DBG_RX':
 C_SIGNAL='@scm_lib.scm(sch_1):uart_bic_dbg_rx';
NODE_NAME     U3 1
 '@SCM_LIB.SCM(SCH_1):PAGE30_I251@PURE_QUANTA.FSA3357K8X(CHIPS)':
 'B0': CDS_PINID='B0';
NODE_NAME     R902 1
 '@SCM_LIB.SCM(SCH_1):PAGE31_I72@PURE_QUANTA.Q_RES(CHIPS)':
 'A': CDS_PINID='A';
NET_NAME
'UART_BIC_DBG_RX_R'
 '@SCM_LIB.SCM(SCH_1):UART_BIC_DBG_RX_R':
 C_SIGNAL='@scm_lib.scm(sch_1):uart_bic_dbg_rx_r';
NODE_NAME     U51 1
 '@SCM_LIB.SCM(SCH_1):PAGE31_I24@PURE_QUANTA.NC7SB3157(CHIPS)':
 'B1': CDS_PINID='B1';
NODE_NAME     R902 2
 '@SCM_LIB.SCM(SCH_1):PAGE31_I72@PURE_QUANTA.Q_RES(CHIPS)':
 'B': CDS_PINID='B';
NET_NAME
'UART_BIC_DBG_TX'
 '@SCM_LIB.SCM(SCH_1):UART_BIC_DBG_TX':
 C_SIGNAL='@scm_lib.scm(sch_1):uart_bic_dbg_tx';
NODE_NAME     U2 1
 '@SCM_LIB.SCM(SCH_1):PAGE30_I250@PURE_QUANTA.FSA3357K8X(CHIPS)':
 'B0': CDS_PINID='B0';
NODE_NAME     R900 1
 '@SCM_LIB.SCM(SCH_1):PAGE31_I70@PURE_QUANTA.Q_RES(CHIPS)':
 'A': CDS_PINID='A';
NET_NAME
'UART_BIC_DBG_TX_R'
 '@SCM_LIB.SCM(SCH_1):UART_BIC_DBG_TX_R':
 C_SIGNAL='@scm_lib.scm(sch_1):uart_bic_dbg_tx_r';
NODE_NAME     U50 1
 '@SCM_LIB.SCM(SCH_1):PAGE31_I23@PURE_QUANTA.NC7SB3157(CHIPS)':
 'B1': CDS_PINID='B1';
NODE_NAME     R900 2
 '@SCM_LIB.SCM(SCH_1):PAGE31_I70@PURE_QUANTA.Q_RES(CHIPS)':
 'B': CDS_PINID='B';
NET_NAME
'UART_BIC_GF_RXD'
 '@SCM_LIB.SCM(SCH_1):UART_BIC_GF_RXD':
 C_SIGNAL='@scm_lib.scm(sch_1):uart_bic_gf_rxd';
NODE_NAME     GF1 OB6
 '@SCM_LIB.SCM(SCH_1):PAGE10_I553@PURE_QUANTA.FCONN168_ME1016810202011_SCM(CHIPS)':
 'UART1_SCM_RX': CDS_PINID='UART1_SCM_RX';
NODE_NAME     U50 4
 '@SCM_LIB.SCM(SCH_1):PAGE31_I23@PURE_QUANTA.NC7SB3157(CHIPS)':
 'A': CDS_PINID='A';
NODE_NAME     R396 2
 '@SCM_LIB.SCM(SCH_1):PAGE31_I80@PURE_QUANTA.Q_RES(CHIPS)':
 'B': CDS_PINID='B';
NET_NAME
'UART_BIC_GF_TXD'
 '@SCM_LIB.SCM(SCH_1):UART_BIC_GF_TXD':
 C_SIGNAL='@scm_lib.scm(sch_1):uart_bic_gf_txd';
NODE_NAME     GF1 OB5
 '@SCM_LIB.SCM(SCH_1):PAGE10_I553@PURE_QUANTA.FCONN168_ME1016810202011_SCM(CHIPS)':
 'UART1_SCM_TX': CDS_PINID='UART1_SCM_TX';
NODE_NAME     U51 4
 '@SCM_LIB.SCM(SCH_1):PAGE31_I24@PURE_QUANTA.NC7SB3157(CHIPS)':
 'A': CDS_PINID='A';
NET_NAME
'UART_BMC_1_RXD'
 '@SCM_LIB.SCM(SCH_1):UART_BMC_1_RXD':
 C_SIGNAL='@scm_lib.scm(sch_1):uart_bmc_1_rxd';
NODE_NAME     R427 2
 '@SCM_LIB.SCM(SCH_1):PAGE13_I198@PURE_QUANTA.Q_RES(CHIPS)':
 'B': CDS_PINID='B';
NODE_NAME     U5 D13
 '@SCM_LIB.SCM(SCH_1):PAGE13_I363@PURE_QUANTA.AST2600A3GP(CHIPS)':
 'GPIOM7||RXD1': CDS_PINID='\gpiom7||rxd1\';
NET_NAME
'UART_BMC_1_RXD_R'
 '@SCM_LIB.SCM(SCH_1):UART_BMC_1_RXD_R':
 C_SIGNAL='@scm_lib.scm(sch_1):uart_bmc_1_rxd_r';
NODE_NAME     R427 1
 '@SCM_LIB.SCM(SCH_1):PAGE13_I198@PURE_QUANTA.Q_RES(CHIPS)':
 'A': CDS_PINID='A';
NODE_NAME     U3 3
 '@SCM_LIB.SCM(SCH_1):PAGE30_I251@PURE_QUANTA.FSA3357K8X(CHIPS)':
 'B2': CDS_PINID='B2';
NET_NAME
'UART_BMC_1_TXD'
 '@SCM_LIB.SCM(SCH_1):UART_BMC_1_TXD':
 C_SIGNAL='@scm_lib.scm(sch_1):uart_bmc_1_txd';
NODE_NAME     R157 2
 '@SCM_LIB.SCM(SCH_1):PAGE13_I18@PURE_QUANTA.Q_RES(CHIPS)':
 'B': CDS_PINID='B';
NODE_NAME     U5 C13
 '@SCM_LIB.SCM(SCH_1):PAGE13_I363@PURE_QUANTA.AST2600A3GP(CHIPS)':
 'GPIOM6||TXD1': CDS_PINID='\gpiom6||txd1\';
NET_NAME
'UART_BMC_1_TXD_R'
 '@SCM_LIB.SCM(SCH_1):UART_BMC_1_TXD_R':
 C_SIGNAL='@scm_lib.scm(sch_1):uart_bmc_1_txd_r';
NODE_NAME     R157 1
 '@SCM_LIB.SCM(SCH_1):PAGE13_I18@PURE_QUANTA.Q_RES(CHIPS)':
 'A': CDS_PINID='A';
NODE_NAME     U2 3
 '@SCM_LIB.SCM(SCH_1):PAGE30_I250@PURE_QUANTA.FSA3357K8X(CHIPS)':
 'B2': CDS_PINID='B2';
NET_NAME
'UART_BMC_5_RXD'
 '@SCM_LIB.SCM(SCH_1):UART_BMC_5_RXD':
 C_SIGNAL='@scm_lib.scm(sch_1):uart_bmc_5_rxd';
NODE_NAME     R759 1
 '@SCM_LIB.SCM(SCH_1):PAGE13_I208@PURE_QUANTA.Q_RES(CHIPS)':
 'A': CDS_PINID='A';
NODE_NAME     U5 D8
 '@SCM_LIB.SCM(SCH_1):PAGE13_I363@PURE_QUANTA.AST2600A3GP(CHIPS)':
 'RXD5': CDS_PINID='RXD5';
NET_NAME
'UART_BMC_5_RXD_BUF'
 '@SCM_LIB.SCM(SCH_1):UART_BMC_5_RXD_BUF':
 C_SIGNAL='@scm_lib.scm(sch_1):uart_bmc_5_rxd_buf';
NODE_NAME     J6 3
 '@SCM_LIB.SCM(SCH_1):PAGE30_I184@PURE_QUANTA.SCONN3_21291035BR2(CHIPS)':
 '3': CDS_PINID='\3\';
NODE_NAME     R741 2
 '@SCM_LIB.SCM(SCH_1):PAGE30_I197@PURE_QUANTA.Q_RES(CHIPS)':
 'B': CDS_PINID='B';
NODE_NAME     U24 3
 '@SCM_LIB.SCM(SCH_1):PAGE30_I246@PURE_QUANTA.74LVC2G07DW7(CHIPS)':
 '2A': CDS_PINID='\2a\';
NET_NAME
'UART_BMC_5_RXD_BUF1'
 '@SCM_LIB.SCM(SCH_1):UART_BMC_5_RXD_BUF1':
 C_SIGNAL='@scm_lib.scm(sch_1):uart_bmc_5_rxd_buf1';
NODE_NAME     R104 2
 '@SCM_LIB.SCM(SCH_1):PAGE30_I147@PURE_QUANTA.Q_RES(CHIPS)':
 'B': CDS_PINID='B';
NODE_NAME     R72 2
 '@SCM_LIB.SCM(SCH_1):PAGE30_I231@PURE_QUANTA.Q_RES(CHIPS)':
 'B': CDS_PINID='B';
NODE_NAME     R766 1
 '@SCM_LIB.SCM(SCH_1):PAGE30_I237@PURE_QUANTA.Q_RES(CHIPS)':
 'A': CDS_PINID='A';
NODE_NAME     U47 3
 '@SCM_LIB.SCM(SCH_1):PAGE30_I247@PURE_QUANTA.74LVC2G07DW7(CHIPS)':
 '2A': CDS_PINID='\2a\';
NET_NAME
'UART_BMC_5_RXD_BUF1_R'
 '@SCM_LIB.SCM(SCH_1):UART_BMC_5_RXD_BUF1_R':
 C_SIGNAL='@scm_lib.scm(sch_1):uart_bmc_5_rxd_buf1_r';
NODE_NAME     R757 1
 '@SCM_LIB.SCM(SCH_1):PAGE30_I226@PURE_QUANTA.Q_RES(CHIPS)':
 'A': CDS_PINID='A';
NODE_NAME     U47 4
 '@SCM_LIB.SCM(SCH_1):PAGE30_I247@PURE_QUANTA.74LVC2G07DW7(CHIPS)':
 '2Y': CDS_PINID='\2y\';
NET_NAME
'UART_BMC_5_RXD_BUF1_SW'
 '@SCM_LIB.SCM(SCH_1):UART_BMC_5_RXD_BUF1_SW':
 C_SIGNAL='@scm_lib.scm(sch_1):uart_bmc_5_rxd_buf1_sw';
NODE_NAME     R766 2
 '@SCM_LIB.SCM(SCH_1):PAGE30_I237@PURE_QUANTA.Q_RES(CHIPS)':
 'B': CDS_PINID='B';
NODE_NAME     U3 2
 '@SCM_LIB.SCM(SCH_1):PAGE30_I251@PURE_QUANTA.FSA3357K8X(CHIPS)':
 'B1': CDS_PINID='B1';
NET_NAME
'UART_BMC_5_RXD_BUF_R'
 '@SCM_LIB.SCM(SCH_1):UART_BMC_5_RXD_BUF_R':
 C_SIGNAL='@scm_lib.scm(sch_1):uart_bmc_5_rxd_buf_r';
NODE_NAME     R104 1
 '@SCM_LIB.SCM(SCH_1):PAGE30_I147@PURE_QUANTA.Q_RES(CHIPS)':
 'A': CDS_PINID='A';
NODE_NAME     U24 4
 '@SCM_LIB.SCM(SCH_1):PAGE30_I246@PURE_QUANTA.74LVC2G07DW7(CHIPS)':
 '2Y': CDS_PINID='\2y\';
NET_NAME
'UART_BMC_5_RXD_R'
 '@SCM_LIB.SCM(SCH_1):UART_BMC_5_RXD_R':
 C_SIGNAL='@scm_lib.scm(sch_1):uart_bmc_5_rxd_r';
NODE_NAME     R759 2
 '@SCM_LIB.SCM(SCH_1):PAGE13_I208@PURE_QUANTA.Q_RES(CHIPS)':
 'B': CDS_PINID='B';
NODE_NAME     R758 2
 '@SCM_LIB.SCM(SCH_1):PAGE30_I221@PURE_QUANTA.Q_RES(CHIPS)':
 'B': CDS_PINID='B';
NODE_NAME     R757 2
 '@SCM_LIB.SCM(SCH_1):PAGE30_I226@PURE_QUANTA.Q_RES(CHIPS)':
 'B': CDS_PINID='B';
NET_NAME
'UART_BMC_5_TXD'
 '@SCM_LIB.SCM(SCH_1):UART_BMC_5_TXD':
 C_SIGNAL='@scm_lib.scm(sch_1):uart_bmc_5_txd';
NODE_NAME     R170 1
 '@SCM_LIB.SCM(SCH_1):PAGE13_I67@PURE_QUANTA.Q_RES(CHIPS)':
 'A': CDS_PINID='A';
NODE_NAME     U5 C8
 '@SCM_LIB.SCM(SCH_1):PAGE13_I363@PURE_QUANTA.AST2600A3GP(CHIPS)':
 'TXD5': CDS_PINID='TXD5';
NET_NAME
'UART_BMC_5_TXD_BUF'
 '@SCM_LIB.SCM(SCH_1):UART_BMC_5_TXD_BUF':
 C_SIGNAL='@scm_lib.scm(sch_1):uart_bmc_5_txd_buf';
NODE_NAME     R102 1
 '@SCM_LIB.SCM(SCH_1):PAGE30_I148@PURE_QUANTA.Q_RES(CHIPS)':
 'A': CDS_PINID='A';
NODE_NAME     U24 6
 '@SCM_LIB.SCM(SCH_1):PAGE30_I246@PURE_QUANTA.74LVC2G07DW7(CHIPS)':
 '1Y': CDS_PINID='\1y\';
NET_NAME
'UART_BMC_5_TXD_BUF1'
 '@SCM_LIB.SCM(SCH_1):UART_BMC_5_TXD_BUF1':
 C_SIGNAL='@scm_lib.scm(sch_1):uart_bmc_5_txd_buf1';
NODE_NAME     R715 1
 '@SCM_LIB.SCM(SCH_1):PAGE30_I225@PURE_QUANTA.Q_RES(CHIPS)':
 'A': CDS_PINID='A';
NODE_NAME     U47 6
 '@SCM_LIB.SCM(SCH_1):PAGE30_I247@PURE_QUANTA.74LVC2G07DW7(CHIPS)':
 '1Y': CDS_PINID='\1y\';
NET_NAME
'UART_BMC_5_TXD_BUF1_R'
 '@SCM_LIB.SCM(SCH_1):UART_BMC_5_TXD_BUF1_R':
 C_SIGNAL='@scm_lib.scm(sch_1):uart_bmc_5_txd_buf1_r';
NODE_NAME     R67 2
 '@SCM_LIB.SCM(SCH_1):PAGE30_I146@PURE_QUANTA.Q_RES(CHIPS)':
 'B': CDS_PINID='B';
NODE_NAME     R715 2
 '@SCM_LIB.SCM(SCH_1):PAGE30_I225@PURE_QUANTA.Q_RES(CHIPS)':
 'B': CDS_PINID='B';
NODE_NAME     U24 1
 '@SCM_LIB.SCM(SCH_1):PAGE30_I246@PURE_QUANTA.74LVC2G07DW7(CHIPS)':
 '1A': CDS_PINID='\1a\';
NODE_NAME     U2 2
 '@SCM_LIB.SCM(SCH_1):PAGE30_I250@PURE_QUANTA.FSA3357K8X(CHIPS)':
 'B1': CDS_PINID='B1';
NET_NAME
'UART_BMC_5_TXD_BUF_R'
 '@SCM_LIB.SCM(SCH_1):UART_BMC_5_TXD_BUF_R':
 C_SIGNAL='@scm_lib.scm(sch_1):uart_bmc_5_txd_buf_r';
NODE_NAME     R102 2
 '@SCM_LIB.SCM(SCH_1):PAGE30_I148@PURE_QUANTA.Q_RES(CHIPS)':
 'B': CDS_PINID='B';
NODE_NAME     J6 1
 '@SCM_LIB.SCM(SCH_1):PAGE30_I184@PURE_QUANTA.SCONN3_21291035BR2(CHIPS)':
 '1': CDS_PINID='\1\';
NODE_NAME     R765 2
 '@SCM_LIB.SCM(SCH_1):PAGE30_I239@PURE_QUANTA.Q_RES(CHIPS)':
 'B': CDS_PINID='B';
NET_NAME
'UART_BMC_5_TXD_R'
 '@SCM_LIB.SCM(SCH_1):UART_BMC_5_TXD_R':
 C_SIGNAL='@scm_lib.scm(sch_1):uart_bmc_5_txd_r';
NODE_NAME     R170 2
 '@SCM_LIB.SCM(SCH_1):PAGE13_I67@PURE_QUANTA.Q_RES(CHIPS)':
 'B': CDS_PINID='B';
NODE_NAME     U11 2
 '@SCM_LIB.SCM(SCH_1):PAGE27_I185@PURE_QUANTA.BAT54C(CHIPS)':
 'A': CDS_PINID='A';
NODE_NAME     R754 2
 '@SCM_LIB.SCM(SCH_1):PAGE27_I213@PURE_QUANTA.Q_RES(CHIPS)':
 'B': CDS_PINID='B';
NODE_NAME     R770 2
 '@SCM_LIB.SCM(SCH_1):PAGE27_I217@PURE_QUANTA.Q_RES(CHIPS)':
 'B': CDS_PINID='B';
NODE_NAME     U47 1
 '@SCM_LIB.SCM(SCH_1):PAGE30_I247@PURE_QUANTA.74LVC2G07DW7(CHIPS)':
 '1A': CDS_PINID='\1a\';
NET_NAME
'UART_SYS_DBG_RX'
 '@SCM_LIB.SCM(SCH_1):UART_SYS_DBG_RX':
 C_SIGNAL='@scm_lib.scm(sch_1):uart_sys_dbg_rx';
NODE_NAME     GF1 OB9
 '@SCM_LIB.SCM(SCH_1):PAGE10_I553@PURE_QUANTA.FCONN168_ME1016810202011_SCM(CHIPS)':
 'UART0_SCM_RX': CDS_PINID='UART0_SCM_RX';
NODE_NAME     R618 1
 '@SCM_LIB.SCM(SCH_1):PAGE31_I76@PURE_QUANTA.Q_RES(CHIPS)':
 'A': CDS_PINID='A';
NET_NAME
'UART_SYS_DBG_RX_R'
 '@SCM_LIB.SCM(SCH_1):UART_SYS_DBG_RX_R':
 C_SIGNAL='@scm_lib.scm(sch_1):uart_sys_dbg_rx_r';
NODE_NAME     U20 3
 '@SCM_LIB.SCM(SCH_1):PAGE31_I38@PURE_QUANTA.NC7SB3157(CHIPS)':
 'B0': CDS_PINID='B0';
NODE_NAME     R618 2
 '@SCM_LIB.SCM(SCH_1):PAGE31_I76@PURE_QUANTA.Q_RES(CHIPS)':
 'B': CDS_PINID='B';
NET_NAME
'UART_SYS_DBG_TX'
 '@SCM_LIB.SCM(SCH_1):UART_SYS_DBG_TX':
 C_SIGNAL='@scm_lib.scm(sch_1):uart_sys_dbg_tx';
NODE_NAME     GF1 OB8
 '@SCM_LIB.SCM(SCH_1):PAGE10_I553@PURE_QUANTA.FCONN168_ME1016810202011_SCM(CHIPS)':
 'UART0_SCM_TX': CDS_PINID='UART0_SCM_TX';
NODE_NAME     R544 1
 '@SCM_LIB.SCM(SCH_1):PAGE31_I74@PURE_QUANTA.Q_RES(CHIPS)':
 'A': CDS_PINID='A';
NET_NAME
'UART_SYS_DBG_TX_R'
 '@SCM_LIB.SCM(SCH_1):UART_SYS_DBG_TX_R':
 C_SIGNAL='@scm_lib.scm(sch_1):uart_sys_dbg_tx_r';
NODE_NAME     U7 3
 '@SCM_LIB.SCM(SCH_1):PAGE31_I27@PURE_QUANTA.NC7SB3157(CHIPS)':
 'B0': CDS_PINID='B0';
NODE_NAME     R544 2
 '@SCM_LIB.SCM(SCH_1):PAGE31_I74@PURE_QUANTA.Q_RES(CHIPS)':
 'B': CDS_PINID='B';
NET_NAME
'USB2_01_F_DN'
 '@SCM_LIB.SCM(SCH_1):USB2_01_F_DN':
 C_SIGNAL='@scm_lib.scm(sch_1):usb2_01_f_dn';
NODE_NAME     R385 2
 '@SCM_LIB.SCM(SCH_1):PAGE29_I96@PURE_QUANTA.Q_RES(CHIPS)':
 'B': CDS_PINID='B';
NODE_NAME     U38 3
 '@SCM_LIB.SCM(SCH_1):PAGE29_I99@PURE_QUANTA.PRTR5V0U2X(CHIPS)':
 'IO2': CDS_PINID='IO2';
NODE_NAME     L23 3
 '@SCM_LIB.SCM(SCH_1):PAGE29_I102@PURE_QUANTA.Q_INDUCTOR4P_12(CHIPS)':
 '3': CDS_PINID='\3\';
NODE_NAME     J2 2
 '@SCM_LIB.SCM(SCH_1):PAGE29_I221@PURE_QUANTA.CONN9_GSB3111315HR(CHIPS)':
 'D-': CDS_PINID='\d-\';
NET_NAME
'USB2_01_F_DP'
 '@SCM_LIB.SCM(SCH_1):USB2_01_F_DP':
 C_SIGNAL='@scm_lib.scm(sch_1):usb2_01_f_dp';
NODE_NAME     U38 2
 '@SCM_LIB.SCM(SCH_1):PAGE29_I99@PURE_QUANTA.PRTR5V0U2X(CHIPS)':
 'IO1': CDS_PINID='IO1';
NODE_NAME     R386 2
 '@SCM_LIB.SCM(SCH_1):PAGE29_I101@PURE_QUANTA.Q_RES(CHIPS)':
 'B': CDS_PINID='B';
NODE_NAME     L23 2
 '@SCM_LIB.SCM(SCH_1):PAGE29_I102@PURE_QUANTA.Q_INDUCTOR4P_12(CHIPS)':
 '2': CDS_PINID='\2\';
NODE_NAME     J2 3
 '@SCM_LIB.SCM(SCH_1):PAGE29_I221@PURE_QUANTA.CONN9_GSB3111315HR(CHIPS)':
 'D+': CDS_PINID='\d+\';
NET_NAME
'USB3_01_FB_RXN'
 '@SCM_LIB.SCM(SCH_1):USB3_01_FB_RXN':
 C_SIGNAL='@scm_lib.scm(sch_1):usb3_01_fb_rxn';
NODE_NAME     R668 2
 '@SCM_LIB.SCM(SCH_1):PAGE29_I111@PURE_QUANTA.Q_RES(CHIPS)':
 'B': CDS_PINID='B';
NODE_NAME     L22 3
 '@SCM_LIB.SCM(SCH_1):PAGE29_I113@PURE_QUANTA.Q_INDUCTOR4P_12(CHIPS)':
 '3': CDS_PINID='\3\';
NODE_NAME     U27 5
 '@SCM_LIB.SCM(SCH_1):PAGE29_I211@PURE_QUANTA.DT1240E04LP7(CHIPS)':
 'IO4': CDS_PINID='IO4';
NODE_NAME     U27 6
 '@SCM_LIB.SCM(SCH_1):PAGE29_I211@PURE_QUANTA.DT1240E04LP7(CHIPS)':
 'NC1': CDS_PINID='NC1';
NODE_NAME     J2 5
 '@SCM_LIB.SCM(SCH_1):PAGE29_I221@PURE_QUANTA.CONN9_GSB3111315HR(CHIPS)':
 'SSRX-': CDS_PINID='\ssrx-\';
NET_NAME
'USB3_01_FB_RXP'
 '@SCM_LIB.SCM(SCH_1):USB3_01_FB_RXP':
 C_SIGNAL='@scm_lib.scm(sch_1):usb3_01_fb_rxp';
NODE_NAME     R675 2
 '@SCM_LIB.SCM(SCH_1):PAGE29_I109@PURE_QUANTA.Q_RES(CHIPS)':
 'B': CDS_PINID='B';
NODE_NAME     L22 2
 '@SCM_LIB.SCM(SCH_1):PAGE29_I113@PURE_QUANTA.Q_INDUCTOR4P_12(CHIPS)':
 '2': CDS_PINID='\2\';
NODE_NAME     U27 4
 '@SCM_LIB.SCM(SCH_1):PAGE29_I211@PURE_QUANTA.DT1240E04LP7(CHIPS)':
 'IO3': CDS_PINID='IO3';
NODE_NAME     U27 7
 '@SCM_LIB.SCM(SCH_1):PAGE29_I211@PURE_QUANTA.DT1240E04LP7(CHIPS)':
 'NC2': CDS_PINID='NC2';
NODE_NAME     J2 6
 '@SCM_LIB.SCM(SCH_1):PAGE29_I221@PURE_QUANTA.CONN9_GSB3111315HR(CHIPS)':
 'SSRX+': CDS_PINID='\ssrx+\';
NET_NAME
'USB3_01_FB_TXN'
 '@SCM_LIB.SCM(SCH_1):USB3_01_FB_TXN':
 C_SIGNAL='@scm_lib.scm(sch_1):usb3_01_fb_txn';
NODE_NAME     L21 3
 '@SCM_LIB.SCM(SCH_1):PAGE29_I123@PURE_QUANTA.Q_INDUCTOR4P_12(CHIPS)':
 '3': CDS_PINID='\3\';
NODE_NAME     R666 2
 '@SCM_LIB.SCM(SCH_1):PAGE29_I124@PURE_QUANTA.Q_RES(CHIPS)':
 'B': CDS_PINID='B';
NODE_NAME     U27 2
 '@SCM_LIB.SCM(SCH_1):PAGE29_I211@PURE_QUANTA.DT1240E04LP7(CHIPS)':
 'IO2': CDS_PINID='IO2';
NODE_NAME     U27 9
 '@SCM_LIB.SCM(SCH_1):PAGE29_I211@PURE_QUANTA.DT1240E04LP7(CHIPS)':
 'NC3': CDS_PINID='NC3';
NODE_NAME     J2 8
 '@SCM_LIB.SCM(SCH_1):PAGE29_I221@PURE_QUANTA.CONN9_GSB3111315HR(CHIPS)':
 'SSTX-': CDS_PINID='\sstx-\';
NET_NAME
'USB3_01_FB_TXP'
 '@SCM_LIB.SCM(SCH_1):USB3_01_FB_TXP':
 C_SIGNAL='@scm_lib.scm(sch_1):usb3_01_fb_txp';
NODE_NAME     R673 2
 '@SCM_LIB.SCM(SCH_1):PAGE29_I122@PURE_QUANTA.Q_RES(CHIPS)':
 'B': CDS_PINID='B';
NODE_NAME     L21 2
 '@SCM_LIB.SCM(SCH_1):PAGE29_I123@PURE_QUANTA.Q_INDUCTOR4P_12(CHIPS)':
 '2': CDS_PINID='\2\';
NODE_NAME     U27 1
 '@SCM_LIB.SCM(SCH_1):PAGE29_I211@PURE_QUANTA.DT1240E04LP7(CHIPS)':
 'IO1': CDS_PINID='IO1';
NODE_NAME     U27 10
 '@SCM_LIB.SCM(SCH_1):PAGE29_I211@PURE_QUANTA.DT1240E04LP7(CHIPS)':
 'NC4': CDS_PINID='NC4';
NODE_NAME     J2 9
 '@SCM_LIB.SCM(SCH_1):PAGE29_I221@PURE_QUANTA.CONN9_GSB3111315HR(CHIPS)':
 'SSTX+': CDS_PINID='\sstx+\';
NET_NAME
'USB3_01_MUX_FB_RXN'
 '@SCM_LIB.SCM(SCH_1):USB3_01_MUX_FB_RXN':
 C_SIGNAL='@scm_lib.scm(sch_1):usb3_01_mux_fb_rxn';
NODE_NAME     R668 1
 '@SCM_LIB.SCM(SCH_1):PAGE29_I111@PURE_QUANTA.Q_RES(CHIPS)':
 'A': CDS_PINID='A';
NODE_NAME     L22 4
 '@SCM_LIB.SCM(SCH_1):PAGE29_I113@PURE_QUANTA.Q_INDUCTOR4P_12(CHIPS)':
 '4': CDS_PINID='\4\';
NODE_NAME     U22 8
 '@SCM_LIB.SCM(SCH_1):PAGE29_I206@PURE_QUANTA.PI3PCIE3212ZBEX(CHIPS)':
 'A1_N': CDS_PINID='A1_N';
NET_NAME
'USB3_01_MUX_FB_RXP'
 '@SCM_LIB.SCM(SCH_1):USB3_01_MUX_FB_RXP':
 C_SIGNAL='@scm_lib.scm(sch_1):usb3_01_mux_fb_rxp';
NODE_NAME     R675 1
 '@SCM_LIB.SCM(SCH_1):PAGE29_I109@PURE_QUANTA.Q_RES(CHIPS)':
 'A': CDS_PINID='A';
NODE_NAME     L22 1
 '@SCM_LIB.SCM(SCH_1):PAGE29_I113@PURE_QUANTA.Q_INDUCTOR4P_12(CHIPS)':
 '1': CDS_PINID='\1\';
NODE_NAME     U22 7
 '@SCM_LIB.SCM(SCH_1):PAGE29_I206@PURE_QUANTA.PI3PCIE3212ZBEX(CHIPS)':
 'A1_P': CDS_PINID='A1_P';
NET_NAME
'USB3_01_MUX_FB_TXN'
 '@SCM_LIB.SCM(SCH_1):USB3_01_MUX_FB_TXN':
 C_SIGNAL='@scm_lib.scm(sch_1):usb3_01_mux_fb_txn';
NODE_NAME     L21 4
 '@SCM_LIB.SCM(SCH_1):PAGE29_I123@PURE_QUANTA.Q_INDUCTOR4P_12(CHIPS)':
 '4': CDS_PINID='\4\';
NODE_NAME     R666 1
 '@SCM_LIB.SCM(SCH_1):PAGE29_I124@PURE_QUANTA.Q_RES(CHIPS)':
 'A': CDS_PINID='A';
NODE_NAME     U22 4
 '@SCM_LIB.SCM(SCH_1):PAGE29_I206@PURE_QUANTA.PI3PCIE3212ZBEX(CHIPS)':
 'A0_N': CDS_PINID='A0_N';
NET_NAME
'USB3_01_MUX_FB_TXP'
 '@SCM_LIB.SCM(SCH_1):USB3_01_MUX_FB_TXP':
 C_SIGNAL='@scm_lib.scm(sch_1):usb3_01_mux_fb_txp';
NODE_NAME     R673 1
 '@SCM_LIB.SCM(SCH_1):PAGE29_I122@PURE_QUANTA.Q_RES(CHIPS)':
 'A': CDS_PINID='A';
NODE_NAME     L21 1
 '@SCM_LIB.SCM(SCH_1):PAGE29_I123@PURE_QUANTA.Q_INDUCTOR4P_12(CHIPS)':
 '1': CDS_PINID='\1\';
NODE_NAME     U22 3
 '@SCM_LIB.SCM(SCH_1):PAGE29_I206@PURE_QUANTA.PI3PCIE3212ZBEX(CHIPS)':
 'A0_P': CDS_PINID='A0_P';
NET_NAME
'USB3_01_TXN_C'
 '@SCM_LIB.SCM(SCH_1):USB3_01_TXN_C':
 C_SIGNAL='@scm_lib.scm(sch_1):usb3_01_txn_c';
NODE_NAME     C239 2
 '@SCM_LIB.SCM(SCH_1):PAGE29_I143@PURE_QUANTA.Q_CAP(CHIPS)':
 'B': CDS_PINID='B';
NODE_NAME     R672 1
 '@SCM_LIB.SCM(SCH_1):PAGE29_I144@PURE_QUANTA.Q_RES(CHIPS)':
 'A': CDS_PINID='A';
NODE_NAME     U22 18
 '@SCM_LIB.SCM(SCH_1):PAGE29_I206@PURE_QUANTA.PI3PCIE3212ZBEX(CHIPS)':
 'B0_N': CDS_PINID='B0_N';
NET_NAME
'USB3_01_TXP_C'
 '@SCM_LIB.SCM(SCH_1):USB3_01_TXP_C':
 C_SIGNAL='@scm_lib.scm(sch_1):usb3_01_txp_c';
NODE_NAME     R671 1
 '@SCM_LIB.SCM(SCH_1):PAGE29_I141@PURE_QUANTA.Q_RES(CHIPS)':
 'A': CDS_PINID='A';
NODE_NAME     C238 2
 '@SCM_LIB.SCM(SCH_1):PAGE29_I142@PURE_QUANTA.Q_CAP(CHIPS)':
 'B': CDS_PINID='B';
NODE_NAME     U22 19
 '@SCM_LIB.SCM(SCH_1):PAGE29_I206@PURE_QUANTA.PI3PCIE3212ZBEX(CHIPS)':
 'B0_P': CDS_PINID='B0_P';
NET_NAME
'USB3_FPNL_RXN'
 '@SCM_LIB.SCM(SCH_1):USB3_FPNL_RXN':
 C_SIGNAL='@scm_lib.scm(sch_1):usb3_fpnl_rxn';
NODE_NAME     GF1 A60
 '@SCM_LIB.SCM(SCH_1):PAGE10_I553@PURE_QUANTA.FCONN168_ME1016810202011_SCM(CHIPS)':
 'PCIE_HPM_RXN_0': CDS_PINID='PCIE_HPM_RXN_0';
NODE_NAME     U22 16
 '@SCM_LIB.SCM(SCH_1):PAGE29_I206@PURE_QUANTA.PI3PCIE3212ZBEX(CHIPS)':
 'B1_N': CDS_PINID='B1_N';
NET_NAME
'USB3_FPNL_RXP'
 '@SCM_LIB.SCM(SCH_1):USB3_FPNL_RXP':
 C_SIGNAL='@scm_lib.scm(sch_1):usb3_fpnl_rxp';
NODE_NAME     GF1 A59
 '@SCM_LIB.SCM(SCH_1):PAGE10_I553@PURE_QUANTA.FCONN168_ME1016810202011_SCM(CHIPS)':
 'PCIE_HPM_RXP_0': CDS_PINID='PCIE_HPM_RXP_0';
NODE_NAME     U22 17
 '@SCM_LIB.SCM(SCH_1):PAGE29_I206@PURE_QUANTA.PI3PCIE3212ZBEX(CHIPS)':
 'B1_P': CDS_PINID='B1_P';
NET_NAME
'USB3_FPNL_TXN'
 '@SCM_LIB.SCM(SCH_1):USB3_FPNL_TXN':
 C_SIGNAL='@scm_lib.scm(sch_1):usb3_fpnl_txn';
NODE_NAME     GF1 B60
 '@SCM_LIB.SCM(SCH_1):PAGE10_I553@PURE_QUANTA.FCONN168_ME1016810202011_SCM(CHIPS)':
 'PCIE_HPM_TXN_0': CDS_PINID='PCIE_HPM_TXN_0';
NODE_NAME     C239 1
 '@SCM_LIB.SCM(SCH_1):PAGE29_I143@PURE_QUANTA.Q_CAP(CHIPS)':
 'A': CDS_PINID='A';
NODE_NAME     R672 2
 '@SCM_LIB.SCM(SCH_1):PAGE29_I144@PURE_QUANTA.Q_RES(CHIPS)':
 'B': CDS_PINID='B';
NET_NAME
'USB3_FPNL_TXP'
 '@SCM_LIB.SCM(SCH_1):USB3_FPNL_TXP':
 C_SIGNAL='@scm_lib.scm(sch_1):usb3_fpnl_txp';
NODE_NAME     GF1 B59
 '@SCM_LIB.SCM(SCH_1):PAGE10_I553@PURE_QUANTA.FCONN168_ME1016810202011_SCM(CHIPS)':
 'PCIE_HPM_TXP_0': CDS_PINID='PCIE_HPM_TXP_0';
NODE_NAME     R671 2
 '@SCM_LIB.SCM(SCH_1):PAGE29_I141@PURE_QUANTA.Q_RES(CHIPS)':
 'B': CDS_PINID='B';
NODE_NAME     C238 1
 '@SCM_LIB.SCM(SCH_1):PAGE29_I142@PURE_QUANTA.Q_CAP(CHIPS)':
 'A': CDS_PINID='A';
NET_NAME
'USB3_MUX_PD'
 '@SCM_LIB.SCM(SCH_1):USB3_MUX_PD':
 C_SIGNAL='@scm_lib.scm(sch_1):usb3_mux_pd';
NODE_NAME     R712 2
 '@SCM_LIB.SCM(SCH_1):PAGE29_I153@PURE_QUANTA.Q_RES(CHIPS)':
 'B': CDS_PINID='B';
NODE_NAME     R694 1
 '@SCM_LIB.SCM(SCH_1):PAGE29_I155@PURE_QUANTA.Q_RES(CHIPS)':
 'A': CDS_PINID='A';
NODE_NAME     U22 2
 '@SCM_LIB.SCM(SCH_1):PAGE29_I206@PURE_QUANTA.PI3PCIE3212ZBEX(CHIPS)':
 'PD': CDS_PINID='PD';
NET_NAME
'USB_FPNL_DN'
 '@SCM_LIB.SCM(SCH_1):USB_FPNL_DN':
 C_SIGNAL='@scm_lib.scm(sch_1):usb_fpnl_dn';
NODE_NAME     GF1 B57
 '@SCM_LIB.SCM(SCH_1):PAGE10_I553@PURE_QUANTA.FCONN168_ME1016810202011_SCM(CHIPS)':
 'RSVD1': CDS_PINID='RSVD1';
NODE_NAME     R385 1
 '@SCM_LIB.SCM(SCH_1):PAGE29_I96@PURE_QUANTA.Q_RES(CHIPS)':
 'A': CDS_PINID='A';
NODE_NAME     L23 4
 '@SCM_LIB.SCM(SCH_1):PAGE29_I102@PURE_QUANTA.Q_INDUCTOR4P_12(CHIPS)':
 '4': CDS_PINID='\4\';
NET_NAME
'USB_FPNL_DP'
 '@SCM_LIB.SCM(SCH_1):USB_FPNL_DP':
 C_SIGNAL='@scm_lib.scm(sch_1):usb_fpnl_dp';
NODE_NAME     GF1 B56
 '@SCM_LIB.SCM(SCH_1):PAGE10_I553@PURE_QUANTA.FCONN168_ME1016810202011_SCM(CHIPS)':
 'RSVD0': CDS_PINID='RSVD0';
NODE_NAME     R386 1
 '@SCM_LIB.SCM(SCH_1):PAGE29_I101@PURE_QUANTA.Q_RES(CHIPS)':
 'A': CDS_PINID='A';
NODE_NAME     L23 1
 '@SCM_LIB.SCM(SCH_1):PAGE29_I102@PURE_QUANTA.Q_INDUCTOR4P_12(CHIPS)':
 '1': CDS_PINID='\1\';
NET_NAME
'USB_HOST_BMC_A_DN'
 '@SCM_LIB.SCM(SCH_1):USB_HOST_BMC_A_DN':
 C_SIGNAL='@scm_lib.scm(sch_1):usb_host_bmc_a_dn';
NODE_NAME     GF1 B54
 '@SCM_LIB.SCM(SCH_1):PAGE10_I553@PURE_QUANTA.FCONN168_ME1016810202011_SCM(CHIPS)':
 'USB1_DN': CDS_PINID='USB1_DN';
NODE_NAME     R218 2
 '@SCM_LIB.SCM(SCH_1):PAGE15_I93@PURE_QUANTA.Q_RES(CHIPS)':
 'B': CDS_PINID='B';
NODE_NAME     R441 1
 '@SCM_LIB.SCM(SCH_1):PAGE15_I353@PURE_QUANTA.Q_RES(CHIPS)':
 'A': CDS_PINID='A';
NET_NAME
'USB_HOST_BMC_A_DP'
 '@SCM_LIB.SCM(SCH_1):USB_HOST_BMC_A_DP':
 C_SIGNAL='@scm_lib.scm(sch_1):usb_host_bmc_a_dp';
NODE_NAME     GF1 B53
 '@SCM_LIB.SCM(SCH_1):PAGE10_I553@PURE_QUANTA.FCONN168_ME1016810202011_SCM(CHIPS)':
 'USB1_DP': CDS_PINID='USB1_DP';
NODE_NAME     R217 2
 '@SCM_LIB.SCM(SCH_1):PAGE15_I92@PURE_QUANTA.Q_RES(CHIPS)':
 'B': CDS_PINID='B';
NODE_NAME     R440 1
 '@SCM_LIB.SCM(SCH_1):PAGE15_I354@PURE_QUANTA.Q_RES(CHIPS)':
 'A': CDS_PINID='A';
NET_NAME
'USB_HOST_BMC_A_R_DN'
 '@SCM_LIB.SCM(SCH_1):USB_HOST_BMC_A_R_DN':
 C_SIGNAL='@scm_lib.scm(sch_1):usb_host_bmc_a_r_dn';
NODE_NAME     R218 1
 '@SCM_LIB.SCM(SCH_1):PAGE15_I93@PURE_QUANTA.Q_RES(CHIPS)':
 'A': CDS_PINID='A';
NODE_NAME     U5 B4
 '@SCM_LIB.SCM(SCH_1):PAGE15_I350@PURE_QUANTA.AST2600A3GP(CHIPS)':
 'USB2A_DN': CDS_PINID='USB2A_DN';
NET_NAME
'USB_HOST_BMC_A_R_DP'
 '@SCM_LIB.SCM(SCH_1):USB_HOST_BMC_A_R_DP':
 C_SIGNAL='@scm_lib.scm(sch_1):usb_host_bmc_a_r_dp';
NODE_NAME     R217 1
 '@SCM_LIB.SCM(SCH_1):PAGE15_I92@PURE_QUANTA.Q_RES(CHIPS)':
 'A': CDS_PINID='A';
NODE_NAME     U5 A4
 '@SCM_LIB.SCM(SCH_1):PAGE15_I350@PURE_QUANTA.AST2600A3GP(CHIPS)':
 'USB2A_DP': CDS_PINID='USB2A_DP';
NET_NAME
'USB_HOST_BMC_B_DN'
 '@SCM_LIB.SCM(SCH_1):USB_HOST_BMC_B_DN':
 C_SIGNAL='@scm_lib.scm(sch_1):usb_host_bmc_b_dn';
NODE_NAME     GF1 B51
 '@SCM_LIB.SCM(SCH_1):PAGE10_I553@PURE_QUANTA.FCONN168_ME1016810202011_SCM(CHIPS)':
 'USB2_DN': CDS_PINID='USB2_DN';
NODE_NAME     R528 2
 '@SCM_LIB.SCM(SCH_1):PAGE15_I168@PURE_QUANTA.Q_RES(CHIPS)':
 'B': CDS_PINID='B';
NET_NAME
'USB_HOST_BMC_B_DP'
 '@SCM_LIB.SCM(SCH_1):USB_HOST_BMC_B_DP':
 C_SIGNAL='@scm_lib.scm(sch_1):usb_host_bmc_b_dp';
NODE_NAME     GF1 B50
 '@SCM_LIB.SCM(SCH_1):PAGE10_I553@PURE_QUANTA.FCONN168_ME1016810202011_SCM(CHIPS)':
 'USB2_DP': CDS_PINID='USB2_DP';
NODE_NAME     R527 2
 '@SCM_LIB.SCM(SCH_1):PAGE15_I169@PURE_QUANTA.Q_RES(CHIPS)':
 'B': CDS_PINID='B';
NET_NAME
'USB_HOST_BMC_B_R_DN'
 '@SCM_LIB.SCM(SCH_1):USB_HOST_BMC_B_R_DN':
 C_SIGNAL='@scm_lib.scm(sch_1):usb_host_bmc_b_r_dn';
NODE_NAME     R528 1
 '@SCM_LIB.SCM(SCH_1):PAGE15_I168@PURE_QUANTA.Q_RES(CHIPS)':
 'A': CDS_PINID='A';
NODE_NAME     U5 B6
 '@SCM_LIB.SCM(SCH_1):PAGE15_I350@PURE_QUANTA.AST2600A3GP(CHIPS)':
 'USB2B_DN': CDS_PINID='USB2B_DN';
NET_NAME
'USB_HOST_BMC_B_R_DP'
 '@SCM_LIB.SCM(SCH_1):USB_HOST_BMC_B_R_DP':
 C_SIGNAL='@scm_lib.scm(sch_1):usb_host_bmc_b_r_dp';
NODE_NAME     R527 1
 '@SCM_LIB.SCM(SCH_1):PAGE15_I169@PURE_QUANTA.Q_RES(CHIPS)':
 'A': CDS_PINID='A';
NODE_NAME     U5 A6
 '@SCM_LIB.SCM(SCH_1):PAGE15_I350@PURE_QUANTA.AST2600A3GP(CHIPS)':
 'USB2B_DP': CDS_PINID='USB2B_DP';
NET_NAME
'USB_OC0_EN'
 '@SCM_LIB.SCM(SCH_1):USB_OC0_EN':
 C_SIGNAL='@scm_lib.scm(sch_1):usb_oc0_en';
NODE_NAME     R376 2
 '@SCM_LIB.SCM(SCH_1):PAGE28_I62@PURE_QUANTA.Q_RES(CHIPS)':
 'B': CDS_PINID='B';
NODE_NAME     R377 1
 '@SCM_LIB.SCM(SCH_1):PAGE28_I63@PURE_QUANTA.Q_RES(CHIPS)':
 'A': CDS_PINID='A';
NODE_NAME     U10 3
 '@SCM_LIB.SCM(SCH_1):PAGE28_I179@PURE_QUANTA.NCP380HSNAJAAT1G(CHIPS)':
 'EN': CDS_PINID='EN';
NET_NAME
'USB_OC0_ILIM'
 '@SCM_LIB.SCM(SCH_1):USB_OC0_ILIM':
 C_SIGNAL='@scm_lib.scm(sch_1):usb_oc0_ilim';
NODE_NAME     R378 1
 '@SCM_LIB.SCM(SCH_1):PAGE28_I54@PURE_QUANTA.Q_RES(CHIPS)':
 'A': CDS_PINID='A';
NODE_NAME     U10 5
 '@SCM_LIB.SCM(SCH_1):PAGE28_I179@PURE_QUANTA.NCP380HSNAJAAT1G(CHIPS)':
 'ILIM': CDS_PINID='ILIM';
NET_NAME
'USB_OC0_REAR_N'
 '@SCM_LIB.SCM(SCH_1):USB_OC0_REAR_N':
 C_SIGNAL='@scm_lib.scm(sch_1):usb_oc0_rear_n';
NODE_NAME     R383 2
 '@SCM_LIB.SCM(SCH_1):PAGE28_I42@PURE_QUANTA.Q_RES(CHIPS)':
 'B': CDS_PINID='B';
NODE_NAME     U10 4
 '@SCM_LIB.SCM(SCH_1):PAGE28_I179@PURE_QUANTA.NCP380HSNAJAAT1G(CHIPS)':
 'FLAG_N': CDS_PINID='FLAG_N';
NODE_NAME     R384 1
 '@SCM_LIB.SCM(SCH_1):PAGE28_I185@PURE_QUANTA.Q_RES(CHIPS)':
 'A': CDS_PINID='A';
NET_NAME
'USB_OC0_REAR_R_N'
 '@SCM_LIB.SCM(SCH_1):USB_OC0_REAR_R_N':
 C_SIGNAL='@scm_lib.scm(sch_1):usb_oc0_rear_r_n';
NODE_NAME     U5 AB25
 '@SCM_LIB.SCM(SCH_1):PAGE15_I350@PURE_QUANTA.AST2600A3GP(CHIPS)':
 'GPIOQ1||TACH1': CDS_PINID='\gpioq1||tach1\';
NODE_NAME     U25 L16
 '@SCM_LIB.SCM(SCH_1):PAGE35_I1@PURE_QUANTA.LCMXO3LF2100C5BG256C(CHIPS)':
 'PR11A': CDS_PINID='PR11A';
NODE_NAME     R384 2
 '@SCM_LIB.SCM(SCH_1):PAGE28_I185@PURE_QUANTA.Q_RES(CHIPS)':
 'B': CDS_PINID='B';
NET_NAME
'VCCIO0'
 '@SCM_LIB.SCM(SCH_1):VCCIO0':
 C_SIGNAL='@scm_lib.scm(sch_1):vccio0',
 CDS_GLOBAL_NET='TRUE';
NODE_NAME     U25 D5
 '@SCM_LIB.SCM(SCH_1):PAGE34_I1@PURE_QUANTA.LCMXO3LF2100C5BG256C(CHIPS)':
 'VCCIO0_D5': CDS_PINID='VCCIO0_D5';
NODE_NAME     U25 D12
 '@SCM_LIB.SCM(SCH_1):PAGE34_I1@PURE_QUANTA.LCMXO3LF2100C5BG256C(CHIPS)':
 'VCCIO0_D12': CDS_PINID='VCCIO0_D12';
NODE_NAME     U25 G8
 '@SCM_LIB.SCM(SCH_1):PAGE34_I1@PURE_QUANTA.LCMXO3LF2100C5BG256C(CHIPS)':
 'VCCIO0_G8': CDS_PINID='VCCIO0_G8';
NODE_NAME     U25 G9
 '@SCM_LIB.SCM(SCH_1):PAGE34_I1@PURE_QUANTA.LCMXO3LF2100C5BG256C(CHIPS)':
 'VCCIO0_G9': CDS_PINID='VCCIO0_G9';
NODE_NAME     C242 1
 '@SCM_LIB.SCM(SCH_1):PAGE41_I1@PURE_QUANTA.Q_CAP(CHIPS)':
 'A': CDS_PINID='A';
NODE_NAME     C166 1
 '@SCM_LIB.SCM(SCH_1):PAGE41_I8@PURE_QUANTA.Q_CAP(CHIPS)':
 'A': CDS_PINID='A';
NODE_NAME     R305 2
 '@SCM_LIB.SCM(SCH_1):PAGE41_I71@PURE_QUANTA.Q_RES(CHIPS)':
 'B': CDS_PINID='B';
NODE_NAME     C247 1
 '@SCM_LIB.SCM(SCH_1):PAGE41_I77@PURE_QUANTA.Q_CAP(CHIPS)':
 'A': CDS_PINID='A';
NODE_NAME     C189 1
 '@SCM_LIB.SCM(SCH_1):PAGE41_I78@PURE_QUANTA.Q_CAP(CHIPS)':
 'A': CDS_PINID='A';
NODE_NAME     C261 1
 '@SCM_LIB.SCM(SCH_1):PAGE41_I79@PURE_QUANTA.Q_CAP(CHIPS)':
 'A': CDS_PINID='A';
NODE_NAME     C283 1
 '@SCM_LIB.SCM(SCH_1):PAGE41_I126@PURE_QUANTA.Q_CAP(CHIPS)':
 'A': CDS_PINID='A';
NET_NAME
'VCCIO1'
 '@SCM_LIB.SCM(SCH_1):VCCIO1':
 C_SIGNAL='@scm_lib.scm(sch_1):vccio1',
 CDS_GLOBAL_NET='TRUE';
NODE_NAME     U25 E13
 '@SCM_LIB.SCM(SCH_1):PAGE35_I1@PURE_QUANTA.LCMXO3LF2100C5BG256C(CHIPS)':
 'VCCIO1_E13': CDS_PINID='VCCIO1_E13';
NODE_NAME     U25 H10
 '@SCM_LIB.SCM(SCH_1):PAGE35_I1@PURE_QUANTA.LCMXO3LF2100C5BG256C(CHIPS)':
 'VCCIO1_H10': CDS_PINID='VCCIO1_H10';
NODE_NAME     U25 J10
 '@SCM_LIB.SCM(SCH_1):PAGE35_I1@PURE_QUANTA.LCMXO3LF2100C5BG256C(CHIPS)':
 'VCCIO1_J10': CDS_PINID='VCCIO1_J10';
NODE_NAME     U25 M13
 '@SCM_LIB.SCM(SCH_1):PAGE35_I1@PURE_QUANTA.LCMXO3LF2100C5BG256C(CHIPS)':
 'VCCIO1_M13': CDS_PINID='VCCIO1_M13';
NODE_NAME     R525 2
 '@SCM_LIB.SCM(SCH_1):PAGE41_I72@PURE_QUANTA.Q_RES(CHIPS)':
 'B': CDS_PINID='B';
NODE_NAME     C167 1
 '@SCM_LIB.SCM(SCH_1):PAGE41_I80@PURE_QUANTA.Q_CAP(CHIPS)':
 'A': CDS_PINID='A';
NODE_NAME     C243 1
 '@SCM_LIB.SCM(SCH_1):PAGE41_I81@PURE_QUANTA.Q_CAP(CHIPS)':
 'A': CDS_PINID='A';
NODE_NAME     C254 1
 '@SCM_LIB.SCM(SCH_1):PAGE41_I82@PURE_QUANTA.Q_CAP(CHIPS)':
 'A': CDS_PINID='A';
NODE_NAME     C141 1
 '@SCM_LIB.SCM(SCH_1):PAGE41_I83@PURE_QUANTA.Q_CAP(CHIPS)':
 'A': CDS_PINID='A';
NODE_NAME     C164 1
 '@SCM_LIB.SCM(SCH_1):PAGE41_I92@PURE_QUANTA.Q_CAP(CHIPS)':
 'A': CDS_PINID='A';
NODE_NAME     C281 1
 '@SCM_LIB.SCM(SCH_1):PAGE41_I125@PURE_QUANTA.Q_CAP(CHIPS)':
 'A': CDS_PINID='A';
NET_NAME
'VCCIO2'
 '@SCM_LIB.SCM(SCH_1):VCCIO2':
 C_SIGNAL='@scm_lib.scm(sch_1):vccio2',
 CDS_GLOBAL_NET='TRUE';
NODE_NAME     U25 K8
 '@SCM_LIB.SCM(SCH_1):PAGE36_I1@PURE_QUANTA.LCMXO3LF2100C5BG256C(CHIPS)':
 'VCCIO2_K8': CDS_PINID='VCCIO2_K8';
NODE_NAME     U25 K9
 '@SCM_LIB.SCM(SCH_1):PAGE36_I1@PURE_QUANTA.LCMXO3LF2100C5BG256C(CHIPS)':
 'VCCIO2_K9': CDS_PINID='VCCIO2_K9';
NODE_NAME     U25 N5
 '@SCM_LIB.SCM(SCH_1):PAGE36_I1@PURE_QUANTA.LCMXO3LF2100C5BG256C(CHIPS)':
 'VCCIO2_N5': CDS_PINID='VCCIO2_N5';
NODE_NAME     U25 N12
 '@SCM_LIB.SCM(SCH_1):PAGE36_I1@PURE_QUANTA.LCMXO3LF2100C5BG256C(CHIPS)':
 'VCCIO2_N12': CDS_PINID='VCCIO2_N12';
NODE_NAME     R304 2
 '@SCM_LIB.SCM(SCH_1):PAGE41_I73@PURE_QUANTA.Q_RES(CHIPS)':
 'B': CDS_PINID='B';
NODE_NAME     C187 1
 '@SCM_LIB.SCM(SCH_1):PAGE41_I84@PURE_QUANTA.Q_CAP(CHIPS)':
 'A': CDS_PINID='A';
NODE_NAME     C245 1
 '@SCM_LIB.SCM(SCH_1):PAGE41_I85@PURE_QUANTA.Q_CAP(CHIPS)':
 'A': CDS_PINID='A';
NODE_NAME     C188 1
 '@SCM_LIB.SCM(SCH_1):PAGE41_I86@PURE_QUANTA.Q_CAP(CHIPS)':
 'A': CDS_PINID='A';
NODE_NAME     C260 1
 '@SCM_LIB.SCM(SCH_1):PAGE41_I87@PURE_QUANTA.Q_CAP(CHIPS)':
 'A': CDS_PINID='A';
NODE_NAME     C165 1
 '@SCM_LIB.SCM(SCH_1):PAGE41_I93@PURE_QUANTA.Q_CAP(CHIPS)':
 'A': CDS_PINID='A';
NODE_NAME     C285 1
 '@SCM_LIB.SCM(SCH_1):PAGE41_I124@PURE_QUANTA.Q_CAP(CHIPS)':
 'A': CDS_PINID='A';
NODE_NAME     R288 1
 '@SCM_LIB.SCM(SCH_1):PAGE36_I50@PURE_QUANTA.Q_RES(CHIPS)':
 'A': CDS_PINID='A';
NODE_NAME     R297 2
 '@SCM_LIB.SCM(SCH_1):PAGE34_I137@PURE_QUANTA.Q_RES(CHIPS)':
 'B': CDS_PINID='B';
NET_NAME
'VCCIO3'
 '@SCM_LIB.SCM(SCH_1):VCCIO3':
 C_SIGNAL='@scm_lib.scm(sch_1):vccio3',
 CDS_GLOBAL_NET='TRUE';
NODE_NAME     U25 M4
 '@SCM_LIB.SCM(SCH_1):PAGE37_I1@PURE_QUANTA.LCMXO3LF2100C5BG256C(CHIPS)':
 'VCCIO3': CDS_PINID='VCCIO3';
NODE_NAME     R308 2
 '@SCM_LIB.SCM(SCH_1):PAGE41_I74@PURE_QUANTA.Q_RES(CHIPS)':
 'B': CDS_PINID='B';
NODE_NAME     C152 1
 '@SCM_LIB.SCM(SCH_1):PAGE41_I88@PURE_QUANTA.Q_CAP(CHIPS)':
 'A': CDS_PINID='A';
NODE_NAME     C216 1
 '@SCM_LIB.SCM(SCH_1):PAGE41_I94@PURE_QUANTA.Q_CAP(CHIPS)':
 'A': CDS_PINID='A';
NET_NAME
'VCCIO4'
 '@SCM_LIB.SCM(SCH_1):VCCIO4':
 C_SIGNAL='@scm_lib.scm(sch_1):vccio4',
 CDS_GLOBAL_NET='TRUE';
NODE_NAME     U25 H7
 '@SCM_LIB.SCM(SCH_1):PAGE38_I1@PURE_QUANTA.LCMXO3LF2100C5BG256C(CHIPS)':
 'VCCIO4_H7': CDS_PINID='VCCIO4_H7';
NODE_NAME     U25 J7
 '@SCM_LIB.SCM(SCH_1):PAGE38_I1@PURE_QUANTA.LCMXO3LF2100C5BG256C(CHIPS)':
 'VCCIO4_J7': CDS_PINID='VCCIO4_J7';
NODE_NAME     R307 2
 '@SCM_LIB.SCM(SCH_1):PAGE41_I76@PURE_QUANTA.Q_RES(CHIPS)':
 'B': CDS_PINID='B';
NODE_NAME     C220 1
 '@SCM_LIB.SCM(SCH_1):PAGE41_I90@PURE_QUANTA.Q_CAP(CHIPS)':
 'A': CDS_PINID='A';
NODE_NAME     C162 1
 '@SCM_LIB.SCM(SCH_1):PAGE41_I91@PURE_QUANTA.Q_CAP(CHIPS)':
 'A': CDS_PINID='A';
NODE_NAME     C195 1
 '@SCM_LIB.SCM(SCH_1):PAGE41_I96@PURE_QUANTA.Q_CAP(CHIPS)':
 'A': CDS_PINID='A';
NET_NAME
'VCCIO5'
 '@SCM_LIB.SCM(SCH_1):VCCIO5':
 C_SIGNAL='@scm_lib.scm(sch_1):vccio5',
 CDS_GLOBAL_NET='TRUE';
NODE_NAME     U25 E4
 '@SCM_LIB.SCM(SCH_1):PAGE39_I1@PURE_QUANTA.LCMXO3LF2100C5BG256C(CHIPS)':
 'VCCIO5': CDS_PINID='VCCIO5';
NODE_NAME     R301 2
 '@SCM_LIB.SCM(SCH_1):PAGE41_I75@PURE_QUANTA.Q_RES(CHIPS)':
 'B': CDS_PINID='B';
NODE_NAME     C160 1
 '@SCM_LIB.SCM(SCH_1):PAGE41_I89@PURE_QUANTA.Q_CAP(CHIPS)':
 'A': CDS_PINID='A';
NODE_NAME     C218 1
 '@SCM_LIB.SCM(SCH_1):PAGE41_I95@PURE_QUANTA.Q_CAP(CHIPS)':
 'A': CDS_PINID='A';
NET_NAME
'VOL_SEN_ALERT_R'
 '@SCM_LIB.SCM(SCH_1):VOL_SEN_ALERT_R':
 C_SIGNAL='@scm_lib.scm(sch_1):vol_sen_alert_r';
NODE_NAME     U5 K23
 '@SCM_LIB.SCM(SCH_1):PAGE13_I363@PURE_QUANTA.AST2600A3GP(CHIPS)':
 'GPIOB1||SALT2': CDS_PINID='\gpiob1||salt2\';
NODE_NAME     R267 2
 '@SCM_LIB.SCM(SCH_1):PAGE27_I85@PURE_QUANTA.Q_RES(CHIPS)':
 'B': CDS_PINID='B';
NODE_NAME     U25 C15
 '@SCM_LIB.SCM(SCH_1):PAGE35_I1@PURE_QUANTA.LCMXO3LF2100C5BG256C(CHIPS)':
 'PR1C': CDS_PINID='PR1C';
NET_NAME
'V_BMC_DDC_LS_GATE'
 '@SCM_LIB.SCM(SCH_1):V_BMC_DDC_LS_GATE':
 C_SIGNAL='@scm_lib.scm(sch_1):v_bmc_ddc_ls_gate';
NODE_NAME     Q2 5
 '@SCM_LIB.SCM(SCH_1):PAGE23_I2@PURE_QUANTA.MOSFET_NCH_DUAL(CHIPS)':
 'G2': CDS_PINID='G2';
NODE_NAME     R86 2
 '@SCM_LIB.SCM(SCH_1):PAGE23_I51@PURE_QUANTA.Q_RES(CHIPS)':
 'B': CDS_PINID='B';
NODE_NAME     Q2 2
 '@SCM_LIB.SCM(SCH_1):PAGE23_I56@PURE_QUANTA.MOSFET_NCH_DUAL(CHIPS)':
 'G1': CDS_PINID='G1';
NET_NAME
'V_BMC_DDC_SCL'
 '@SCM_LIB.SCM(SCH_1):V_BMC_DDC_SCL':
 C_SIGNAL='@scm_lib.scm(sch_1):v_bmc_ddc_scl';
NODE_NAME     U5 B8
 '@SCM_LIB.SCM(SCH_1):PAGE15_I350@PURE_QUANTA.AST2600A3GP(CHIPS)':
 'DDCCLK': CDS_PINID='DDCCLK';
NODE_NAME     Q2 4
 '@SCM_LIB.SCM(SCH_1):PAGE23_I2@PURE_QUANTA.MOSFET_NCH_DUAL(CHIPS)':
 'S2': CDS_PINID='S2';
NODE_NAME     R32 2
 '@SCM_LIB.SCM(SCH_1):PAGE23_I50@PURE_QUANTA.Q_RES(CHIPS)':
 'B': CDS_PINID='B';
NET_NAME
'V_BMC_DDC_SDA'
 '@SCM_LIB.SCM(SCH_1):V_BMC_DDC_SDA':
 C_SIGNAL='@scm_lib.scm(sch_1):v_bmc_ddc_sda';
NODE_NAME     U5 A8
 '@SCM_LIB.SCM(SCH_1):PAGE15_I350@PURE_QUANTA.AST2600A3GP(CHIPS)':
 'DDCDAT': CDS_PINID='DDCDAT';
NODE_NAME     R31 2
 '@SCM_LIB.SCM(SCH_1):PAGE23_I27@PURE_QUANTA.Q_RES(CHIPS)':
 'B': CDS_PINID='B';
NODE_NAME     Q2 1
 '@SCM_LIB.SCM(SCH_1):PAGE23_I56@PURE_QUANTA.MOSFET_NCH_DUAL(CHIPS)':
 'S1': CDS_PINID='S1';
NET_NAME
'V_BMC_LS_DDC_SCL'
 '@SCM_LIB.SCM(SCH_1):V_BMC_LS_DDC_SCL':
 C_SIGNAL='@scm_lib.scm(sch_1):v_bmc_ls_ddc_scl';
NODE_NAME     Q2 3
 '@SCM_LIB.SCM(SCH_1):PAGE23_I2@PURE_QUANTA.MOSFET_NCH_DUAL(CHIPS)':
 'D2': CDS_PINID='D2';
NODE_NAME     R92 2
 '@SCM_LIB.SCM(SCH_1):PAGE23_I64@PURE_QUANTA.Q_RES(CHIPS)':
 'B': CDS_PINID='B';
NODE_NAME     R28 1
 '@SCM_LIB.SCM(SCH_1):PAGE23_I99@PURE_QUANTA.Q_RES(CHIPS)':
 'A': CDS_PINID='A';
NET_NAME
'V_BMC_LS_DDC_SCL_R'
 '@SCM_LIB.SCM(SCH_1):V_BMC_LS_DDC_SCL_R':
 C_SIGNAL='@scm_lib.scm(sch_1):v_bmc_ls_ddc_scl_r';
NODE_NAME     R16 1
 '@SCM_LIB.SCM(SCH_1):PAGE23_I75@PURE_QUANTA.Q_RES(CHIPS)':
 'A': CDS_PINID='A';
NODE_NAME     C214 1
 '@SCM_LIB.SCM(SCH_1):PAGE23_I84@PURE_QUANTA.Q_CAP(CHIPS)':
 'A': CDS_PINID='A';
NODE_NAME     R28 2
 '@SCM_LIB.SCM(SCH_1):PAGE23_I99@PURE_QUANTA.Q_RES(CHIPS)':
 'B': CDS_PINID='B';
NODE_NAME     U34 1
 '@SCM_LIB.SCM(SCH_1):PAGE23_I156@PURE_QUANTA.DT1240E04LP7(CHIPS)':
 'IO1': CDS_PINID='IO1';
NODE_NAME     U34 10
 '@SCM_LIB.SCM(SCH_1):PAGE23_I156@PURE_QUANTA.DT1240E04LP7(CHIPS)':
 'NC4': CDS_PINID='NC4';
NODE_NAME     J8 12
 '@SCM_LIB.SCM(SCH_1):PAGE23_I165@PURE_QUANTA.SCONN13_502280130CV01(CHIPS)':
 '12': CDS_PINID='\12\';
NET_NAME
'V_BMC_LS_DDC_SDA'
 '@SCM_LIB.SCM(SCH_1):V_BMC_LS_DDC_SDA':
 C_SIGNAL='@scm_lib.scm(sch_1):v_bmc_ls_ddc_sda';
NODE_NAME     R29 1
 '@SCM_LIB.SCM(SCH_1):PAGE23_I34@PURE_QUANTA.Q_RES(CHIPS)':
 'A': CDS_PINID='A';
NODE_NAME     Q2 6
 '@SCM_LIB.SCM(SCH_1):PAGE23_I56@PURE_QUANTA.MOSFET_NCH_DUAL(CHIPS)':
 'D1': CDS_PINID='D1';
NODE_NAME     R91 2
 '@SCM_LIB.SCM(SCH_1):PAGE23_I62@PURE_QUANTA.Q_RES(CHIPS)':
 'B': CDS_PINID='B';
NET_NAME
'V_BMC_LS_DDC_SDA_R'
 '@SCM_LIB.SCM(SCH_1):V_BMC_LS_DDC_SDA_R':
 C_SIGNAL='@scm_lib.scm(sch_1):v_bmc_ls_ddc_sda_r';
NODE_NAME     R29 2
 '@SCM_LIB.SCM(SCH_1):PAGE23_I34@PURE_QUANTA.Q_RES(CHIPS)':
 'B': CDS_PINID='B';
NODE_NAME     R17 1
 '@SCM_LIB.SCM(SCH_1):PAGE23_I68@PURE_QUANTA.Q_RES(CHIPS)':
 'A': CDS_PINID='A';
NODE_NAME     C213 1
 '@SCM_LIB.SCM(SCH_1):PAGE23_I83@PURE_QUANTA.Q_CAP(CHIPS)':
 'A': CDS_PINID='A';
NODE_NAME     U34 2
 '@SCM_LIB.SCM(SCH_1):PAGE23_I156@PURE_QUANTA.DT1240E04LP7(CHIPS)':
 'IO2': CDS_PINID='IO2';
NODE_NAME     U34 9
 '@SCM_LIB.SCM(SCH_1):PAGE23_I156@PURE_QUANTA.DT1240E04LP7(CHIPS)':
 'NC3': CDS_PINID='NC3';
NODE_NAME     J8 11
 '@SCM_LIB.SCM(SCH_1):PAGE23_I165@PURE_QUANTA.SCONN13_502280130CV01(CHIPS)':
 '11': CDS_PINID='\11\';
NET_NAME
'V_DACB'
 '@SCM_LIB.SCM(SCH_1):V_DACB':
 C_SIGNAL='@scm_lib.scm(sch_1):v_dacb';
NODE_NAME     R24 2
 '@SCM_LIB.SCM(SCH_1):PAGE15_I134@PURE_QUANTA.Q_RES(CHIPS)':
 'B': CDS_PINID='B';
NODE_NAME     C207 1
 '@SCM_LIB.SCM(SCH_1):PAGE23_I29@PURE_QUANTA.Q_CAP(CHIPS)':
 'A': CDS_PINID='A';
NODE_NAME     L28 1
 '@SCM_LIB.SCM(SCH_1):PAGE23_I166@PURE_QUANTA.Q_INDUCTOR(CHIPS)':
 '1': CDS_PINID='\1\';
NET_NAME
'V_DACB_IO'
 '@SCM_LIB.SCM(SCH_1):V_DACB_IO':
 C_SIGNAL='@scm_lib.scm(sch_1):v_dacb_io';
NODE_NAME     R87 1
 '@SCM_LIB.SCM(SCH_1):PAGE23_I57@PURE_QUANTA.Q_RES(CHIPS)':
 'A': CDS_PINID='A';
NODE_NAME     U35 1
 '@SCM_LIB.SCM(SCH_1):PAGE23_I155@PURE_QUANTA.DT1240E04LP7(CHIPS)':
 'IO1': CDS_PINID='IO1';
NODE_NAME     U35 10
 '@SCM_LIB.SCM(SCH_1):PAGE23_I155@PURE_QUANTA.DT1240E04LP7(CHIPS)':
 'NC4': CDS_PINID='NC4';
NODE_NAME     J8 5
 '@SCM_LIB.SCM(SCH_1):PAGE23_I165@PURE_QUANTA.SCONN13_502280130CV01(CHIPS)':
 '5': CDS_PINID='\5\';
NODE_NAME     L28 2
 '@SCM_LIB.SCM(SCH_1):PAGE23_I166@PURE_QUANTA.Q_INDUCTOR(CHIPS)':
 '2': CDS_PINID='\2\';
NODE_NAME     C210 1
 '@SCM_LIB.SCM(SCH_1):PAGE23_I170@PURE_QUANTA.Q_CAP(CHIPS)':
 'A': CDS_PINID='A';
NET_NAME
'V_DACB_R'
 '@SCM_LIB.SCM(SCH_1):V_DACB_R':
 C_SIGNAL='@scm_lib.scm(sch_1):v_dacb_r';
NODE_NAME     R24 1
 '@SCM_LIB.SCM(SCH_1):PAGE15_I134@PURE_QUANTA.Q_RES(CHIPS)':
 'A': CDS_PINID='A';
NODE_NAME     R22 1
 '@SCM_LIB.SCM(SCH_1):PAGE15_I151@PURE_QUANTA.Q_RES(CHIPS)':
 'A': CDS_PINID='A';
NODE_NAME     U5 AD21
 '@SCM_LIB.SCM(SCH_1):PAGE15_I350@PURE_QUANTA.AST2600A3GP(CHIPS)':
 'DACB': CDS_PINID='DACB';
NET_NAME
'V_DACG'
 '@SCM_LIB.SCM(SCH_1):V_DACG':
 C_SIGNAL='@scm_lib.scm(sch_1):v_dacg';
NODE_NAME     R21 2
 '@SCM_LIB.SCM(SCH_1):PAGE15_I133@PURE_QUANTA.Q_RES(CHIPS)':
 'B': CDS_PINID='B';
NODE_NAME     C206 1
 '@SCM_LIB.SCM(SCH_1):PAGE23_I26@PURE_QUANTA.Q_CAP(CHIPS)':
 'A': CDS_PINID='A';
NODE_NAME     L29 1
 '@SCM_LIB.SCM(SCH_1):PAGE23_I167@PURE_QUANTA.Q_INDUCTOR(CHIPS)':
 '1': CDS_PINID='\1\';
NET_NAME
'V_DACG_IO'
 '@SCM_LIB.SCM(SCH_1):V_DACG_IO':
 C_SIGNAL='@scm_lib.scm(sch_1):v_dacg_io';
NODE_NAME     C209 1
 '@SCM_LIB.SCM(SCH_1):PAGE23_I54@PURE_QUANTA.Q_CAP(CHIPS)':
 'A': CDS_PINID='A';
NODE_NAME     R88 1
 '@SCM_LIB.SCM(SCH_1):PAGE23_I59@PURE_QUANTA.Q_RES(CHIPS)':
 'A': CDS_PINID='A';
NODE_NAME     U35 2
 '@SCM_LIB.SCM(SCH_1):PAGE23_I155@PURE_QUANTA.DT1240E04LP7(CHIPS)':
 'IO2': CDS_PINID='IO2';
NODE_NAME     U35 9
 '@SCM_LIB.SCM(SCH_1):PAGE23_I155@PURE_QUANTA.DT1240E04LP7(CHIPS)':
 'NC3': CDS_PINID='NC3';
NODE_NAME     J8 3
 '@SCM_LIB.SCM(SCH_1):PAGE23_I165@PURE_QUANTA.SCONN13_502280130CV01(CHIPS)':
 '3': CDS_PINID='\3\';
NODE_NAME     L29 2
 '@SCM_LIB.SCM(SCH_1):PAGE23_I167@PURE_QUANTA.Q_INDUCTOR(CHIPS)':
 '2': CDS_PINID='\2\';
NET_NAME
'V_DACG_R'
 '@SCM_LIB.SCM(SCH_1):V_DACG_R':
 C_SIGNAL='@scm_lib.scm(sch_1):v_dacg_r';
NODE_NAME     R21 1
 '@SCM_LIB.SCM(SCH_1):PAGE15_I133@PURE_QUANTA.Q_RES(CHIPS)':
 'A': CDS_PINID='A';
NODE_NAME     R23 1
 '@SCM_LIB.SCM(SCH_1):PAGE15_I150@PURE_QUANTA.Q_RES(CHIPS)':
 'A': CDS_PINID='A';
NODE_NAME     U5 AE21
 '@SCM_LIB.SCM(SCH_1):PAGE15_I350@PURE_QUANTA.AST2600A3GP(CHIPS)':
 'DACG': CDS_PINID='DACG';
NET_NAME
'V_DACR'
 '@SCM_LIB.SCM(SCH_1):V_DACR':
 C_SIGNAL='@scm_lib.scm(sch_1):v_dacr';
NODE_NAME     R26 2
 '@SCM_LIB.SCM(SCH_1):PAGE15_I142@PURE_QUANTA.Q_RES(CHIPS)':
 'B': CDS_PINID='B';
NODE_NAME     C205 1
 '@SCM_LIB.SCM(SCH_1):PAGE23_I25@PURE_QUANTA.Q_CAP(CHIPS)':
 'A': CDS_PINID='A';
NODE_NAME     L30 1
 '@SCM_LIB.SCM(SCH_1):PAGE23_I168@PURE_QUANTA.Q_INDUCTOR(CHIPS)':
 '1': CDS_PINID='\1\';
NET_NAME
'V_DACR_IO'
 '@SCM_LIB.SCM(SCH_1):V_DACR_IO':
 C_SIGNAL='@scm_lib.scm(sch_1):v_dacr_io';
NODE_NAME     R89 1
 '@SCM_LIB.SCM(SCH_1):PAGE23_I65@PURE_QUANTA.Q_RES(CHIPS)':
 'A': CDS_PINID='A';
NODE_NAME     U35 4
 '@SCM_LIB.SCM(SCH_1):PAGE23_I155@PURE_QUANTA.DT1240E04LP7(CHIPS)':
 'IO3': CDS_PINID='IO3';
NODE_NAME     U35 7
 '@SCM_LIB.SCM(SCH_1):PAGE23_I155@PURE_QUANTA.DT1240E04LP7(CHIPS)':
 'NC2': CDS_PINID='NC2';
NODE_NAME     J8 1
 '@SCM_LIB.SCM(SCH_1):PAGE23_I165@PURE_QUANTA.SCONN13_502280130CV01(CHIPS)':
 '1': CDS_PINID='\1\';
NODE_NAME     L30 2
 '@SCM_LIB.SCM(SCH_1):PAGE23_I168@PURE_QUANTA.Q_INDUCTOR(CHIPS)':
 '2': CDS_PINID='\2\';
NODE_NAME     C208 1
 '@SCM_LIB.SCM(SCH_1):PAGE23_I169@PURE_QUANTA.Q_CAP(CHIPS)':
 'A': CDS_PINID='A';
NET_NAME
'V_DACR_R'
 '@SCM_LIB.SCM(SCH_1):V_DACR_R':
 C_SIGNAL='@scm_lib.scm(sch_1):v_dacr_r';
NODE_NAME     R26 1
 '@SCM_LIB.SCM(SCH_1):PAGE15_I142@PURE_QUANTA.Q_RES(CHIPS)':
 'A': CDS_PINID='A';
NODE_NAME     R25 1
 '@SCM_LIB.SCM(SCH_1):PAGE15_I149@PURE_QUANTA.Q_RES(CHIPS)':
 'A': CDS_PINID='A';
NODE_NAME     U5 AF21
 '@SCM_LIB.SCM(SCH_1):PAGE15_I350@PURE_QUANTA.AST2600A3GP(CHIPS)':
 'DACR': CDS_PINID='DACR';
NET_NAME
'V_VGAHS'
 '@SCM_LIB.SCM(SCH_1):V_VGAHS':
 C_SIGNAL='@scm_lib.scm(sch_1):v_vgahs';
NODE_NAME     R19 2
 '@SCM_LIB.SCM(SCH_1):PAGE15_I141@PURE_QUANTA.Q_RES(CHIPS)':
 'B': CDS_PINID='B';
NODE_NAME     U33 2
 '@SCM_LIB.SCM(SCH_1):PAGE23_I32@PURE_QUANTA.74HC1G126GW(CHIPS)':
 '2': CDS_PINID='\2\';
NET_NAME
'V_VGAHS_BUF'
 '@SCM_LIB.SCM(SCH_1):V_VGAHS_BUF':
 C_SIGNAL='@scm_lib.scm(sch_1):v_vgahs_buf';
NODE_NAME     R85 2
 '@SCM_LIB.SCM(SCH_1):PAGE23_I60@PURE_QUANTA.Q_RES(CHIPS)':
 'B': CDS_PINID='B';
NODE_NAME     C211 1
 '@SCM_LIB.SCM(SCH_1):PAGE23_I67@PURE_QUANTA.Q_CAP(CHIPS)':
 'A': CDS_PINID='A';
NODE_NAME     U34 4
 '@SCM_LIB.SCM(SCH_1):PAGE23_I156@PURE_QUANTA.DT1240E04LP7(CHIPS)':
 'IO3': CDS_PINID='IO3';
NODE_NAME     U34 7
 '@SCM_LIB.SCM(SCH_1):PAGE23_I156@PURE_QUANTA.DT1240E04LP7(CHIPS)':
 'NC2': CDS_PINID='NC2';
NODE_NAME     J8 9
 '@SCM_LIB.SCM(SCH_1):PAGE23_I165@PURE_QUANTA.SCONN13_502280130CV01(CHIPS)':
 '9': CDS_PINID='\9\';
NET_NAME
'V_VGAHS_BUF_R'
 '@SCM_LIB.SCM(SCH_1):V_VGAHS_BUF_R':
 C_SIGNAL='@scm_lib.scm(sch_1):v_vgahs_buf_r';
NODE_NAME     U33 4
 '@SCM_LIB.SCM(SCH_1):PAGE23_I32@PURE_QUANTA.74HC1G126GW(CHIPS)':
 '4': CDS_PINID='\4\';
NODE_NAME     R85 1
 '@SCM_LIB.SCM(SCH_1):PAGE23_I60@PURE_QUANTA.Q_RES(CHIPS)':
 'A': CDS_PINID='A';
NET_NAME
'V_VGAHS_R'
 '@SCM_LIB.SCM(SCH_1):V_VGAHS_R':
 C_SIGNAL='@scm_lib.scm(sch_1):v_vgahs_r';
NODE_NAME     R19 1
 '@SCM_LIB.SCM(SCH_1):PAGE15_I141@PURE_QUANTA.Q_RES(CHIPS)':
 'A': CDS_PINID='A';
NODE_NAME     U5 B14
 '@SCM_LIB.SCM(SCH_1):PAGE15_I350@PURE_QUANTA.AST2600A3GP(CHIPS)':
 'GPIOL6||VGAHS': CDS_PINID='\gpiol6||vgahs\';
NET_NAME
'V_VGAVS'
 '@SCM_LIB.SCM(SCH_1):V_VGAVS':
 C_SIGNAL='@scm_lib.scm(sch_1):v_vgavs';
NODE_NAME     R20 2
 '@SCM_LIB.SCM(SCH_1):PAGE15_I140@PURE_QUANTA.Q_RES(CHIPS)':
 'B': CDS_PINID='B';
NODE_NAME     U26 2
 '@SCM_LIB.SCM(SCH_1):PAGE23_I33@PURE_QUANTA.74HC1G126GW(CHIPS)':
 '2': CDS_PINID='\2\';
NET_NAME
'V_VGAVS_BUF'
 '@SCM_LIB.SCM(SCH_1):V_VGAVS_BUF':
 C_SIGNAL='@scm_lib.scm(sch_1):v_vgavs_buf';
NODE_NAME     R84 2
 '@SCM_LIB.SCM(SCH_1):PAGE23_I61@PURE_QUANTA.Q_RES(CHIPS)':
 'B': CDS_PINID='B';
NODE_NAME     C212 1
 '@SCM_LIB.SCM(SCH_1):PAGE23_I77@PURE_QUANTA.Q_CAP(CHIPS)':
 'A': CDS_PINID='A';
NODE_NAME     U34 5
 '@SCM_LIB.SCM(SCH_1):PAGE23_I156@PURE_QUANTA.DT1240E04LP7(CHIPS)':
 'IO4': CDS_PINID='IO4';
NODE_NAME     U34 6
 '@SCM_LIB.SCM(SCH_1):PAGE23_I156@PURE_QUANTA.DT1240E04LP7(CHIPS)':
 'NC1': CDS_PINID='NC1';
NODE_NAME     J8 7
 '@SCM_LIB.SCM(SCH_1):PAGE23_I165@PURE_QUANTA.SCONN13_502280130CV01(CHIPS)':
 '7': CDS_PINID='\7\';
NET_NAME
'V_VGAVS_BUF_R'
 '@SCM_LIB.SCM(SCH_1):V_VGAVS_BUF_R':
 C_SIGNAL='@scm_lib.scm(sch_1):v_vgavs_buf_r';
NODE_NAME     U26 4
 '@SCM_LIB.SCM(SCH_1):PAGE23_I33@PURE_QUANTA.74HC1G126GW(CHIPS)':
 '4': CDS_PINID='\4\';
NODE_NAME     R84 1
 '@SCM_LIB.SCM(SCH_1):PAGE23_I61@PURE_QUANTA.Q_RES(CHIPS)':
 'A': CDS_PINID='A';
NET_NAME
'V_VGAVS_R'
 '@SCM_LIB.SCM(SCH_1):V_VGAVS_R':
 C_SIGNAL='@scm_lib.scm(sch_1):v_vgavs_r';
NODE_NAME     R20 1
 '@SCM_LIB.SCM(SCH_1):PAGE15_I140@PURE_QUANTA.Q_RES(CHIPS)':
 'A': CDS_PINID='A';
NODE_NAME     U5 C14
 '@SCM_LIB.SCM(SCH_1):PAGE15_I350@PURE_QUANTA.AST2600A3GP(CHIPS)':
 'GPIOL7||VGAVS': CDS_PINID='\gpiol7||vgavs\';
END.
